G04 ================== begin FILE IDENTIFICATION RECORD ==================*
G04 Layout Name:  15126-1b.brd*
G04 Film Name:    DP_REF_L12*
G04 File Format:  Gerber RS274X*
G04 File Origin:  Cadence Allegro 16.6-2015-S079*
G04 Origin Date:  Fri Feb 10 17:23:36 2017*
G04 *
G04 Layer:  BOARD GEOMETRY/PANEL_OUTLINE*
G04 Layer:  BOARD GEOMETRY/DP_REF_L12_TBL*
G04 Layer:  BOARD GEOMETRY/DP_REF_L12_L12*
G04 *
G04 Offset:    (0.00 0.00)*
G04 Mirror:    No*
G04 Mode:      Positive*
G04 Rotation:  0*
G04 FullContactRelief:  No*
G04 UndefLineWidth:     6.00*
G04 ================== end FILE IDENTIFICATION RECORD ====================*
%FSLAX35Y35*MOIN*%
%IR0*IPPOS*OFA0.00000B0.00000*MIA0B0*SFA1.00000B1.00000*%
%ADD10C,.02*%
%ADD11C,.006*%
%ADD12C,.00402*%
%ADD13C,.0045*%
%ADD14C,.0056*%
%ADD15C,.00399*%
G75*
%LPD*%
G75*
G54D10*
G01X2026678Y631398D02*
Y458148D01*
G01D02*
X2901678D01*
G01X2026678Y492798D02*
X2901678D01*
G01X2026678Y527448D02*
X2901678D01*
G01X2026678Y562098D02*
X2901678D01*
G01X2026678Y596748D02*
X2901678D01*
G01X2026678Y631398D02*
X2901678D01*
G01X2201678D02*
Y458148D01*
G01X2586678Y631398D02*
Y458148D01*
G01X2691678Y631398D02*
Y458148D01*
G01X2901678Y631398D02*
Y458148D01*
G54D11*
G01X-17372Y-95792D02*
Y-113292D01*
G01X-22394Y-95792D02*
X-12350D01*
G01X-3584Y-113292D02*
Y-95792D01*
G01Y-104250D02*
X-2492Y-102792D01*
X-1400Y-101917D01*
X346Y-101626D01*
X1656Y-101917D01*
X3185Y-103084D01*
X3840Y-104834D01*
Y-113292D01*
G01X17628Y-101626D02*
Y-113292D01*
G01Y-96959D02*
X17191Y-96667D01*
Y-96084D01*
X17628Y-95792D01*
X18065Y-96084D01*
Y-96667D01*
X17628Y-96959D01*
G01X31853Y-111251D02*
X32945Y-112417D01*
X34473Y-113292D01*
X35783D01*
X37093Y-112709D01*
X37966Y-111834D01*
X38403Y-110668D01*
X38185Y-108917D01*
X37311Y-108042D01*
X33381Y-106292D01*
X32508Y-104250D01*
X32945Y-102792D01*
X33818Y-101917D01*
X35128Y-101626D01*
X36438Y-101917D01*
X37748Y-102792D01*
G01X67071Y-117667D02*
X68600Y-118834D01*
X70346Y-119125D01*
X71874Y-118834D01*
X73185Y-117376D01*
X74058Y-115334D01*
Y-101626D01*
G01Y-103959D02*
X73185Y-102792D01*
X71874Y-101917D01*
X70346Y-101626D01*
X68600Y-102209D01*
X67508Y-103375D01*
X66634Y-105417D01*
X66198Y-107459D01*
X66416Y-109209D01*
X67290Y-111251D01*
X68600Y-112709D01*
X70346Y-113292D01*
X71656Y-113000D01*
X73185Y-111834D01*
X74058Y-110668D01*
G01X84353Y-105417D02*
X91340D01*
X90685Y-103375D01*
X89593Y-102209D01*
X88065Y-101626D01*
X86536Y-101917D01*
X85226Y-102792D01*
X84353Y-104834D01*
X83916Y-106584D01*
Y-108334D01*
X84353Y-110084D01*
X85445Y-111834D01*
X86755Y-113000D01*
X88283Y-113292D01*
X89811Y-112709D01*
X91340Y-110959D01*
G01X102071Y-113292D02*
Y-101626D01*
G01Y-103959D02*
X103163Y-102792D01*
X104255Y-101917D01*
X105783Y-101626D01*
X106874Y-101917D01*
X108185Y-102792D01*
G01X118698Y-113292D02*
Y-95792D01*
G01Y-104542D02*
X119790Y-102792D01*
X121100Y-101917D01*
X122410Y-101626D01*
X124374Y-102209D01*
X125685Y-103375D01*
X126558Y-105417D01*
Y-107750D01*
X126121Y-110084D01*
X125248Y-111834D01*
X123720Y-113000D01*
X122410Y-113292D01*
X121100Y-113000D01*
X119790Y-112126D01*
X118698Y-110668D01*
G01X136853Y-105417D02*
X143840D01*
X143185Y-103375D01*
X142093Y-102209D01*
X140565Y-101626D01*
X139036Y-101917D01*
X137726Y-102792D01*
X136853Y-104834D01*
X136416Y-106584D01*
Y-108334D01*
X136853Y-110084D01*
X137945Y-111834D01*
X139255Y-113000D01*
X140783Y-113292D01*
X142311Y-112709D01*
X143840Y-110959D01*
G01X154571Y-113292D02*
Y-101626D01*
G01Y-103959D02*
X155663Y-102792D01*
X156755Y-101917D01*
X158283Y-101626D01*
X159374Y-101917D01*
X160685Y-102792D01*
G01X192628Y-101626D02*
Y-113292D01*
G01Y-96959D02*
X192191Y-96667D01*
Y-96084D01*
X192628Y-95792D01*
X193065Y-96084D01*
Y-96667D01*
X192628Y-96959D01*
G01X206853Y-111251D02*
X207945Y-112417D01*
X209473Y-113292D01*
X210783D01*
X212093Y-112709D01*
X212966Y-111834D01*
X213403Y-110668D01*
X213185Y-108917D01*
X212311Y-108042D01*
X208381Y-106292D01*
X207508Y-104250D01*
X207945Y-102792D01*
X208818Y-101917D01*
X210128Y-101626D01*
X211438Y-101917D01*
X212748Y-102792D01*
G01X241634Y-117667D02*
X243163Y-118834D01*
X244473Y-119125D01*
X246220Y-118542D01*
X247530Y-117084D01*
X248185Y-114458D01*
Y-101626D01*
G01Y-96959D02*
X247748Y-96667D01*
Y-96084D01*
X248185Y-95792D01*
X248621Y-96084D01*
Y-96667D01*
X248185Y-96959D01*
G01X258916Y-101626D02*
Y-109792D01*
X259790Y-111834D01*
X261100Y-113000D01*
X262628Y-113292D01*
X264156Y-113000D01*
X265466Y-111834D01*
X266340Y-109792D01*
G01Y-113292D02*
Y-101626D01*
G01X276853Y-111251D02*
X277945Y-112417D01*
X279473Y-113292D01*
X280783D01*
X282093Y-112709D01*
X282966Y-111834D01*
X283403Y-110668D01*
X283185Y-108917D01*
X282311Y-108042D01*
X278381Y-106292D01*
X277508Y-104250D01*
X277945Y-102792D01*
X278818Y-101917D01*
X280128Y-101626D01*
X281438Y-101917D01*
X282748Y-102792D01*
G01X297628Y-95792D02*
Y-113292D01*
G01X294571Y-101626D02*
X300685D01*
G01X331318Y-113292D02*
Y-98417D01*
X331755Y-96959D01*
X332628Y-96084D01*
X333938Y-95792D01*
X335248Y-96375D01*
X335903Y-97834D01*
G01X333283Y-102792D02*
X328916D01*
G01X350128Y-113292D02*
X348818Y-113000D01*
X347508Y-111834D01*
X346634Y-109792D01*
X346198Y-107459D01*
X346634Y-105125D01*
X347508Y-103084D01*
X348818Y-101917D01*
X350128Y-101626D01*
X351438Y-101917D01*
X352748Y-103084D01*
X353621Y-105125D01*
X353840Y-107459D01*
X353621Y-109792D01*
X352748Y-111834D01*
X351438Y-113000D01*
X350128Y-113292D01*
G01X364571D02*
Y-101626D01*
G01Y-103959D02*
X365663Y-102792D01*
X366755Y-101917D01*
X368283Y-101626D01*
X369374Y-101917D01*
X370685Y-102792D01*
G01X398043Y-118542D02*
X399353Y-119125D01*
X401100Y-118542D01*
X402191Y-117376D01*
X403065Y-115917D01*
X404374Y-111251D01*
X407213Y-101626D01*
G01X400226D02*
X404374Y-111251D01*
G01X420128Y-113292D02*
X418818Y-113000D01*
X417508Y-111834D01*
X416634Y-109792D01*
X416198Y-107459D01*
X416634Y-105125D01*
X417508Y-103084D01*
X418818Y-101917D01*
X420128Y-101626D01*
X421438Y-101917D01*
X422748Y-103084D01*
X423621Y-105125D01*
X423840Y-107459D01*
X423621Y-109792D01*
X422748Y-111834D01*
X421438Y-113000D01*
X420128Y-113292D01*
G01X433916Y-101626D02*
Y-109792D01*
X434790Y-111834D01*
X436100Y-113000D01*
X437628Y-113292D01*
X439156Y-113000D01*
X440466Y-111834D01*
X441340Y-109792D01*
G01Y-113292D02*
Y-101626D01*
G01X452071Y-113292D02*
Y-101626D01*
G01Y-103959D02*
X453163Y-102792D01*
X454255Y-101917D01*
X455783Y-101626D01*
X456874Y-101917D01*
X458185Y-102792D01*
G01X487071Y-113292D02*
Y-101626D01*
G01Y-103959D02*
X488163Y-102792D01*
X489255Y-101917D01*
X490783Y-101626D01*
X491874Y-101917D01*
X493185Y-102792D01*
G01X504353Y-105417D02*
X511340D01*
X510685Y-103375D01*
X509593Y-102209D01*
X508065Y-101626D01*
X506536Y-101917D01*
X505226Y-102792D01*
X504353Y-104834D01*
X503916Y-106584D01*
Y-108334D01*
X504353Y-110084D01*
X505445Y-111834D01*
X506755Y-113000D01*
X508283Y-113292D01*
X509811Y-112709D01*
X511340Y-110959D01*
G01X523818Y-113292D02*
Y-98417D01*
X524255Y-96959D01*
X525128Y-96084D01*
X526438Y-95792D01*
X527748Y-96375D01*
X528403Y-97834D01*
G01X525783Y-102792D02*
X521416D01*
G01X539353Y-105417D02*
X546340D01*
X545685Y-103375D01*
X544593Y-102209D01*
X543065Y-101626D01*
X541536Y-101917D01*
X540226Y-102792D01*
X539353Y-104834D01*
X538916Y-106584D01*
Y-108334D01*
X539353Y-110084D01*
X540445Y-111834D01*
X541755Y-113000D01*
X543283Y-113292D01*
X544811Y-112709D01*
X546340Y-110959D01*
G01X557071Y-113292D02*
Y-101626D01*
G01Y-103959D02*
X558163Y-102792D01*
X559255Y-101917D01*
X560783Y-101626D01*
X561874Y-101917D01*
X563185Y-102792D01*
G01X574353Y-105417D02*
X581340D01*
X580685Y-103375D01*
X579593Y-102209D01*
X578065Y-101626D01*
X576536Y-101917D01*
X575226Y-102792D01*
X574353Y-104834D01*
X573916Y-106584D01*
Y-108334D01*
X574353Y-110084D01*
X575445Y-111834D01*
X576755Y-113000D01*
X578283Y-113292D01*
X579811Y-112709D01*
X581340Y-110959D01*
G01X591416Y-113292D02*
Y-101626D01*
G01Y-104542D02*
X592290Y-103084D01*
X593600Y-101917D01*
X595346Y-101626D01*
X596874Y-101917D01*
X598185Y-103084D01*
X598840Y-105125D01*
Y-113292D01*
G01X616121Y-103084D02*
X614593Y-101917D01*
X613283Y-101626D01*
X611536Y-102209D01*
X610226Y-103375D01*
X609353Y-105417D01*
X609134Y-107459D01*
X609353Y-109501D01*
X610226Y-111251D01*
X611536Y-112709D01*
X613283Y-113292D01*
X614811Y-112709D01*
X616121Y-111542D01*
G01X626853Y-105417D02*
X633840D01*
X633185Y-103375D01*
X632093Y-102209D01*
X630565Y-101626D01*
X629036Y-101917D01*
X627726Y-102792D01*
X626853Y-104834D01*
X626416Y-106584D01*
Y-108334D01*
X626853Y-110084D01*
X627945Y-111834D01*
X629255Y-113000D01*
X630783Y-113292D01*
X632311Y-112709D01*
X633840Y-110959D01*
G01X665128Y-95792D02*
Y-113292D01*
G01X662071Y-101626D02*
X668185D01*
G01X682628Y-113292D02*
X681318Y-113000D01*
X680008Y-111834D01*
X679134Y-109792D01*
X678698Y-107459D01*
X679134Y-105125D01*
X680008Y-103084D01*
X681318Y-101917D01*
X682628Y-101626D01*
X683938Y-101917D01*
X685248Y-103084D01*
X686121Y-105125D01*
X686340Y-107459D01*
X686121Y-109792D01*
X685248Y-111834D01*
X683938Y-113000D01*
X682628Y-113292D01*
G01X716318D02*
Y-98417D01*
X716755Y-96959D01*
X717628Y-96084D01*
X718938Y-95792D01*
X720248Y-96375D01*
X720903Y-97834D01*
G01X718283Y-102792D02*
X713916D01*
G01X735128Y-101626D02*
Y-113292D01*
G01Y-96959D02*
X734691Y-96667D01*
Y-96084D01*
X735128Y-95792D01*
X735565Y-96084D01*
Y-96667D01*
X735128Y-96959D01*
G01X748916Y-113292D02*
Y-101626D01*
G01Y-104542D02*
X749790Y-103084D01*
X751100Y-101917D01*
X752846Y-101626D01*
X754374Y-101917D01*
X755685Y-103084D01*
X756340Y-105125D01*
Y-113292D01*
G01X774058Y-95792D02*
Y-113292D01*
G01Y-110668D02*
X773185Y-112126D01*
X771874Y-113000D01*
X770346Y-113292D01*
X768600Y-112709D01*
X767290Y-111251D01*
X766416Y-109501D01*
X766198Y-107459D01*
X766416Y-105417D01*
X767290Y-103667D01*
X768600Y-102209D01*
X770346Y-101626D01*
X771874Y-101917D01*
X772966Y-102501D01*
X774058Y-103667D01*
G01X805128Y-95792D02*
Y-113292D01*
G01X802071Y-101626D02*
X808185D01*
G01X818916Y-113292D02*
Y-95792D01*
G01Y-104250D02*
X820008Y-102792D01*
X821100Y-101917D01*
X822846Y-101626D01*
X824156Y-101917D01*
X825685Y-103084D01*
X826340Y-104834D01*
Y-113292D01*
G01X836853Y-105417D02*
X843840D01*
X843185Y-103375D01*
X842093Y-102209D01*
X840565Y-101626D01*
X839036Y-101917D01*
X837726Y-102792D01*
X836853Y-104834D01*
X836416Y-106584D01*
Y-108334D01*
X836853Y-110084D01*
X837945Y-111834D01*
X839255Y-113000D01*
X840783Y-113292D01*
X842311Y-112709D01*
X843840Y-110959D01*
G01X870325Y-113292D02*
Y-95792D01*
X874691D01*
X876438Y-96667D01*
X877748Y-97834D01*
X878840Y-99583D01*
X879713Y-101626D01*
X879931Y-104542D01*
X879713Y-107459D01*
X878840Y-109501D01*
X877748Y-111251D01*
X876438Y-112417D01*
X874691Y-113292D01*
X870325D01*
G01X888261D02*
Y-95792D01*
X893501D01*
X895248Y-96667D01*
X896558Y-98709D01*
X896995Y-101042D01*
X896558Y-103375D01*
X895466Y-105125D01*
X893501Y-106001D01*
X888261D01*
G01X927628Y-101626D02*
Y-113292D01*
G01Y-96959D02*
X927191Y-96667D01*
Y-96084D01*
X927628Y-95792D01*
X928065Y-96084D01*
Y-96667D01*
X927628Y-96959D01*
G01X938578Y-113292D02*
Y-101626D01*
G01Y-104834D02*
X939233Y-103375D01*
X940325Y-102209D01*
X941853Y-101626D01*
X943381Y-102209D01*
X944473Y-103375D01*
X945128Y-104834D01*
Y-113292D01*
G01Y-104834D02*
X945783Y-103375D01*
X946874Y-102209D01*
X948403Y-101626D01*
X949931Y-102209D01*
X951023Y-103375D01*
X951678Y-105125D01*
Y-113292D01*
G01X958698Y-119125D02*
Y-101626D01*
G01Y-104250D02*
X959790Y-102792D01*
X960881Y-101917D01*
X962628Y-101626D01*
X964156Y-101917D01*
X965685Y-103375D01*
X966340Y-105417D01*
X966558Y-107459D01*
X966340Y-109501D01*
X965685Y-111542D01*
X964374Y-112709D01*
X962628Y-113292D01*
X961100Y-113000D01*
X959571Y-112126D01*
X958698Y-110959D01*
G01X976853Y-105417D02*
X983840D01*
X983185Y-103375D01*
X982093Y-102209D01*
X980565Y-101626D01*
X979036Y-101917D01*
X977726Y-102792D01*
X976853Y-104834D01*
X976416Y-106584D01*
Y-108334D01*
X976853Y-110084D01*
X977945Y-111834D01*
X979255Y-113000D01*
X980783Y-113292D01*
X982311Y-112709D01*
X983840Y-110959D01*
G01X1001558Y-95792D02*
Y-113292D01*
G01Y-110668D02*
X1000685Y-112126D01*
X999374Y-113000D01*
X997846Y-113292D01*
X996100Y-112709D01*
X994790Y-111251D01*
X993916Y-109501D01*
X993698Y-107459D01*
X993916Y-105417D01*
X994790Y-103667D01*
X996100Y-102209D01*
X997846Y-101626D01*
X999374Y-101917D01*
X1000466Y-102501D01*
X1001558Y-103667D01*
G01X1019058Y-113292D02*
Y-101626D01*
G01Y-103667D02*
X1018185Y-102501D01*
X1016874Y-101917D01*
X1015346Y-101626D01*
X1013818Y-102209D01*
X1012508Y-103375D01*
X1011634Y-105125D01*
X1011198Y-107459D01*
X1011634Y-109792D01*
X1012508Y-111542D01*
X1013818Y-112709D01*
X1015346Y-113292D01*
X1016874Y-113000D01*
X1018185Y-112126D01*
X1019058Y-110959D01*
G01X1028916Y-113292D02*
Y-101626D01*
G01Y-104542D02*
X1029790Y-103084D01*
X1031100Y-101917D01*
X1032846Y-101626D01*
X1034374Y-101917D01*
X1035685Y-103084D01*
X1036340Y-105125D01*
Y-113292D01*
G01X1053621Y-103084D02*
X1052093Y-101917D01*
X1050783Y-101626D01*
X1049036Y-102209D01*
X1047726Y-103375D01*
X1046853Y-105417D01*
X1046634Y-107459D01*
X1046853Y-109501D01*
X1047726Y-111251D01*
X1049036Y-112709D01*
X1050783Y-113292D01*
X1052311Y-112709D01*
X1053621Y-111542D01*
G01X1064353Y-105417D02*
X1071340D01*
X1070685Y-103375D01*
X1069593Y-102209D01*
X1068065Y-101626D01*
X1066536Y-101917D01*
X1065226Y-102792D01*
X1064353Y-104834D01*
X1063916Y-106584D01*
Y-108334D01*
X1064353Y-110084D01*
X1065445Y-111834D01*
X1066755Y-113000D01*
X1068283Y-113292D01*
X1069811Y-112709D01*
X1071340Y-110959D01*
G01X1102628Y-95792D02*
Y-113292D01*
G01X1099571Y-101626D02*
X1105685D01*
G01X1117071Y-113292D02*
Y-101626D01*
G01Y-103959D02*
X1118163Y-102792D01*
X1119255Y-101917D01*
X1120783Y-101626D01*
X1121874Y-101917D01*
X1123185Y-102792D01*
G01X1141558Y-113292D02*
Y-101626D01*
G01Y-103667D02*
X1140685Y-102501D01*
X1139374Y-101917D01*
X1137846Y-101626D01*
X1136318Y-102209D01*
X1135008Y-103375D01*
X1134134Y-105125D01*
X1133698Y-107459D01*
X1134134Y-109792D01*
X1135008Y-111542D01*
X1136318Y-112709D01*
X1137846Y-113292D01*
X1139374Y-113000D01*
X1140685Y-112126D01*
X1141558Y-110959D01*
G01X1158621Y-103084D02*
X1157093Y-101917D01*
X1155783Y-101626D01*
X1154036Y-102209D01*
X1152726Y-103375D01*
X1151853Y-105417D01*
X1151634Y-107459D01*
X1151853Y-109501D01*
X1152726Y-111251D01*
X1154036Y-112709D01*
X1155783Y-113292D01*
X1157311Y-112709D01*
X1158621Y-111542D01*
G01X1169353Y-105417D02*
X1176340D01*
X1175685Y-103375D01*
X1174593Y-102209D01*
X1173065Y-101626D01*
X1171536Y-101917D01*
X1170226Y-102792D01*
X1169353Y-104834D01*
X1168916Y-106584D01*
Y-108334D01*
X1169353Y-110084D01*
X1170445Y-111834D01*
X1171755Y-113000D01*
X1173283Y-113292D01*
X1174811Y-112709D01*
X1176340Y-110959D01*
G01X1186853Y-111251D02*
X1187945Y-112417D01*
X1189473Y-113292D01*
X1190783D01*
X1192093Y-112709D01*
X1192966Y-111834D01*
X1193403Y-110668D01*
X1193185Y-108917D01*
X1192311Y-108042D01*
X1188381Y-106292D01*
X1187508Y-104250D01*
X1187945Y-102792D01*
X1188818Y-101917D01*
X1190128Y-101626D01*
X1191438Y-101917D01*
X1192748Y-102792D01*
G01X1225128Y-101626D02*
Y-113292D01*
G01Y-96959D02*
X1224691Y-96667D01*
Y-96084D01*
X1225128Y-95792D01*
X1225565Y-96084D01*
Y-96667D01*
X1225128Y-96959D01*
G01X1238916Y-113292D02*
Y-101626D01*
G01Y-104542D02*
X1239790Y-103084D01*
X1241100Y-101917D01*
X1242846Y-101626D01*
X1244374Y-101917D01*
X1245685Y-103084D01*
X1246340Y-105125D01*
Y-113292D01*
G01X1277628D02*
Y-95792D01*
G01X1299058Y-113292D02*
Y-101626D01*
G01Y-103667D02*
X1298185Y-102501D01*
X1296874Y-101917D01*
X1295346Y-101626D01*
X1293818Y-102209D01*
X1292508Y-103375D01*
X1291634Y-105125D01*
X1291198Y-107459D01*
X1291634Y-109792D01*
X1292508Y-111542D01*
X1293818Y-112709D01*
X1295346Y-113292D01*
X1296874Y-113000D01*
X1298185Y-112126D01*
X1299058Y-110959D01*
G01X1308043Y-118542D02*
X1309353Y-119125D01*
X1311100Y-118542D01*
X1312191Y-117376D01*
X1313065Y-115917D01*
X1314374Y-111251D01*
X1317213Y-101626D01*
G01X1310226D02*
X1314374Y-111251D01*
G01X1326853Y-105417D02*
X1333840D01*
X1333185Y-103375D01*
X1332093Y-102209D01*
X1330565Y-101626D01*
X1329036Y-101917D01*
X1327726Y-102792D01*
X1326853Y-104834D01*
X1326416Y-106584D01*
Y-108334D01*
X1326853Y-110084D01*
X1327945Y-111834D01*
X1329255Y-113000D01*
X1330783Y-113292D01*
X1332311Y-112709D01*
X1333840Y-110959D01*
G01X1344571Y-113292D02*
Y-101626D01*
G01Y-103959D02*
X1345663Y-102792D01*
X1346755Y-101917D01*
X1348283Y-101626D01*
X1349374Y-101917D01*
X1350685Y-102792D01*
G01X1378261Y-95792D02*
Y-113292D01*
X1386995D01*
G01X1400128D02*
Y-95792D01*
X1397508Y-99292D01*
G01Y-113292D02*
X1402748D01*
G01X1413480Y-98709D02*
X1414790Y-96959D01*
X1416318Y-96084D01*
X1418065Y-95792D01*
X1420248Y-96375D01*
X1421776Y-97834D01*
X1422213Y-99583D01*
X1421995Y-101334D01*
X1421121Y-102792D01*
X1416755Y-105709D01*
X1414790Y-107750D01*
X1413480Y-110668D01*
X1413043Y-113292D01*
X1422213D01*
G01X1435128Y-113875D02*
X1434691Y-113584D01*
Y-113000D01*
X1435128Y-112709D01*
X1435565Y-113000D01*
Y-113584D01*
X1435128Y-113875D01*
G01X2079178Y467898D02*
Y485398D01*
X2076558Y481898D01*
G01Y467898D02*
X2081798D01*
G01X2096678Y485398D02*
X2094931Y484815D01*
X2093621Y483356D01*
X2092748Y481607D01*
X2092093Y479273D01*
X2091875Y476648D01*
X2092093Y474023D01*
X2092748Y471689D01*
X2093621Y469939D01*
X2094931Y468481D01*
X2096678Y467898D01*
X2098424Y468481D01*
X2099735Y469939D01*
X2100608Y471689D01*
X2101263Y474023D01*
X2101481Y476648D01*
X2101263Y479273D01*
X2100608Y481607D01*
X2099735Y483356D01*
X2098424Y484815D01*
X2096678Y485398D01*
G01X2114178D02*
X2112431Y484815D01*
X2111121Y483356D01*
X2110248Y481607D01*
X2109593Y479273D01*
X2109375Y476648D01*
X2109593Y474023D01*
X2110248Y471689D01*
X2111121Y469939D01*
X2112431Y468481D01*
X2114178Y467898D01*
X2115924Y468481D01*
X2117235Y469939D01*
X2118108Y471689D01*
X2118763Y474023D01*
X2118981Y476648D01*
X2118763Y479273D01*
X2118108Y481607D01*
X2117235Y483356D01*
X2115924Y484815D01*
X2114178Y485398D01*
G01X2131678Y467315D02*
X2131241Y467606D01*
Y468190D01*
X2131678Y468481D01*
X2132115Y468190D01*
Y467606D01*
X2131678Y467315D01*
G01X2149178Y485398D02*
X2147431Y484815D01*
X2146121Y483356D01*
X2145248Y481607D01*
X2144593Y479273D01*
X2144375Y476648D01*
X2144593Y474023D01*
X2145248Y471689D01*
X2146121Y469939D01*
X2147431Y468481D01*
X2149178Y467898D01*
X2150924Y468481D01*
X2152235Y469939D01*
X2153108Y471689D01*
X2153763Y474023D01*
X2153981Y476648D01*
X2153763Y479273D01*
X2153108Y481607D01*
X2152235Y483356D01*
X2150924Y484815D01*
X2149178Y485398D01*
G01X2084216Y504589D02*
X2085745Y503131D01*
X2087491Y502548D01*
X2089238Y503131D01*
X2090766Y504881D01*
X2091858Y507506D01*
X2092295Y510131D01*
Y513339D01*
X2091858Y515964D01*
X2090766Y518298D01*
X2089456Y519465D01*
X2087928Y520048D01*
X2086181Y519465D01*
X2084871Y518298D01*
X2083998Y516548D01*
X2083561Y514214D01*
X2083998Y512173D01*
X2085090Y510131D01*
X2086400Y508964D01*
X2087928Y508673D01*
X2089674Y509256D01*
X2090985Y510715D01*
X2092295Y513339D01*
G01X2100625Y505172D02*
X2101934Y503714D01*
X2103463Y502840D01*
X2105428Y502548D01*
X2107393Y503131D01*
X2108921Y504298D01*
X2110013Y506339D01*
X2110231Y508673D01*
X2109795Y511006D01*
X2108703Y512465D01*
X2107174Y513631D01*
X2105646Y513923D01*
X2104118Y513631D01*
X2102153Y512465D01*
X2102808Y520048D01*
X2108703D01*
G01X2122928Y501965D02*
X2122491Y502256D01*
Y502840D01*
X2122928Y503131D01*
X2123365Y502840D01*
Y502256D01*
X2122928Y501965D01*
G01X2140428Y520048D02*
X2138681Y519465D01*
X2137371Y518006D01*
X2136498Y516257D01*
X2135843Y513923D01*
X2135625Y511298D01*
X2135843Y508673D01*
X2136498Y506339D01*
X2137371Y504589D01*
X2138681Y503131D01*
X2140428Y502548D01*
X2142174Y503131D01*
X2143485Y504589D01*
X2144358Y506339D01*
X2145013Y508673D01*
X2145231Y511298D01*
X2145013Y513923D01*
X2144358Y516257D01*
X2143485Y518006D01*
X2142174Y519465D01*
X2140428Y520048D01*
G01X2087928Y537198D02*
X2089456Y537490D01*
X2091203Y538364D01*
X2092295Y539822D01*
X2092731Y541865D01*
X2092295Y543906D01*
X2090985Y545656D01*
X2089020Y546531D01*
X2086836D01*
X2085526Y547115D01*
X2084434Y548573D01*
X2083998Y550614D01*
X2084653Y552656D01*
X2086181Y554115D01*
X2087928Y554698D01*
X2089674Y554115D01*
X2091203Y552656D01*
X2091858Y550614D01*
X2091421Y548573D01*
X2090330Y547115D01*
X2089020Y546531D01*
X2086836D01*
X2084871Y545656D01*
X2083561Y543906D01*
X2083125Y541865D01*
X2083561Y539822D01*
X2084653Y538364D01*
X2086400Y537490D01*
X2087928Y537198D01*
G01X2100625Y539822D02*
X2101934Y538364D01*
X2103463Y537490D01*
X2105428Y537198D01*
X2107393Y537781D01*
X2108921Y538948D01*
X2110013Y540989D01*
X2110231Y543323D01*
X2109795Y545656D01*
X2108703Y547115D01*
X2107174Y548281D01*
X2105646Y548573D01*
X2104118Y548281D01*
X2102153Y547115D01*
X2102808Y554698D01*
X2108703D01*
G01X2122928Y536615D02*
X2122491Y536906D01*
Y537490D01*
X2122928Y537781D01*
X2123365Y537490D01*
Y536906D01*
X2122928Y536615D01*
G01X2140428Y554698D02*
X2138681Y554115D01*
X2137371Y552656D01*
X2136498Y550907D01*
X2135843Y548573D01*
X2135625Y545948D01*
X2135843Y543323D01*
X2136498Y540989D01*
X2137371Y539239D01*
X2138681Y537781D01*
X2140428Y537198D01*
X2142174Y537781D01*
X2143485Y539239D01*
X2144358Y540989D01*
X2145013Y543323D01*
X2145231Y545948D01*
X2145013Y548573D01*
X2144358Y550907D01*
X2143485Y552656D01*
X2142174Y554115D01*
X2140428Y554698D01*
G01X2087491Y571848D02*
X2087928Y575639D01*
X2088583Y578848D01*
X2089456Y581765D01*
X2090548Y584973D01*
X2092295Y589348D01*
X2083561D01*
G01X2100625Y575348D02*
X2101934Y573306D01*
X2103681Y572140D01*
X2105646Y571848D01*
X2107393Y572140D01*
X2109140Y573598D01*
X2110231Y575348D01*
X2110450Y577098D01*
X2110013Y579139D01*
X2108485Y580598D01*
X2106956Y581181D01*
X2104991D01*
G01X2106956D02*
X2108266Y582056D01*
X2109358Y583514D01*
X2109795Y585264D01*
X2109358Y587015D01*
X2108266Y588473D01*
X2106301Y589348D01*
X2104336Y589056D01*
X2102371Y587889D01*
G01X2122928Y571265D02*
X2122491Y571556D01*
Y572140D01*
X2122928Y572431D01*
X2123365Y572140D01*
Y571556D01*
X2122928Y571265D01*
G01X2140428Y589348D02*
X2138681Y588765D01*
X2137371Y587306D01*
X2136498Y585557D01*
X2135843Y583223D01*
X2135625Y580598D01*
X2135843Y577973D01*
X2136498Y575639D01*
X2137371Y573889D01*
X2138681Y572431D01*
X2140428Y571848D01*
X2142174Y572431D01*
X2143485Y573889D01*
X2144358Y575639D01*
X2145013Y577973D01*
X2145231Y580598D01*
X2145013Y583223D01*
X2144358Y585557D01*
X2143485Y587306D01*
X2142174Y588765D01*
X2140428Y589348D01*
G01X2050308Y623998D02*
X2055548D01*
G01X2052928D02*
Y606498D01*
G01X2050308D02*
X2055548D01*
G01X2064751D02*
Y623998D01*
X2070428Y609415D01*
X2076105Y623998D01*
Y606498D01*
G01X2083561D02*
Y623998D01*
X2088801D01*
X2090548Y623123D01*
X2091858Y621081D01*
X2092295Y618748D01*
X2091858Y616415D01*
X2090766Y614665D01*
X2088801Y613789D01*
X2083561D01*
G01X2104336Y600665D02*
X2102153Y603581D01*
X2101061Y606498D01*
Y618164D01*
X2102153Y621081D01*
X2104336Y623998D01*
G01X2122928Y606498D02*
X2121181Y606790D01*
X2119653Y607956D01*
X2118343Y609706D01*
X2117469Y611748D01*
X2117033Y614081D01*
Y616415D01*
X2117469Y618748D01*
X2118343Y620790D01*
X2119653Y622539D01*
X2121181Y623706D01*
X2122928Y623998D01*
X2124674Y623706D01*
X2126203Y622539D01*
X2127513Y620790D01*
X2128387Y618748D01*
X2128823Y616415D01*
Y614081D01*
X2128387Y611748D01*
X2127513Y609706D01*
X2126203Y607956D01*
X2124674Y606790D01*
X2122928Y606498D01*
G01X2136716D02*
Y623998D01*
G01Y615540D02*
X2137808Y616998D01*
X2138900Y617873D01*
X2140646Y618164D01*
X2141956Y617873D01*
X2143485Y616706D01*
X2144140Y614956D01*
Y606498D01*
G01X2151378D02*
Y618164D01*
G01Y614956D02*
X2152033Y616415D01*
X2153125Y617581D01*
X2154653Y618164D01*
X2156181Y617581D01*
X2157273Y616415D01*
X2157928Y614956D01*
Y606498D01*
G01Y614956D02*
X2158583Y616415D01*
X2159674Y617581D01*
X2161203Y618164D01*
X2162731Y617581D01*
X2163823Y616415D01*
X2164478Y614665D01*
Y606498D01*
G01X2176520Y600665D02*
X2178703Y603581D01*
X2179795Y606498D01*
Y618164D01*
X2178703Y621081D01*
X2176520Y623998D01*
G01X2028425Y641148D02*
Y658648D01*
X2032791D01*
X2034538Y657773D01*
X2035848Y656606D01*
X2036940Y654857D01*
X2037813Y652814D01*
X2038031Y649898D01*
X2037813Y646981D01*
X2036940Y644939D01*
X2035848Y643189D01*
X2034538Y642023D01*
X2032791Y641148D01*
X2028425D01*
G01X2046361D02*
Y658648D01*
X2051601D01*
X2053348Y657773D01*
X2054658Y655731D01*
X2055095Y653398D01*
X2054658Y651065D01*
X2053566Y649315D01*
X2051601Y648439D01*
X2046361D01*
G01X2083108Y658648D02*
X2088348D01*
G01X2085728D02*
Y641148D01*
G01X2083108D02*
X2088348D01*
G01X2097551D02*
Y658648D01*
X2103228Y644065D01*
X2108905Y658648D01*
Y641148D01*
G01X2116361D02*
Y658648D01*
X2121601D01*
X2123348Y657773D01*
X2124658Y655731D01*
X2125095Y653398D01*
X2124658Y651065D01*
X2123566Y649315D01*
X2121601Y648439D01*
X2116361D01*
G01X2142595Y641148D02*
X2133861D01*
Y658648D01*
X2142595D01*
G01X2139101Y650190D02*
X2133861D01*
G01X2150925Y641148D02*
Y658648D01*
X2155291D01*
X2157038Y657773D01*
X2158348Y656606D01*
X2159440Y654857D01*
X2160313Y652814D01*
X2160531Y649898D01*
X2160313Y646981D01*
X2159440Y644939D01*
X2158348Y643189D01*
X2157038Y642023D01*
X2155291Y641148D01*
X2150925D01*
G01X2167769D02*
X2173228Y658648D01*
X2178687Y641148D01*
G01X2176721Y647273D02*
X2169734D01*
G01X2185706Y641148D02*
Y658648D01*
X2195750Y641148D01*
Y658648D01*
G01X2213031Y657189D02*
X2211721Y658065D01*
X2210193Y658648D01*
X2208446D01*
X2206481Y657773D01*
X2204953Y656315D01*
X2203861Y654564D01*
X2202988Y651648D01*
X2202769Y649023D01*
X2203206Y646398D01*
X2203861Y644648D01*
X2205171Y642898D01*
X2206700Y641731D01*
X2208228Y641148D01*
X2209756D01*
X2211285Y641731D01*
X2212595Y642606D01*
X2213687Y643772D01*
G01X2230095Y641148D02*
X2221361D01*
Y658648D01*
X2230095D01*
G01X2226601Y650190D02*
X2221361D01*
G01X2260728Y658648D02*
Y641148D01*
G01X2255706Y658648D02*
X2265750D01*
G01X2272769Y641148D02*
X2278228Y658648D01*
X2283687Y641148D01*
G01X2281721Y647273D02*
X2274734D01*
G01X2297474Y650481D02*
X2298348Y651356D01*
X2299003Y652814D01*
X2299440Y654857D01*
X2299003Y656606D01*
X2298130Y657773D01*
X2296601Y658648D01*
X2290706D01*
Y641148D01*
X2297911D01*
X2299440Y642314D01*
X2300313Y644065D01*
X2300750Y646106D01*
X2300313Y648148D01*
X2299003Y649898D01*
X2297474Y650481D01*
X2290706D01*
G01X2308861Y658648D02*
Y641148D01*
X2317595D01*
G01X2335095D02*
X2326361D01*
Y658648D01*
X2335095D01*
G01X2331601Y650190D02*
X2326361D01*
G01X2348228Y640565D02*
X2347791Y640856D01*
Y641440D01*
X2348228Y641731D01*
X2348665Y641440D01*
Y640856D01*
X2348228Y640565D01*
G01Y648439D02*
X2347791Y648731D01*
Y649315D01*
X2348228Y649606D01*
X2348665Y649315D01*
Y648731D01*
X2348228Y648439D01*
G01X2378861Y658648D02*
Y641148D01*
X2387595D01*
G01X2400728D02*
Y658648D01*
X2398108Y655148D01*
G01Y641148D02*
X2403348D01*
G01X2414080Y655731D02*
X2415390Y657481D01*
X2416918Y658356D01*
X2418665Y658648D01*
X2420848Y658065D01*
X2422376Y656606D01*
X2422813Y654857D01*
X2422595Y653106D01*
X2421721Y651648D01*
X2417355Y648731D01*
X2415390Y646690D01*
X2414080Y643772D01*
X2413643Y641148D01*
X2422813D01*
G01X2310625Y471398D02*
X2311934Y469356D01*
X2313681Y468190D01*
X2315646Y467898D01*
X2317393Y468190D01*
X2319140Y469648D01*
X2320231Y471398D01*
X2320450Y473148D01*
X2320013Y475189D01*
X2318485Y476648D01*
X2316956Y477231D01*
X2314991D01*
G01X2316956D02*
X2318266Y478106D01*
X2319358Y479564D01*
X2319795Y481314D01*
X2319358Y483065D01*
X2318266Y484523D01*
X2316301Y485398D01*
X2314336Y485106D01*
X2312371Y483939D01*
G01X2332928Y467315D02*
X2332491Y467606D01*
Y468190D01*
X2332928Y468481D01*
X2333365Y468190D01*
Y467606D01*
X2332928Y467315D01*
G01X2346716Y469939D02*
X2348245Y468481D01*
X2349991Y467898D01*
X2351738Y468481D01*
X2353266Y470231D01*
X2354358Y472856D01*
X2354795Y475481D01*
Y478689D01*
X2354358Y481314D01*
X2353266Y483648D01*
X2351956Y484815D01*
X2350428Y485398D01*
X2348681Y484815D01*
X2347371Y483648D01*
X2346498Y481898D01*
X2346061Y479564D01*
X2346498Y477523D01*
X2347590Y475481D01*
X2348900Y474314D01*
X2350428Y474023D01*
X2352174Y474606D01*
X2353485Y476065D01*
X2354795Y478689D01*
G01X2364216Y469939D02*
X2365745Y468481D01*
X2367491Y467898D01*
X2369238Y468481D01*
X2370766Y470231D01*
X2371858Y472856D01*
X2372295Y475481D01*
Y478689D01*
X2371858Y481314D01*
X2370766Y483648D01*
X2369456Y484815D01*
X2367928Y485398D01*
X2366181Y484815D01*
X2364871Y483648D01*
X2363998Y481898D01*
X2363561Y479564D01*
X2363998Y477523D01*
X2365090Y475481D01*
X2366400Y474314D01*
X2367928Y474023D01*
X2369674Y474606D01*
X2370985Y476065D01*
X2372295Y478689D01*
G01X2381498Y467315D02*
X2389358Y485398D01*
G01X2402928Y467898D02*
Y485398D01*
X2400308Y481898D01*
G01Y467898D02*
X2405548D01*
G01X2416280Y482481D02*
X2417590Y484231D01*
X2419118Y485106D01*
X2420865Y485398D01*
X2423048Y484815D01*
X2424576Y483356D01*
X2425013Y481607D01*
X2424795Y479856D01*
X2423921Y478398D01*
X2419555Y475481D01*
X2417590Y473440D01*
X2416280Y470522D01*
X2415843Y467898D01*
X2425013D01*
G01X2437928Y467315D02*
X2437491Y467606D01*
Y468190D01*
X2437928Y468481D01*
X2438365Y468190D01*
Y467606D01*
X2437928Y467315D01*
G01X2450625Y470522D02*
X2451934Y469064D01*
X2453463Y468190D01*
X2455428Y467898D01*
X2457393Y468481D01*
X2458921Y469648D01*
X2460013Y471689D01*
X2460231Y474023D01*
X2459795Y476356D01*
X2458703Y477815D01*
X2457174Y478981D01*
X2455646Y479273D01*
X2454118Y478981D01*
X2452153Y477815D01*
X2452808Y485398D01*
X2458703D01*
G01X2468780Y482481D02*
X2470090Y484231D01*
X2471618Y485106D01*
X2473365Y485398D01*
X2475548Y484815D01*
X2477076Y483356D01*
X2477513Y481607D01*
X2477295Y479856D01*
X2476421Y478398D01*
X2472055Y475481D01*
X2470090Y473440D01*
X2468780Y470522D01*
X2468343Y467898D01*
X2477513D01*
G01X2318048Y502548D02*
Y520048D01*
X2309969Y507506D01*
X2320887D01*
G01X2332928Y501965D02*
X2332491Y502256D01*
Y502840D01*
X2332928Y503131D01*
X2333365Y502840D01*
Y502256D01*
X2332928Y501965D01*
G01X2350428Y520048D02*
X2348681Y519465D01*
X2347371Y518006D01*
X2346498Y516257D01*
X2345843Y513923D01*
X2345625Y511298D01*
X2345843Y508673D01*
X2346498Y506339D01*
X2347371Y504589D01*
X2348681Y503131D01*
X2350428Y502548D01*
X2352174Y503131D01*
X2353485Y504589D01*
X2354358Y506339D01*
X2355013Y508673D01*
X2355231Y511298D01*
X2355013Y513923D01*
X2354358Y516257D01*
X2353485Y518006D01*
X2352174Y519465D01*
X2350428Y520048D01*
G01X2363780Y517131D02*
X2365090Y518881D01*
X2366618Y519756D01*
X2368365Y520048D01*
X2370548Y519465D01*
X2372076Y518006D01*
X2372513Y516257D01*
X2372295Y514506D01*
X2371421Y513048D01*
X2367055Y510131D01*
X2365090Y508090D01*
X2363780Y505172D01*
X2363343Y502548D01*
X2372513D01*
G01X2381498Y501965D02*
X2389358Y520048D01*
G01X2402928Y502548D02*
Y520048D01*
X2400308Y516548D01*
G01Y502548D02*
X2405548D01*
G01X2420428D02*
Y520048D01*
X2417808Y516548D01*
G01Y502548D02*
X2423048D01*
G01X2437928Y501965D02*
X2437491Y502256D01*
Y502840D01*
X2437928Y503131D01*
X2438365Y502840D01*
Y502256D01*
X2437928Y501965D01*
G01X2451716Y504589D02*
X2453245Y503131D01*
X2454991Y502548D01*
X2456738Y503131D01*
X2458266Y504881D01*
X2459358Y507506D01*
X2459795Y510131D01*
Y513339D01*
X2459358Y515964D01*
X2458266Y518298D01*
X2456956Y519465D01*
X2455428Y520048D01*
X2453681Y519465D01*
X2452371Y518298D01*
X2451498Y516548D01*
X2451061Y514214D01*
X2451498Y512173D01*
X2452590Y510131D01*
X2453900Y508964D01*
X2455428Y508673D01*
X2457174Y509256D01*
X2458485Y510715D01*
X2459795Y513339D01*
G01X2472928Y502548D02*
X2474456Y502840D01*
X2476203Y503714D01*
X2477295Y505172D01*
X2477731Y507215D01*
X2477295Y509256D01*
X2475985Y511006D01*
X2474020Y511881D01*
X2471836D01*
X2470526Y512465D01*
X2469434Y513923D01*
X2468998Y515964D01*
X2469653Y518006D01*
X2471181Y519465D01*
X2472928Y520048D01*
X2474674Y519465D01*
X2476203Y518006D01*
X2476858Y515964D01*
X2476421Y513923D01*
X2475330Y512465D01*
X2474020Y511881D01*
X2471836D01*
X2469871Y511006D01*
X2468561Y509256D01*
X2468125Y507215D01*
X2468561Y505172D01*
X2469653Y503714D01*
X2471400Y502840D01*
X2472928Y502548D01*
G01X2300128Y623998D02*
X2303184Y606498D01*
X2306678Y623998D01*
X2310171Y606498D01*
X2313228Y623998D01*
G01X2321558D02*
X2326798D01*
G01X2324178D02*
Y606498D01*
G01X2321558D02*
X2326798D01*
G01X2336875D02*
Y623998D01*
X2341241D01*
X2342988Y623123D01*
X2344298Y621956D01*
X2345390Y620207D01*
X2346263Y618164D01*
X2346481Y615248D01*
X2346263Y612331D01*
X2345390Y610289D01*
X2344298Y608539D01*
X2342988Y607373D01*
X2341241Y606498D01*
X2336875D01*
G01X2359178Y623998D02*
Y606498D01*
G01X2354156Y623998D02*
X2364200D01*
G01X2372093Y606498D02*
Y623998D01*
G01X2381263D02*
Y606498D01*
G01Y615248D02*
X2372093D01*
G01X2393086Y600665D02*
X2390903Y603581D01*
X2389811Y606498D01*
Y618164D01*
X2390903Y621081D01*
X2393086Y623998D01*
G01X2405128Y606498D02*
Y618164D01*
G01Y614956D02*
X2405783Y616415D01*
X2406875Y617581D01*
X2408403Y618164D01*
X2409931Y617581D01*
X2411023Y616415D01*
X2411678Y614956D01*
Y606498D01*
G01Y614956D02*
X2412333Y616415D01*
X2413424Y617581D01*
X2414953Y618164D01*
X2416481Y617581D01*
X2417573Y616415D01*
X2418228Y614665D01*
Y606498D01*
G01X2429178Y618164D02*
Y606498D01*
G01Y622831D02*
X2428741Y623123D01*
Y623706D01*
X2429178Y623998D01*
X2429615Y623706D01*
Y623123D01*
X2429178Y622831D01*
G01X2446678Y606498D02*
Y623998D01*
G01X2460903Y608539D02*
X2461995Y607373D01*
X2463523Y606498D01*
X2464833D01*
X2466143Y607081D01*
X2467016Y607956D01*
X2467453Y609122D01*
X2467235Y610873D01*
X2466361Y611748D01*
X2462431Y613498D01*
X2461558Y615540D01*
X2461995Y616998D01*
X2462868Y617873D01*
X2464178Y618164D01*
X2465488Y617873D01*
X2466798Y616998D01*
G01X2482770Y600665D02*
X2484953Y603581D01*
X2486045Y606498D01*
Y618164D01*
X2484953Y621081D01*
X2482770Y623998D01*
G01X2344298Y537198D02*
Y554698D01*
X2336219Y542156D01*
X2347137D01*
G01X2359178Y536615D02*
X2358741Y536906D01*
Y537490D01*
X2359178Y537781D01*
X2359615Y537490D01*
Y536906D01*
X2359178Y536615D01*
G01X2371875Y539822D02*
X2373184Y538364D01*
X2374713Y537490D01*
X2376678Y537198D01*
X2378643Y537781D01*
X2380171Y538948D01*
X2381263Y540989D01*
X2381481Y543323D01*
X2381045Y545656D01*
X2379953Y547115D01*
X2378424Y548281D01*
X2376896Y548573D01*
X2375368Y548281D01*
X2373403Y547115D01*
X2374058Y554698D01*
X2379953D01*
G01X2390248Y536615D02*
X2398108Y554698D01*
G01X2411241Y537198D02*
X2411678Y540989D01*
X2412333Y544198D01*
X2413206Y547115D01*
X2414298Y550323D01*
X2416045Y554698D01*
X2407311D01*
G01X2429178Y536615D02*
X2428741Y536906D01*
Y537490D01*
X2429178Y537781D01*
X2429615Y537490D01*
Y536906D01*
X2429178Y536615D01*
G01X2446678Y554698D02*
X2444931Y554115D01*
X2443621Y552656D01*
X2442748Y550907D01*
X2442093Y548573D01*
X2441875Y545948D01*
X2442093Y543323D01*
X2442748Y540989D01*
X2443621Y539239D01*
X2444931Y537781D01*
X2446678Y537198D01*
X2448424Y537781D01*
X2449735Y539239D01*
X2450608Y540989D01*
X2451263Y543323D01*
X2451481Y545948D01*
X2451263Y548573D01*
X2450608Y550907D01*
X2449735Y552656D01*
X2448424Y554115D01*
X2446678Y554698D01*
G01X2336875Y574472D02*
X2338184Y573014D01*
X2339713Y572140D01*
X2341678Y571848D01*
X2343643Y572431D01*
X2345171Y573598D01*
X2346263Y575639D01*
X2346481Y577973D01*
X2346045Y580306D01*
X2344953Y581765D01*
X2343424Y582931D01*
X2341896Y583223D01*
X2340368Y582931D01*
X2338403Y581765D01*
X2339058Y589348D01*
X2344953D01*
G01X2359178Y571265D02*
X2358741Y571556D01*
Y572140D01*
X2359178Y572431D01*
X2359615Y572140D01*
Y571556D01*
X2359178Y571265D01*
G01X2372530Y579139D02*
X2374058Y581181D01*
X2375368Y582348D01*
X2377115Y582931D01*
X2378643Y582348D01*
X2379735Y581181D01*
X2380608Y579431D01*
X2380826Y577390D01*
X2380608Y575639D01*
X2379735Y573889D01*
X2378424Y572431D01*
X2376896Y571848D01*
X2375150Y572431D01*
X2373621Y574181D01*
X2372748Y576806D01*
X2372530Y579723D01*
X2372966Y583514D01*
X2373621Y585557D01*
X2374713Y587598D01*
X2376241Y589056D01*
X2377770Y589348D01*
X2379298Y588765D01*
X2380390Y587306D01*
G01X2390248Y571265D02*
X2398108Y589348D01*
G01X2406875Y574472D02*
X2408184Y573014D01*
X2409713Y572140D01*
X2411678Y571848D01*
X2413643Y572431D01*
X2415171Y573598D01*
X2416263Y575639D01*
X2416481Y577973D01*
X2416045Y580306D01*
X2414953Y581765D01*
X2413424Y582931D01*
X2411896Y583223D01*
X2410368Y582931D01*
X2408403Y581765D01*
X2409058Y589348D01*
X2414953D01*
G01X2429178Y571265D02*
X2428741Y571556D01*
Y572140D01*
X2429178Y572431D01*
X2429615Y572140D01*
Y571556D01*
X2429178Y571265D01*
G01X2446678Y589348D02*
X2444931Y588765D01*
X2443621Y587306D01*
X2442748Y585557D01*
X2442093Y583223D01*
X2441875Y580598D01*
X2442093Y577973D01*
X2442748Y575639D01*
X2443621Y573889D01*
X2444931Y572431D01*
X2446678Y571848D01*
X2448424Y572431D01*
X2449735Y573889D01*
X2450608Y575639D01*
X2451263Y577973D01*
X2451481Y580598D01*
X2451263Y583223D01*
X2450608Y585557D01*
X2449735Y587306D01*
X2448424Y588765D01*
X2446678Y589348D01*
G01X2625625Y467898D02*
Y485398D01*
X2629991D01*
X2631738Y484523D01*
X2633048Y483356D01*
X2634140Y481607D01*
X2635013Y479564D01*
X2635231Y476648D01*
X2635013Y473731D01*
X2634140Y471689D01*
X2633048Y469939D01*
X2631738Y468773D01*
X2629991Y467898D01*
X2625625D01*
G01X2643561D02*
Y485398D01*
X2648801D01*
X2650548Y484523D01*
X2651858Y482481D01*
X2652295Y480148D01*
X2651858Y477815D01*
X2650766Y476065D01*
X2648801Y475189D01*
X2643561D01*
G01X2625625Y502548D02*
Y520048D01*
X2629991D01*
X2631738Y519173D01*
X2633048Y518006D01*
X2634140Y516257D01*
X2635013Y514214D01*
X2635231Y511298D01*
X2635013Y508381D01*
X2634140Y506339D01*
X2633048Y504589D01*
X2631738Y503423D01*
X2629991Y502548D01*
X2625625D01*
G01X2643561D02*
Y520048D01*
X2648801D01*
X2650548Y519173D01*
X2651858Y517131D01*
X2652295Y514798D01*
X2651858Y512465D01*
X2650766Y510715D01*
X2648801Y509839D01*
X2643561D01*
G01X2625625Y537198D02*
Y554698D01*
X2629991D01*
X2631738Y553823D01*
X2633048Y552656D01*
X2634140Y550907D01*
X2635013Y548864D01*
X2635231Y545948D01*
X2635013Y543031D01*
X2634140Y540989D01*
X2633048Y539239D01*
X2631738Y538073D01*
X2629991Y537198D01*
X2625625D01*
G01X2643561D02*
Y554698D01*
X2648801D01*
X2650548Y553823D01*
X2651858Y551781D01*
X2652295Y549448D01*
X2651858Y547115D01*
X2650766Y545365D01*
X2648801Y544489D01*
X2643561D01*
G01X2625625Y571848D02*
Y589348D01*
X2629991D01*
X2631738Y588473D01*
X2633048Y587306D01*
X2634140Y585557D01*
X2635013Y583514D01*
X2635231Y580598D01*
X2635013Y577681D01*
X2634140Y575639D01*
X2633048Y573889D01*
X2631738Y572723D01*
X2629991Y571848D01*
X2625625D01*
G01X2643561D02*
Y589348D01*
X2648801D01*
X2650548Y588473D01*
X2651858Y586431D01*
X2652295Y584098D01*
X2651858Y581765D01*
X2650766Y580015D01*
X2648801Y579139D01*
X2643561D01*
G01X2612928Y623998D02*
Y606498D01*
G01X2607906Y623998D02*
X2617950D01*
G01X2630428Y606498D02*
Y614373D01*
X2626061Y623998D01*
G01X2634795D02*
X2630428Y614373D01*
G01X2643561Y606498D02*
Y623998D01*
X2648801D01*
X2650548Y623123D01*
X2651858Y621081D01*
X2652295Y618748D01*
X2651858Y616415D01*
X2650766Y614665D01*
X2648801Y613789D01*
X2643561D01*
G01X2669795Y606498D02*
X2661061D01*
Y623998D01*
X2669795D01*
G01X2666301Y615540D02*
X2661061D01*
G01X2739811Y485398D02*
Y467898D01*
X2748545D01*
G01X2761678D02*
Y485398D01*
X2759058Y481898D01*
G01Y467898D02*
X2764298D01*
G01X2779178D02*
Y485398D01*
X2776558Y481898D01*
G01Y467898D02*
X2781798D01*
G01X2792748Y467315D02*
X2800608Y485398D01*
G01X2809811D02*
Y467898D01*
X2818545D01*
G01X2831678D02*
Y485398D01*
X2829058Y481898D01*
G01Y467898D02*
X2834298D01*
G01X2844375Y471398D02*
X2845684Y469356D01*
X2847431Y468190D01*
X2849396Y467898D01*
X2851143Y468190D01*
X2852890Y469648D01*
X2853981Y471398D01*
X2854200Y473148D01*
X2853763Y475189D01*
X2852235Y476648D01*
X2850706Y477231D01*
X2848741D01*
G01X2850706D02*
X2852016Y478106D01*
X2853108Y479564D01*
X2853545Y481314D01*
X2853108Y483065D01*
X2852016Y484523D01*
X2850051Y485398D01*
X2848086Y485106D01*
X2846121Y483939D01*
G01X2739811Y520048D02*
Y502548D01*
X2748545D01*
G01X2761678D02*
Y520048D01*
X2759058Y516548D01*
G01Y502548D02*
X2764298D01*
G01X2779178D02*
Y520048D01*
X2776558Y516548D01*
G01Y502548D02*
X2781798D01*
G01X2792748Y501965D02*
X2800608Y520048D01*
G01X2809811D02*
Y502548D01*
X2818545D01*
G01X2831678D02*
Y520048D01*
X2829058Y516548D01*
G01Y502548D02*
X2834298D01*
G01X2844375Y506048D02*
X2845684Y504006D01*
X2847431Y502840D01*
X2849396Y502548D01*
X2851143Y502840D01*
X2852890Y504298D01*
X2853981Y506048D01*
X2854200Y507798D01*
X2853763Y509839D01*
X2852235Y511298D01*
X2850706Y511881D01*
X2848741D01*
G01X2850706D02*
X2852016Y512756D01*
X2853108Y514214D01*
X2853545Y515964D01*
X2853108Y517715D01*
X2852016Y519173D01*
X2850051Y520048D01*
X2848086Y519756D01*
X2846121Y518589D01*
G01X2739811Y554698D02*
Y537198D01*
X2748545D01*
G01X2761678D02*
Y554698D01*
X2759058Y551198D01*
G01Y537198D02*
X2764298D01*
G01X2779178D02*
Y554698D01*
X2776558Y551198D01*
G01Y537198D02*
X2781798D01*
G01X2792748Y536615D02*
X2800608Y554698D01*
G01X2809811D02*
Y537198D01*
X2818545D01*
G01X2831678D02*
Y554698D01*
X2829058Y551198D01*
G01Y537198D02*
X2834298D01*
G01X2844375Y540698D02*
X2845684Y538656D01*
X2847431Y537490D01*
X2849396Y537198D01*
X2851143Y537490D01*
X2852890Y538948D01*
X2853981Y540698D01*
X2854200Y542448D01*
X2853763Y544489D01*
X2852235Y545948D01*
X2850706Y546531D01*
X2848741D01*
G01X2850706D02*
X2852016Y547406D01*
X2853108Y548864D01*
X2853545Y550614D01*
X2853108Y552365D01*
X2852016Y553823D01*
X2850051Y554698D01*
X2848086Y554406D01*
X2846121Y553239D01*
G01X2739811Y589348D02*
Y571848D01*
X2748545D01*
G01X2761678D02*
Y589348D01*
X2759058Y585848D01*
G01Y571848D02*
X2764298D01*
G01X2779178D02*
Y589348D01*
X2776558Y585848D01*
G01Y571848D02*
X2781798D01*
G01X2792748Y571265D02*
X2800608Y589348D01*
G01X2809811D02*
Y571848D01*
X2818545D01*
G01X2831678D02*
Y589348D01*
X2829058Y585848D01*
G01Y571848D02*
X2834298D01*
G01X2844375Y575348D02*
X2845684Y573306D01*
X2847431Y572140D01*
X2849396Y571848D01*
X2851143Y572140D01*
X2852890Y573598D01*
X2853981Y575348D01*
X2854200Y577098D01*
X2853763Y579139D01*
X2852235Y580598D01*
X2850706Y581181D01*
X2848741D01*
G01X2850706D02*
X2852016Y582056D01*
X2853108Y583514D01*
X2853545Y585264D01*
X2853108Y587015D01*
X2852016Y588473D01*
X2850051Y589348D01*
X2848086Y589056D01*
X2846121Y587889D01*
G01X2713561Y606498D02*
Y623998D01*
X2719020D01*
X2720766Y623123D01*
X2721858Y621956D01*
X2722295Y619623D01*
X2721858Y617289D01*
X2720548Y615831D01*
X2719020Y614956D01*
X2713561D01*
G01X2719020D02*
X2722295Y606498D01*
G01X2732153Y614373D02*
X2739140D01*
X2738485Y616415D01*
X2737393Y617581D01*
X2735865Y618164D01*
X2734336Y617873D01*
X2733026Y616998D01*
X2732153Y614956D01*
X2731716Y613206D01*
Y611456D01*
X2732153Y609706D01*
X2733245Y607956D01*
X2734555Y606790D01*
X2736083Y606498D01*
X2737611Y607081D01*
X2739140Y608831D01*
G01X2751618Y606498D02*
Y621373D01*
X2752055Y622831D01*
X2752928Y623706D01*
X2754238Y623998D01*
X2755548Y623415D01*
X2756203Y621956D01*
G01X2753583Y616998D02*
X2749216D01*
G01X2770428Y605915D02*
X2769991Y606206D01*
Y606790D01*
X2770428Y607081D01*
X2770865Y606790D01*
Y606206D01*
X2770428Y605915D01*
G01X2801061Y606498D02*
Y623998D01*
X2806301D01*
X2808048Y623123D01*
X2809358Y621081D01*
X2809795Y618748D01*
X2809358Y616415D01*
X2808266Y614665D01*
X2806301Y613789D01*
X2801061D01*
G01X2822928Y606498D02*
Y623998D01*
G01X2844358Y606498D02*
Y618164D01*
G01Y616123D02*
X2843485Y617289D01*
X2842174Y617873D01*
X2840646Y618164D01*
X2839118Y617581D01*
X2837808Y616415D01*
X2836934Y614665D01*
X2836498Y612331D01*
X2836934Y609998D01*
X2837808Y608248D01*
X2839118Y607081D01*
X2840646Y606498D01*
X2842174Y606790D01*
X2843485Y607664D01*
X2844358Y608831D01*
G01X2854216Y606498D02*
Y618164D01*
G01Y615248D02*
X2855090Y616706D01*
X2856400Y617873D01*
X2858146Y618164D01*
X2859674Y617873D01*
X2860985Y616706D01*
X2861640Y614665D01*
Y606498D01*
G01X2872153Y614373D02*
X2879140D01*
X2878485Y616415D01*
X2877393Y617581D01*
X2875865Y618164D01*
X2874336Y617873D01*
X2873026Y616998D01*
X2872153Y614956D01*
X2871716Y613206D01*
Y611456D01*
X2872153Y609706D01*
X2873245Y607956D01*
X2874555Y606790D01*
X2876083Y606498D01*
X2877611Y607081D01*
X2879140Y608831D01*
G01X2993228Y548864D02*
Y537198D01*
G01Y553531D02*
X2992791Y553823D01*
Y554406D01*
X2993228Y554698D01*
X2993665Y554406D01*
Y553823D01*
X2993228Y553531D01*
G01X3007016Y537198D02*
Y548864D01*
G01Y545948D02*
X3007890Y547406D01*
X3009200Y548573D01*
X3010946Y548864D01*
X3012474Y548573D01*
X3013785Y547406D01*
X3014440Y545365D01*
Y537198D01*
G01X3024953Y539239D02*
X3026045Y538073D01*
X3027573Y537198D01*
X3028883D01*
X3030193Y537781D01*
X3031066Y538656D01*
X3031503Y539822D01*
X3031285Y541573D01*
X3030411Y542448D01*
X3026481Y544198D01*
X3025608Y546240D01*
X3026045Y547698D01*
X3026918Y548573D01*
X3028228Y548864D01*
X3029538Y548573D01*
X3030848Y547698D01*
G01X3045728Y548864D02*
Y537198D01*
G01Y553531D02*
X3045291Y553823D01*
Y554406D01*
X3045728Y554698D01*
X3046165Y554406D01*
Y553823D01*
X3045728Y553531D01*
G01X3067158Y554698D02*
Y537198D01*
G01Y539822D02*
X3066285Y538364D01*
X3064974Y537490D01*
X3063446Y537198D01*
X3061700Y537781D01*
X3060390Y539239D01*
X3059516Y540989D01*
X3059298Y543031D01*
X3059516Y545073D01*
X3060390Y546823D01*
X3061700Y548281D01*
X3063446Y548864D01*
X3064974Y548573D01*
X3066066Y547989D01*
X3067158Y546823D01*
G01X3077453Y545073D02*
X3084440D01*
X3083785Y547115D01*
X3082693Y548281D01*
X3081165Y548864D01*
X3079636Y548573D01*
X3078326Y547698D01*
X3077453Y545656D01*
X3077016Y543906D01*
Y542156D01*
X3077453Y540406D01*
X3078545Y538656D01*
X3079855Y537490D01*
X3081383Y537198D01*
X3082911Y537781D01*
X3084440Y539531D01*
G01X3111798Y537198D02*
Y554698D01*
G01Y545948D02*
X3112890Y547698D01*
X3114200Y548573D01*
X3115510Y548864D01*
X3117474Y548281D01*
X3118785Y547115D01*
X3119658Y545073D01*
Y542740D01*
X3119221Y540406D01*
X3118348Y538656D01*
X3116820Y537490D01*
X3115510Y537198D01*
X3114200Y537490D01*
X3112890Y538364D01*
X3111798Y539822D01*
G01X3133228Y537198D02*
X3131918Y537490D01*
X3130608Y538656D01*
X3129734Y540698D01*
X3129298Y543031D01*
X3129734Y545365D01*
X3130608Y547406D01*
X3131918Y548573D01*
X3133228Y548864D01*
X3134538Y548573D01*
X3135848Y547406D01*
X3136721Y545365D01*
X3136940Y543031D01*
X3136721Y540698D01*
X3135848Y538656D01*
X3134538Y537490D01*
X3133228Y537198D01*
G01X3154658D02*
Y548864D01*
G01Y546823D02*
X3153785Y547989D01*
X3152474Y548573D01*
X3150946Y548864D01*
X3149418Y548281D01*
X3148108Y547115D01*
X3147234Y545365D01*
X3146798Y543031D01*
X3147234Y540698D01*
X3148108Y538948D01*
X3149418Y537781D01*
X3150946Y537198D01*
X3152474Y537490D01*
X3153785Y538364D01*
X3154658Y539531D01*
G01X3165171Y537198D02*
Y548864D01*
G01Y546531D02*
X3166263Y547698D01*
X3167355Y548573D01*
X3168883Y548864D01*
X3169974Y548573D01*
X3171285Y547698D01*
G01X3189658Y554698D02*
Y537198D01*
G01Y539822D02*
X3188785Y538364D01*
X3187474Y537490D01*
X3185946Y537198D01*
X3184200Y537781D01*
X3182890Y539239D01*
X3182016Y540989D01*
X3181798Y543031D01*
X3182016Y545073D01*
X3182890Y546823D01*
X3184200Y548281D01*
X3185946Y548864D01*
X3187474Y548573D01*
X3188566Y547989D01*
X3189658Y546823D01*
G01X3220728Y537198D02*
X3219418Y537490D01*
X3218108Y538656D01*
X3217234Y540698D01*
X3216798Y543031D01*
X3217234Y545365D01*
X3218108Y547406D01*
X3219418Y548573D01*
X3220728Y548864D01*
X3222038Y548573D01*
X3223348Y547406D01*
X3224221Y545365D01*
X3224440Y543031D01*
X3224221Y540698D01*
X3223348Y538656D01*
X3222038Y537490D01*
X3220728Y537198D01*
G01X3234516Y548864D02*
Y540698D01*
X3235390Y538656D01*
X3236700Y537490D01*
X3238228Y537198D01*
X3239756Y537490D01*
X3241066Y538656D01*
X3241940Y540698D01*
G01Y537198D02*
Y548864D01*
G01X3255728Y554698D02*
Y537198D01*
G01X3252671Y548864D02*
X3258785D01*
G01X3273228Y537198D02*
Y554698D01*
G01X3290728Y548864D02*
Y537198D01*
G01Y553531D02*
X3290291Y553823D01*
Y554406D01*
X3290728Y554698D01*
X3291165Y554406D01*
Y553823D01*
X3290728Y553531D01*
G01X3304516Y537198D02*
Y548864D01*
G01Y545948D02*
X3305390Y547406D01*
X3306700Y548573D01*
X3308446Y548864D01*
X3309974Y548573D01*
X3311285Y547406D01*
X3311940Y545365D01*
Y537198D01*
G01X3322453Y545073D02*
X3329440D01*
X3328785Y547115D01*
X3327693Y548281D01*
X3326165Y548864D01*
X3324636Y548573D01*
X3323326Y547698D01*
X3322453Y545656D01*
X3322016Y543906D01*
Y542156D01*
X3322453Y540406D01*
X3323545Y538656D01*
X3324855Y537490D01*
X3326383Y537198D01*
X3327911Y537781D01*
X3329440Y539531D01*
G01X3343228Y536615D02*
X3342791Y536906D01*
Y537490D01*
X3343228Y537781D01*
X3343665Y537490D01*
Y536906D01*
X3343228Y536615D01*
G01X2993228Y583514D02*
Y571848D01*
G01Y588181D02*
X2992791Y588473D01*
Y589056D01*
X2993228Y589348D01*
X2993665Y589056D01*
Y588473D01*
X2993228Y588181D01*
G01X3007453Y573889D02*
X3008545Y572723D01*
X3010073Y571848D01*
X3011383D01*
X3012693Y572431D01*
X3013566Y573306D01*
X3014003Y574472D01*
X3013785Y576223D01*
X3012911Y577098D01*
X3008981Y578848D01*
X3008108Y580890D01*
X3008545Y582348D01*
X3009418Y583223D01*
X3010728Y583514D01*
X3012038Y583223D01*
X3013348Y582348D01*
G01X3040706Y571848D02*
Y589348D01*
X3050750Y571848D01*
Y589348D01*
G01X3063228Y571848D02*
X3061481Y572140D01*
X3059953Y573306D01*
X3058643Y575056D01*
X3057769Y577098D01*
X3057333Y579431D01*
Y581765D01*
X3057769Y584098D01*
X3058643Y586140D01*
X3059953Y587889D01*
X3061481Y589056D01*
X3063228Y589348D01*
X3064974Y589056D01*
X3066503Y587889D01*
X3067813Y586140D01*
X3068687Y584098D01*
X3069123Y581765D01*
Y579431D01*
X3068687Y577098D01*
X3067813Y575056D01*
X3066503Y573306D01*
X3064974Y572140D01*
X3063228Y571848D01*
G01X3080728Y589348D02*
Y571848D01*
G01X3075706Y589348D02*
X3085750D01*
G01X3112016Y583514D02*
Y575348D01*
X3112890Y573306D01*
X3114200Y572140D01*
X3115728Y571848D01*
X3117256Y572140D01*
X3118566Y573306D01*
X3119440Y575348D01*
G01Y571848D02*
Y583514D01*
G01X3129953Y573889D02*
X3131045Y572723D01*
X3132573Y571848D01*
X3133883D01*
X3135193Y572431D01*
X3136066Y573306D01*
X3136503Y574472D01*
X3136285Y576223D01*
X3135411Y577098D01*
X3131481Y578848D01*
X3130608Y580890D01*
X3131045Y582348D01*
X3131918Y583223D01*
X3133228Y583514D01*
X3134538Y583223D01*
X3135848Y582348D01*
G01X3147453Y579723D02*
X3154440D01*
X3153785Y581765D01*
X3152693Y582931D01*
X3151165Y583514D01*
X3149636Y583223D01*
X3148326Y582348D01*
X3147453Y580306D01*
X3147016Y578556D01*
Y576806D01*
X3147453Y575056D01*
X3148545Y573306D01*
X3149855Y572140D01*
X3151383Y571848D01*
X3152911Y572431D01*
X3154440Y574181D01*
G01X3172158Y589348D02*
Y571848D01*
G01Y574472D02*
X3171285Y573014D01*
X3169974Y572140D01*
X3168446Y571848D01*
X3166700Y572431D01*
X3165390Y573889D01*
X3164516Y575639D01*
X3164298Y577681D01*
X3164516Y579723D01*
X3165390Y581473D01*
X3166700Y582931D01*
X3168446Y583514D01*
X3169974Y583223D01*
X3171066Y582639D01*
X3172158Y581473D01*
G01X3203228Y583514D02*
Y571848D01*
G01Y588181D02*
X3202791Y588473D01*
Y589056D01*
X3203228Y589348D01*
X3203665Y589056D01*
Y588473D01*
X3203228Y588181D01*
G01X3217016Y571848D02*
Y583514D01*
G01Y580598D02*
X3217890Y582056D01*
X3219200Y583223D01*
X3220946Y583514D01*
X3222474Y583223D01*
X3223785Y582056D01*
X3224440Y580015D01*
Y571848D01*
G01X3255728Y589348D02*
Y571848D01*
G01X3252671Y583514D02*
X3258785D01*
G01X3269516Y571848D02*
Y589348D01*
G01Y580890D02*
X3270608Y582348D01*
X3271700Y583223D01*
X3273446Y583514D01*
X3274756Y583223D01*
X3276285Y582056D01*
X3276940Y580306D01*
Y571848D01*
G01X3290728Y583514D02*
Y571848D01*
G01Y588181D02*
X3290291Y588473D01*
Y589056D01*
X3290728Y589348D01*
X3291165Y589056D01*
Y588473D01*
X3290728Y588181D01*
G01X3304953Y573889D02*
X3306045Y572723D01*
X3307573Y571848D01*
X3308883D01*
X3310193Y572431D01*
X3311066Y573306D01*
X3311503Y574472D01*
X3311285Y576223D01*
X3310411Y577098D01*
X3306481Y578848D01*
X3305608Y580890D01*
X3306045Y582348D01*
X3306918Y583223D01*
X3308228Y583514D01*
X3309538Y583223D01*
X3310848Y582348D01*
G01X3343228Y571848D02*
Y589348D01*
G01X3364658Y571848D02*
Y583514D01*
G01Y581473D02*
X3363785Y582639D01*
X3362474Y583223D01*
X3360946Y583514D01*
X3359418Y582931D01*
X3358108Y581765D01*
X3357234Y580015D01*
X3356798Y577681D01*
X3357234Y575348D01*
X3358108Y573598D01*
X3359418Y572431D01*
X3360946Y571848D01*
X3362474Y572140D01*
X3363785Y573014D01*
X3364658Y574181D01*
G01X3373643Y566598D02*
X3374953Y566015D01*
X3376700Y566598D01*
X3377791Y567764D01*
X3378665Y569223D01*
X3379974Y573889D01*
X3382813Y583514D01*
G01X3375826D02*
X3379974Y573889D01*
G01X3392453Y579723D02*
X3399440D01*
X3398785Y581765D01*
X3397693Y582931D01*
X3396165Y583514D01*
X3394636Y583223D01*
X3393326Y582348D01*
X3392453Y580306D01*
X3392016Y578556D01*
Y576806D01*
X3392453Y575056D01*
X3393545Y573306D01*
X3394855Y572140D01*
X3396383Y571848D01*
X3397911Y572431D01*
X3399440Y574181D01*
G01X3410171Y571848D02*
Y583514D01*
G01Y581181D02*
X3411263Y582348D01*
X3412355Y583223D01*
X3413883Y583514D01*
X3414974Y583223D01*
X3416285Y582348D01*
G01X2918425Y605915D02*
X2928031Y618748D01*
G01X2923228Y621081D02*
Y603581D01*
G01X2928031Y605915D02*
X2918425Y618748D01*
G01X2916678Y612331D02*
X2929778D01*
G01X2955390D02*
X2961066D01*
G01X2988425Y606498D02*
Y623998D01*
X2992791D01*
X2994538Y623123D01*
X2995848Y621956D01*
X2996940Y620207D01*
X2997813Y618164D01*
X2998031Y615248D01*
X2997813Y612331D01*
X2996940Y610289D01*
X2995848Y608539D01*
X2994538Y607373D01*
X2992791Y606498D01*
X2988425D01*
G01X3007453Y614373D02*
X3014440D01*
X3013785Y616415D01*
X3012693Y617581D01*
X3011165Y618164D01*
X3009636Y617873D01*
X3008326Y616998D01*
X3007453Y614956D01*
X3007016Y613206D01*
Y611456D01*
X3007453Y609706D01*
X3008545Y607956D01*
X3009855Y606790D01*
X3011383Y606498D01*
X3012911Y607081D01*
X3014440Y608831D01*
G01X3024516Y606498D02*
Y618164D01*
G01Y615248D02*
X3025390Y616706D01*
X3026700Y617873D01*
X3028446Y618164D01*
X3029974Y617873D01*
X3031285Y616706D01*
X3031940Y614665D01*
Y606498D01*
G01X3045728D02*
X3044418Y606790D01*
X3043108Y607956D01*
X3042234Y609998D01*
X3041798Y612331D01*
X3042234Y614665D01*
X3043108Y616706D01*
X3044418Y617873D01*
X3045728Y618164D01*
X3047038Y617873D01*
X3048348Y616706D01*
X3049221Y614665D01*
X3049440Y612331D01*
X3049221Y609998D01*
X3048348Y607956D01*
X3047038Y606790D01*
X3045728Y606498D01*
G01X3063228Y623998D02*
Y606498D01*
G01X3060171Y618164D02*
X3066285D01*
G01X3077453Y614373D02*
X3084440D01*
X3083785Y616415D01*
X3082693Y617581D01*
X3081165Y618164D01*
X3079636Y617873D01*
X3078326Y616998D01*
X3077453Y614956D01*
X3077016Y613206D01*
Y611456D01*
X3077453Y609706D01*
X3078545Y607956D01*
X3079855Y606790D01*
X3081383Y606498D01*
X3082911Y607081D01*
X3084440Y608831D01*
G01X3094953Y608539D02*
X3096045Y607373D01*
X3097573Y606498D01*
X3098883D01*
X3100193Y607081D01*
X3101066Y607956D01*
X3101503Y609122D01*
X3101285Y610873D01*
X3100411Y611748D01*
X3096481Y613498D01*
X3095608Y615540D01*
X3096045Y616998D01*
X3096918Y617873D01*
X3098228Y618164D01*
X3099538Y617873D01*
X3100848Y616998D01*
G01X3133228Y623998D02*
Y606498D01*
G01X3130171Y618164D02*
X3136285D01*
G01X3147016Y606498D02*
Y623998D01*
G01Y615540D02*
X3148108Y616998D01*
X3149200Y617873D01*
X3150946Y618164D01*
X3152256Y617873D01*
X3153785Y616706D01*
X3154440Y614956D01*
Y606498D01*
G01X3172158D02*
Y618164D01*
G01Y616123D02*
X3171285Y617289D01*
X3169974Y617873D01*
X3168446Y618164D01*
X3166918Y617581D01*
X3165608Y616415D01*
X3164734Y614665D01*
X3164298Y612331D01*
X3164734Y609998D01*
X3165608Y608248D01*
X3166918Y607081D01*
X3168446Y606498D01*
X3169974Y606790D01*
X3171285Y607664D01*
X3172158Y608831D01*
G01X3185728Y623998D02*
Y606498D01*
G01X3182671Y618164D02*
X3188785D01*
G01X3214178Y623998D02*
X3217234Y606498D01*
X3220728Y623998D01*
X3224221Y606498D01*
X3227278Y623998D01*
G01X3235608D02*
X3240848D01*
G01X3238228D02*
Y606498D01*
G01X3235608D02*
X3240848D01*
G01X3250925D02*
Y623998D01*
X3255291D01*
X3257038Y623123D01*
X3258348Y621956D01*
X3259440Y620207D01*
X3260313Y618164D01*
X3260531Y615248D01*
X3260313Y612331D01*
X3259440Y610289D01*
X3258348Y608539D01*
X3257038Y607373D01*
X3255291Y606498D01*
X3250925D01*
G01X3273228Y623998D02*
Y606498D01*
G01X3268206Y623998D02*
X3278250D01*
G01X3286143Y606498D02*
Y623998D01*
G01X3295313D02*
Y606498D01*
G01Y615248D02*
X3286143D01*
G01X-7874Y-31496D02*
X-19685D01*
G01X-7874D02*
X-19685D01*
G01D02*
G03X-23622Y-35433I0J-3937D01*
G01D02*
Y-59055D01*
G01Y-35433D02*
Y-59055D01*
G01X-19685Y-31496D02*
G03X-23622Y-35433I0J-3937D01*
G01Y-59055D02*
G03X-19685Y-62992I3937J0D01*
G01D02*
X1972441D01*
G01X-19685D02*
X1972441D01*
G01X-23622Y-59055D02*
G03X-19685Y-62992I3937J0D01*
G01Y-23622D02*
X1972441D01*
G01X-19685D02*
X1972441D01*
G01X-19685D02*
X1972441D01*
G01X-19685D02*
X1972441D01*
G01X-23622Y622441D02*
Y-19685D01*
G01Y622441D02*
Y-19685D01*
G01Y622441D02*
Y-19685D01*
G01Y622441D02*
Y-19685D01*
G01D02*
G03X-19685Y-23622I3937J0D01*
G01X-23622Y-19685D02*
G03X-19685Y-23622I3937J0D01*
G01X-23622Y-19685D02*
G03X-19685Y-23622I3937J0D01*
G01X-23622Y-19685D02*
G03X-19685Y-23622I3937J0D01*
G01X1972441Y626378D02*
X-19685D01*
G01X1972441D02*
X-19685D01*
G01X1972441D02*
X-19685D01*
G01X1972441D02*
X-19685D01*
G01D02*
G03X-23622Y622441I0J-3937D01*
G01X-19685Y626378D02*
G03X-23622Y622441I0J-3937D01*
G01X-19685Y626378D02*
G03X-23622Y622441I0J-3937D01*
G01X-19685Y626378D02*
G03X-23622Y622441I0J-3937D01*
G01X-19685Y634252D02*
X-7874D01*
G01X-19685D02*
X-7874D01*
G01X-23622Y661811D02*
Y638189D01*
G01Y661811D02*
Y638189D01*
G01D02*
G03X-19685Y634252I3937J0D01*
G01X-23622Y638189D02*
G03X-19685Y634252I3937J0D01*
G01X1972441Y665748D02*
X-19685D01*
G01X1972441D02*
X-19685D01*
G01D02*
G03X-23622Y661811I0J-3937D01*
G01X-19685Y665748D02*
G03X-23622Y661811I0J-3937D01*
G01X-7874Y-31496D02*
G03Y-23622I0J3937D01*
G01Y-31496D02*
G03Y-23622I0J3937D01*
G01X22835D02*
G03Y-31496I0J-3937D01*
G01X137795D02*
X22835D01*
G01X137795D02*
X22835D01*
G01Y-23622D02*
G03Y-31496I0J-3937D01*
G01X0Y616535D02*
G03Y604724I0J-5905D01*
G01Y616535D02*
G03Y604724I0J-5905D01*
G01Y616535D02*
X2646D01*
G01X2644D02*
X0D01*
G01Y604724D02*
X2644D01*
G01X2646D02*
X0D01*
G01X2646D02*
X0D01*
G01D02*
X2644D01*
G01Y616535D02*
X0D01*
G01D02*
X2646D01*
G01X0D02*
G03Y604724I0J-5905D01*
G01Y616535D02*
G03Y604724I0J-5905D01*
G01X2646Y616535D02*
G03X7595Y618285I0J7874D01*
G01X2644Y616535D02*
G03X7593Y618285I0J7874D01*
G01X2644Y616535D02*
G03X7593Y618285I0J7874D01*
G01X7595Y602975D02*
G03X2646Y604724I-4948J-6125D01*
G01X7593Y602975D02*
G03X2644Y604724I-4948J-6125D01*
G01X7593Y602975D02*
G03X2644Y604724I-4948J-6125D01*
G01X7593Y602975D02*
G03X2644Y604724I-4948J-6125D01*
G01X7593Y602975D02*
G03X2644Y604724I-4948J-6125D01*
G01X7595Y602975D02*
G03X2646Y604724I-4948J-6125D01*
G01X2644Y616535D02*
G03X7593Y618285I0J7874D01*
G01X2644Y616535D02*
G03X7593Y618285I0J7874D01*
G01X2646Y616535D02*
G03X7595Y618285I0J7874D01*
G01Y602975D02*
G03Y618285I6186J7655D01*
G01X7593Y602975D02*
G03Y618285I6187J7655D01*
G01Y602975D02*
G03Y618285I6187J7655D01*
G01Y602975D02*
G03Y618285I6187J7655D01*
G01Y602975D02*
G03Y618285I6187J7655D01*
G01X7595Y602975D02*
G03Y618285I6186J7655D01*
G01X-7874Y626378D02*
G03Y634252I0J3937D01*
G01Y626378D02*
G03Y634252I0J3937D01*
G01X22835D02*
G03Y626378I0J-3937D01*
G01Y634252D02*
X137795D01*
G01X22835D02*
X137795D01*
G01X22835D02*
G03Y626378I0J-3937D01*
G01X168504Y-23622D02*
G03Y-31496I0J-3937D01*
G01X137795D02*
G03Y-23622I0J3937D01*
G01X341732Y-31496D02*
X168504D01*
G01X341732D02*
X168504D01*
G01X137795D02*
G03Y-23622I0J3937D01*
G01X168504D02*
G03Y-31496I0J-3937D01*
G01Y634252D02*
G03Y626378I0J-3937D01*
G01X137795D02*
G03Y634252I0J3937D01*
G01X168504D02*
X341732D01*
G01X168504D02*
X341732D01*
G01X137795Y626378D02*
G03Y634252I0J3937D01*
G01X168504D02*
G03Y626378I0J-3937D01*
G01X341732Y-31496D02*
G03Y-23622I0J3937D01*
G01Y-31496D02*
G03Y-23622I0J3937D01*
G01Y626378D02*
G03Y634252I0J3937D01*
G01Y626378D02*
G03Y634252I0J3937D01*
G01X372441Y-23622D02*
G03Y-31496I0J-3937D01*
G01X529921D02*
X372441D01*
G01X529921D02*
X372441D01*
G01Y-23622D02*
G03Y-31496I0J-3937D01*
G01Y634252D02*
G03Y626378I0J-3937D01*
G01Y634252D02*
X529921D01*
G01X372441D02*
X529921D01*
G01X372441D02*
G03Y626378I0J-3937D01*
G01X529921Y-31496D02*
G03Y-23622I0J3937D01*
G01Y-31496D02*
G03Y-23622I0J3937D01*
G01Y626378D02*
G03Y634252I0J3937D01*
G01Y626378D02*
G03Y634252I0J3937D01*
G01X560630Y-23622D02*
G03Y-31496I0J-3937D01*
G01X788976D02*
X560630D01*
G01X788976D02*
X560630D01*
G01Y-23622D02*
G03Y-31496I0J-3937D01*
G01Y634252D02*
G03Y626378I0J-3937D01*
G01Y634252D02*
X788976D01*
G01X560630D02*
X788976D01*
G01X560630D02*
G03Y626378I0J-3937D01*
G01X684760Y-15529D02*
G03Y-219I6187J7655D01*
G01X684759Y-15529D02*
G03X679809Y-13780I-4948J-6125D01*
G01X679811Y-1969D02*
G03X684760Y-219I0J7874D01*
G01X677165Y-1969D02*
X679811D01*
G01X677165D02*
G03Y-13780I0J-5906D01*
G01D02*
X679809D01*
G01X684760Y602975D02*
G03Y618285I6187J7655D01*
G01X684759Y602975D02*
G03Y618285I6186J7655D01*
G01Y602975D02*
G03Y618285I6186J7655D01*
G01Y602975D02*
G03Y618285I6186J7655D01*
G01Y602975D02*
G03Y618285I6186J7655D01*
G01X684760Y602975D02*
G03Y618285I6187J7655D01*
G01X679811Y616535D02*
G03X684760Y618285I0J7874D01*
G01X679809Y616535D02*
G03X684759Y618285I0J7874D01*
G01X679809Y616535D02*
G03X684759Y618285I0J7874D01*
G01X684760Y602975D02*
G03X679811Y604724I-4948J-6125D01*
G01X684759Y602975D02*
G03X679809Y604724I-4948J-6125D01*
G01X684759Y602975D02*
G03X679809Y604724I-4948J-6125D01*
G01X684759Y602975D02*
G03X679809Y604724I-4948J-6125D01*
G01X684759Y602975D02*
G03X679809Y604724I-4948J-6125D01*
G01X684760Y602975D02*
G03X679811Y604724I-4948J-6125D01*
G01X679809Y616535D02*
G03X684759Y618285I0J7874D01*
G01X679809Y616535D02*
G03X684759Y618285I0J7874D01*
G01X679811Y616535D02*
G03X684760Y618285I0J7874D01*
G01X677165Y616535D02*
X679811D01*
G01X677165D02*
G03Y604724I0J-5905D01*
G01D02*
X679809D01*
G01X788976Y-31496D02*
G03Y-23622I0J3937D01*
G01Y-31496D02*
G03Y-23622I0J3937D01*
G01X819685D02*
G03Y-31496I0J-3937D01*
G01X975591D02*
X819685D01*
G01X975591D02*
X819685D01*
G01Y-23622D02*
G03Y-31496I0J-3937D01*
G01X788976Y626378D02*
G03Y634252I0J3937D01*
G01Y626378D02*
G03Y634252I0J3937D01*
G01X819685D02*
G03Y626378I0J-3937D01*
G01Y634252D02*
X975591D01*
G01X819685D02*
X975591D01*
G01X819685D02*
G03Y626378I0J-3937D01*
G01X975591Y-31496D02*
G03Y-23622I0J3937D01*
G01Y-31496D02*
G03Y-23622I0J3937D01*
G01X1006299D02*
G03Y-31496I0J-3937D01*
G01X1162205D02*
X1006299D01*
G01X1162205D02*
X1006299D01*
G01Y-23622D02*
G03Y-31496I0J-3937D01*
G01Y634252D02*
X1162205D01*
G01X1006299D02*
X1162205D01*
G01X975591Y626378D02*
G03Y634252I0J3937D01*
G01Y626378D02*
G03Y634252I0J3937D01*
G01X1006299D02*
G03Y626378I0J-3937D01*
G01Y634252D02*
G03Y626378I0J-3937D01*
G01X1162205Y-31496D02*
G03Y-23622I0J3937D01*
G01Y-31496D02*
G03Y-23622I0J3937D01*
G01X1192913D02*
G03Y-31496I0J-3937D01*
G01X1398425D02*
X1192913D01*
G01X1398425D02*
X1192913D01*
G01Y-23622D02*
G03Y-31496I0J-3937D01*
G01Y634252D02*
X1394488D01*
G01X1192913D02*
X1394488D01*
G01X1162205Y626378D02*
G03Y634252I0J3937D01*
G01Y626378D02*
G03Y634252I0J3937D01*
G01X1192913D02*
G03Y626378I0J-3937D01*
G01Y634252D02*
G03Y626378I0J-3937D01*
G01X1398425Y-31496D02*
G03Y-23622I0J3937D01*
G01Y-31496D02*
G03Y-23622I0J3937D01*
G01X1405512Y-1968D02*
G03Y-13779I0J-5906D01*
G01Y-1968D02*
G03Y-13779I0J-5906D01*
G01Y-1968D02*
G03Y-13779I0J-5906D01*
G01Y-1968D02*
G03Y-13779I0J-5906D01*
G01X1394488Y626378D02*
G03Y634252I0J3937D01*
G01Y626378D02*
G03Y634252I0J3937D01*
G01X1405512Y616535D02*
G03Y604724I0J-5905D01*
G01Y616535D02*
G03Y604724I0J-5905D01*
G01Y616535D02*
G03Y604724I0J-5905D01*
G01Y616535D02*
G03Y604724I0J-5905D01*
G01X1429134Y-23622D02*
G03Y-31496I0J-3937D01*
G01X1851181D02*
X1429134D01*
G01X1851181D02*
X1429134D01*
G01Y-23622D02*
G03Y-31496I0J-3937D01*
G01X1413107Y-15529D02*
G03Y-218I6186J7655D01*
G01X1413105Y-15529D02*
G03Y-218I6186J7655D01*
G01Y-15529D02*
G03Y-218I6186J7655D01*
G01Y-15529D02*
G03Y-218I6186J7655D01*
G01Y-15529D02*
G03Y-218I6186J7655D01*
G01X1413107Y-15529D02*
G03Y-218I6186J7655D01*
G01X1408157Y-1968D02*
G03X1413107Y-218I1J7874D01*
G01X1408156Y-1968D02*
G03X1413105Y-218I0J7874D01*
G01X1408156Y-1968D02*
G03X1413105Y-218I0J7874D01*
G01X1408156Y-1968D02*
G03X1413105Y-218I0J7874D01*
G01X1408156Y-1968D02*
G03X1413105Y-218I0J7874D01*
G01X1408157Y-1968D02*
G03X1413107Y-218I1J7874D01*
G01Y-15529D02*
G03X1408157Y-13779I-4949J-6124D01*
G01X1413105Y-15529D02*
G03X1408156Y-13779I-4949J-6124D01*
G01X1413105Y-15529D02*
G03X1408156Y-13779I-4949J-6124D01*
G01X1413105Y-15529D02*
G03X1408156Y-13779I-4949J-6124D01*
G01X1413105Y-15529D02*
G03X1408156Y-13779I-4949J-6124D01*
G01X1413107Y-15529D02*
G03X1408157Y-13779I-4949J-6124D01*
G01X1405512D02*
X1408156D01*
G01X1408157D02*
X1405512D01*
G01X1408157D02*
X1405512D01*
G01D02*
X1408156D01*
G01X1405512Y-1968D02*
X1408157D01*
G01X1408156D02*
X1405512D01*
G01X1408156D02*
X1405512D01*
G01D02*
X1408157D01*
G01X1425197Y634252D02*
X1851181D01*
G01X1425197D02*
X1851181D01*
G01X1425197D02*
G03Y626378I0J-3937D01*
G01Y634252D02*
G03Y626378I0J-3937D01*
G01X1408157Y616535D02*
G03X1413107Y618285I1J7874D01*
G01X1408156Y616535D02*
G03X1413105Y618285I0J7874D01*
G01X1408156Y616535D02*
G03X1413105Y618285I0J7874D01*
G01X1413107Y602975D02*
G03Y618285I6186J7655D01*
G01X1413105Y602975D02*
G03Y618285I6187J7655D01*
G01Y602975D02*
G03Y618285I6187J7655D01*
G01X1413107Y602975D02*
G03X1408157Y604724I-4948J-6125D01*
G01X1413105Y602975D02*
G03X1408156Y604724I-4948J-6125D01*
G01X1413105Y602975D02*
G03X1408156Y604724I-4948J-6125D01*
G01X1413105Y602975D02*
G03X1408156Y604724I-4948J-6125D01*
G01X1413105Y602975D02*
G03X1408156Y604724I-4948J-6125D01*
G01X1413107Y602975D02*
G03X1408157Y604724I-4948J-6125D01*
G01X1413105Y602975D02*
G03Y618285I6187J7655D01*
G01Y602975D02*
G03Y618285I6187J7655D01*
G01X1413107Y602975D02*
G03Y618285I6186J7655D01*
G01X1408156Y616535D02*
G03X1413105Y618285I0J7874D01*
G01X1408156Y616535D02*
G03X1413105Y618285I0J7874D01*
G01X1408157Y616535D02*
G03X1413107Y618285I1J7874D01*
G01X1405512Y616535D02*
X1408157D01*
G01X1408156D02*
X1405512D01*
G01Y604724D02*
X1408156D01*
G01X1408157D02*
X1405512D01*
G01X1408157D02*
X1405512D01*
G01D02*
X1408156D01*
G01Y616535D02*
X1405512D01*
G01D02*
X1408157D01*
G01X1685866Y267244D02*
X1883780D01*
G01X1685866D02*
X1883780D01*
G01X1685866D02*
X1883780D01*
G01X1685866D02*
X1883780D01*
G01X1681929Y271181D02*
G03X1685866Y267244I3937J0D01*
G01X1681929Y271181D02*
G03X1685866Y267244I3937J0D01*
G01X1681929Y271181D02*
G03X1685866Y267244I3937J0D01*
G01X1681929Y271181D02*
G03X1685866Y267244I3937J0D01*
G01X1681929Y428661D02*
Y271181D01*
G01Y428661D02*
Y271181D01*
G01Y428661D02*
Y271181D01*
G01Y428661D02*
Y271181D01*
G01X1685866Y432598D02*
G03X1681929Y428661I0J-3937D01*
G01X1685866Y432598D02*
G03X1681929Y428661I0J-3937D01*
G01X1972441Y432598D02*
X1685866D01*
G01X1972441D02*
X1685866D01*
G01X1972441D02*
X1685866D01*
G01X1972441D02*
X1685866D01*
G01D02*
G03X1681929Y428661I0J-3937D01*
G01X1685866Y432598D02*
G03X1681929Y428661I0J-3937D01*
G01X1851181Y-31496D02*
G03Y-23622I0J3937D01*
G01Y-31496D02*
G03Y-23622I0J3937D01*
G01X1881890D02*
G03Y-31496I0J-3937D01*
G01X1972441D02*
X1881890D01*
G01X1972441D02*
X1881890D01*
G01Y-23622D02*
G03Y-31496I0J-3937D01*
G01X1861926Y-15529D02*
G03X1856976Y-13780I-4948J-6125D01*
G01X1861924Y-15529D02*
G03X1856975Y-13780I-4948J-6125D01*
G01X1861924Y-15529D02*
G03X1856975Y-13780I-4948J-6125D01*
G01X1861924Y-15529D02*
G03X1856975Y-13780I-4948J-6125D01*
G01X1861924Y-15529D02*
G03X1856975Y-13780I-4948J-6125D01*
G01X1861926Y-15529D02*
G03X1856976Y-13780I-4948J-6125D01*
G01Y-1969D02*
G03X1861926Y-219I0J7874D01*
G01X1856975Y-1969D02*
G03X1861924Y-219I0J7874D01*
G01X1856975Y-1969D02*
G03X1861924Y-219I0J7874D01*
G01X1861926Y-15529D02*
G03Y-219I6186J7655D01*
G01X1861924Y-15529D02*
G03Y-219I6186J7655D01*
G01Y-15529D02*
G03Y-219I6186J7655D01*
G01Y-15529D02*
G03Y-219I6186J7655D01*
G01Y-15529D02*
G03Y-219I6186J7655D01*
G01X1861926Y-15529D02*
G03Y-219I6186J7655D01*
G01X1856975Y-1969D02*
G03X1861924Y-219I0J7874D01*
G01X1856975Y-1969D02*
G03X1861924Y-219I0J7874D01*
G01X1856976Y-1969D02*
G03X1861926Y-219I0J7874D01*
G01X1854331Y-1969D02*
G03Y-13780I0J-5906D01*
G01Y-1969D02*
G03Y-13780I0J-5906D01*
G01D02*
X1856975D01*
G01X1856976D02*
X1854331D01*
G01X1856976D02*
X1854331D01*
G01D02*
X1856975D01*
G01X1854331Y-1969D02*
G03Y-13780I0J-5906D01*
G01Y-1969D02*
G03Y-13780I0J-5906D01*
G01Y-1969D02*
X1856976D01*
G01X1856975D02*
X1854331D01*
G01X1856975D02*
X1854331D01*
G01D02*
X1856976D01*
G01X1891654Y246772D02*
X1972441D01*
G01X1891654D02*
X1972441D01*
G01X1891654D02*
X1972441D01*
G01X1891654D02*
X1972441D01*
G01X1887717Y250709D02*
G03X1891654Y246772I3937J0D01*
G01X1887717Y250709D02*
G03X1891654Y246772I3937J0D01*
G01X1887717Y263307D02*
Y250709D01*
G01Y263307D02*
Y250709D01*
G01Y263307D02*
Y250709D01*
G01Y263307D02*
Y250709D01*
G01D02*
G03X1891654Y246772I3937J0D01*
G01X1887717Y250709D02*
G03X1891654Y246772I3937J0D01*
G01X1887717Y263307D02*
G03X1883780Y267244I-3937J0D01*
G01X1887717Y263307D02*
G03X1883780Y267244I-3937J0D01*
G01X1887717Y263307D02*
G03X1883780Y267244I-3937J0D01*
G01X1887717Y263307D02*
G03X1883780Y267244I-3937J0D01*
G01X1881890Y634252D02*
G03Y626378I0J-3937D01*
G01Y634252D02*
X1972441D01*
G01X1881890D02*
X1972441D01*
G01X1881890D02*
G03Y626378I0J-3937D01*
G01X1851181D02*
G03Y634252I0J3937D01*
G01Y626378D02*
G03Y634252I0J3937D01*
G01X1856976Y616535D02*
G03X1861926Y618285I0J7874D01*
G01X1856975Y616535D02*
G03X1861924Y618285I0J7874D01*
G01X1856975Y616535D02*
G03X1861924Y618285I0J7874D01*
G01X1861926Y602975D02*
G03Y618285I6186J7655D01*
G01X1861924Y602975D02*
G03Y618285I6186J7655D01*
G01Y602975D02*
G03Y618285I6186J7655D01*
G01Y602975D02*
G03Y618285I6186J7655D01*
G01Y602975D02*
G03Y618285I6186J7655D01*
G01X1861926Y602975D02*
G03Y618285I6186J7655D01*
G01X1856975Y616535D02*
G03X1861924Y618285I0J7874D01*
G01X1856975Y616535D02*
G03X1861924Y618285I0J7874D01*
G01X1856976Y616535D02*
G03X1861926Y618285I0J7874D01*
G01Y602975D02*
G03X1856976Y604724I-4948J-6125D01*
G01X1861924Y602975D02*
G03X1856975Y604724I-4948J-6125D01*
G01X1861924Y602975D02*
G03X1856975Y604724I-4948J-6125D01*
G01X1861924Y602975D02*
G03X1856975Y604724I-4948J-6125D01*
G01X1861924Y602975D02*
G03X1856975Y604724I-4948J-6125D01*
G01X1861926Y602975D02*
G03X1856976Y604724I-4948J-6125D01*
G01X1854331Y616535D02*
G03Y604724I0J-5905D01*
G01Y616535D02*
G03Y604724I0J-5905D01*
G01D02*
X1856975D01*
G01X1856976D02*
X1854331D01*
G01X1856976D02*
X1854331D01*
G01D02*
X1856975D01*
G01X1854331Y616535D02*
G03Y604724I0J-5905D01*
G01Y616535D02*
G03Y604724I0J-5905D01*
G01Y616535D02*
X1856976D01*
G01X1856975D02*
X1854331D01*
G01X1856975D02*
X1854331D01*
G01D02*
X1856976D01*
G01X1972441Y-11811D02*
X1906890D01*
G01X1904921Y-9843D02*
G03X1906890Y-11811I1969J1D01*
G01X1904921Y53150D02*
Y-9843D01*
G01X1972441Y-11811D02*
X1906890D01*
G01X1904921Y-9843D02*
G03X1906890Y-11811I1969J1D01*
G01X1904921Y53150D02*
Y-9843D01*
G01X1923071Y53150D02*
Y-9843D01*
G01X1940787Y-3937D02*
X1972441D01*
G01X1940787D02*
G03X1938819Y-5906I0J-1968D01*
G01Y-9843D02*
Y-5906D01*
G01Y-9843D02*
G03X1940787Y-11811I1968J0D01*
G01X1921102D02*
G03X1923071Y-9843I0J1969D01*
G01X1906890Y55118D02*
G03X1904921Y53150I0J-1969D01*
G01X1972441Y55118D02*
X1906890D01*
G01X1972441D02*
X1906890D01*
G01X1972441D02*
X1906890D01*
G01X1972441D02*
X1906890D01*
G01D02*
G03X1904921Y53150I0J-1969D01*
G01X1923071D02*
G03X1921102Y55118I-1969J-1D01*
G01X1940787D02*
G03X1938819Y53150I0J-1968D01*
G01Y49213D02*
Y53150D01*
G01Y49213D02*
G03X1940787Y47244I1968J-1D01*
G01X1972441D02*
X1940787D01*
G01X1976378Y-35433D02*
G03X1972441Y-31496I-3937J0D01*
G01X1976378Y-59055D02*
Y-35433D01*
G01Y-59055D02*
Y-35433D01*
G01D02*
G03X1972441Y-31496I-3937J0D01*
G01Y-62992D02*
G03X1976378Y-59055I0J3937D01*
G01X1972441Y-62992D02*
G03X1976378Y-59055I0J3937D01*
G01X1972441Y-23622D02*
G03X1976378Y-19685I0J3937D01*
G01X1972441Y-23622D02*
G03X1976378Y-19685I0J3937D01*
G01X1972441Y-23622D02*
G03X1976378Y-19685I0J3937D01*
G01X1972441Y-23622D02*
G03X1976378Y-19685I0J3937D01*
G01D02*
Y-15748D01*
G01Y-19685D02*
Y-15748D01*
G01Y-19685D02*
Y-15748D01*
G01Y-19685D02*
Y-15748D01*
G01D02*
G03X1972441Y-11811I-3937J0D01*
G01X1976378Y-15748D02*
G03X1972441Y-11811I-3937J0D01*
G01X1976378Y-15748D02*
G03X1972441Y-11811I-3937J0D01*
G01X1976378Y-15748D02*
G03X1972441Y-11811I-3937J0D01*
G01X1976378Y0D02*
Y43307D01*
G01X1972441Y-3937D02*
G03X1976378Y0I0J3937D01*
G01X1972441Y55118D02*
G03X1976378Y59055I0J3937D01*
G01X1972441Y55118D02*
G03X1976378Y59055I0J3937D01*
G01X1972441Y55118D02*
G03X1976378Y59055I0J3937D01*
G01X1972441Y55118D02*
G03X1976378Y59055I0J3937D01*
G01D02*
Y242835D01*
G01Y59055D02*
Y242835D01*
G01Y59055D02*
Y242835D01*
G01Y59055D02*
Y242835D01*
G01Y43307D02*
G03X1972441Y47244I-3937J0D01*
G01X1976378Y242835D02*
G03X1972441Y246772I-3937J0D01*
G01X1976378Y242835D02*
G03X1972441Y246772I-3937J0D01*
G01X1976378Y242835D02*
G03X1972441Y246772I-3937J0D01*
G01X1976378Y242835D02*
G03X1972441Y246772I-3937J0D01*
G01Y432598D02*
G03X1976378Y436535I0J3937D01*
G01X1972441Y432598D02*
G03X1976378Y436535I0J3937D01*
G01X1972441Y432598D02*
G03X1976378Y436535I0J3937D01*
G01X1972441Y432598D02*
G03X1976378Y436535I0J3937D01*
G01D02*
Y622441D01*
G01Y436535D02*
Y622441D01*
G01Y436535D02*
Y622441D01*
G01Y436535D02*
Y622441D01*
G01D02*
G03X1972441Y626378I-3937J0D01*
G01X1976378Y622441D02*
G03X1972441Y626378I-3937J0D01*
G01X1976378Y622441D02*
G03X1972441Y626378I-3937J0D01*
G01X1976378Y622441D02*
G03X1972441Y626378I-3937J0D01*
G01Y634252D02*
G03X1976378Y638189I0J3937D01*
G01X1972441Y634252D02*
G03X1976378Y638189I0J3937D01*
G01D02*
Y661811D01*
G01Y638189D02*
Y661811D01*
G01D02*
G03X1972441Y665748I-3937J0D01*
G01X1976378Y661811D02*
G03X1972441Y665748I-3937J0D01*
G54D12*
G01X1159783Y-48085D02*
X1161462D01*
G01X1159783Y-46485D02*
X1162125D01*
G01X1161462Y-48085D02*
X1164777Y-51400D01*
G01X1162125Y-46485D02*
X1165440Y-49800D01*
G01X1164777Y-51400D02*
X1363500D01*
G01X1165440Y-49800D02*
X1363500D01*
G01Y-45698D02*
X1169200D01*
G01X1363500Y-47298D02*
X1169200D01*
G01Y-45698D02*
G02Y-43196I0J1251D01*
G01Y-47298D02*
G02Y-41596I0J2851D01*
G01Y-43196D02*
X1365113D01*
G01X1169200Y-41596D02*
X1365113D01*
G01X1159783Y-46485D02*
X1162125D01*
G01X1159783Y-48085D02*
X1161462D01*
G01X1162125Y-46485D02*
X1165440Y-49800D01*
G01X1161462Y-48085D02*
X1164777Y-51400D01*
G01X1165440Y-49800D02*
X1363500D01*
G01X1164777Y-51400D02*
X1363500D01*
G01Y-47298D02*
X1169200D01*
G01X1363500Y-45698D02*
X1169200D01*
G01Y-47298D02*
G02Y-41596I0J2851D01*
G01Y-45698D02*
G02Y-43196I0J1251D01*
G01Y-41596D02*
X1365113D01*
G01X1169200Y-43196D02*
X1365113D01*
G01X1363500Y-51400D02*
G03Y-45698I0J2851D01*
G01Y-49800D02*
G03Y-47298I0J1251D01*
G01Y-49800D02*
G03Y-47298I0J1251D01*
G01Y-51400D02*
G03Y-45698I0J2851D01*
G01X1897607Y54808D02*
X1896501Y55914D01*
G01X1897607Y54808D02*
X1896501Y55914D01*
G01D02*
X1895933D01*
G01X1898270Y56408D02*
X1897164Y57514D01*
G01X1896501Y55914D02*
X1895933D01*
G01X1897164Y57514D02*
X1895270D01*
G01X1895933Y55914D02*
X1894729Y54710D01*
G01X1895270Y57514D02*
X1893129Y55373D01*
G01X1894729Y54710D02*
Y54142D01*
G01X1893129Y55373D02*
Y53479D01*
G01X1894729Y54142D02*
X1895835Y53036D01*
G01X1893129Y53479D02*
X1894235Y52373D01*
G01X1895835Y53036D02*
Y51142D01*
G01X1894235Y52373D02*
Y51805D01*
G01X1895835Y51142D02*
X1892446Y47753D01*
G01X1894235Y51805D02*
X1891783Y49353D01*
G01X1892446Y47753D02*
X1889620D01*
G01X1891783Y49353D02*
X1889620D01*
G01X1898270Y56408D02*
X1897164Y57514D01*
G01X1897607Y54808D02*
X1896501Y55914D01*
G01X1898270Y56408D02*
X1897164Y57514D01*
G01D02*
X1895270D01*
G01X1896501Y55914D02*
X1895933D01*
G01X1895270Y57514D02*
X1893129Y55373D01*
G01X1895933Y55914D02*
X1894729Y54710D01*
G01X1893129Y55373D02*
Y53479D01*
G01X1894729Y54710D02*
Y54142D01*
G01X1893129Y53479D02*
X1894235Y52373D01*
G01X1894729Y54142D02*
X1895835Y53036D01*
G01X1894235Y52373D02*
Y51805D01*
G01X1895835Y53036D02*
Y51142D01*
G01X1894235Y51805D02*
X1891783Y49353D01*
G01X1895835Y51142D02*
X1892446Y47753D01*
G01X1891783Y49353D02*
X1889620D01*
G01X1892446Y47753D02*
X1889620D01*
G01X1898783Y60160D02*
X1893928D01*
G01X1898120Y61760D02*
X1893265D01*
G01X1893928Y60160D02*
X1891179Y57411D01*
G01X1893265Y61760D02*
X1890516Y59011D01*
G01X1891179Y57411D02*
X1890084D01*
G01X1890516Y59011D02*
X1889719D01*
G01X1898120Y61760D02*
X1893265D01*
G01X1898783Y60160D02*
X1893928D01*
G01X1893265Y61760D02*
X1890516Y59011D01*
G01X1893928Y60160D02*
X1891179Y57411D01*
G01X1890516Y59011D02*
X1889719D01*
G01X1891179Y57411D02*
X1890084D01*
G01X1926954Y95587D02*
Y93889D01*
G01X1925354Y96250D02*
Y93226D01*
G01X1926954Y93889D02*
X1927356Y93487D01*
G01X1925354Y93226D02*
X1926693Y91887D01*
G01X1927356Y93487D02*
X1932784D01*
G01X1926693Y91887D02*
X1932121D01*
G01X1932784Y93487D02*
X1934123Y92148D01*
G01X1932121Y91887D02*
X1932523Y91485D01*
G01X1934123Y92148D02*
Y89124D01*
G01X1932523Y91485D02*
Y89787D01*
G01X1934123Y89124D02*
X1932784Y87785D01*
G01X1932523Y89787D02*
X1932121Y89385D01*
G01X1932784Y87785D02*
X1922410D01*
G01X1932121Y89385D02*
X1921747D01*
G01X1922410Y87785D02*
X1922008Y87383D01*
G01X1921747Y89385D02*
X1920408Y88046D01*
G01X1922008Y87383D02*
Y85888D01*
G01X1920408Y88046D02*
Y85225D01*
G01X1922008Y85888D02*
X1922613Y85283D01*
G01X1920408Y85225D02*
X1921950Y83683D01*
G01X1922613Y85283D02*
X1932784D01*
G01X1921950Y83683D02*
X1932121D01*
G01X1932784Y85283D02*
X1934123Y83944D01*
G01X1932121Y83683D02*
X1932523Y83281D01*
G01X1934123Y83944D02*
Y80920D01*
G01X1932523Y83281D02*
Y81583D01*
G01X1934123Y80920D02*
X1932784Y79581D01*
G01X1932523Y81583D02*
X1932121Y81181D01*
G01X1932784Y79581D02*
X1925516D01*
G01X1932121Y81181D02*
X1924853D01*
G01X1925516Y79581D02*
X1924859Y78924D01*
G01X1924853Y81181D02*
X1923259Y79587D01*
G01X1924859Y78924D02*
Y72364D01*
G01X1923259Y79587D02*
Y71701D01*
G01X1924859Y72364D02*
X1931082Y66141D01*
G01X1923259Y71701D02*
X1930419Y64541D01*
G01X1931082Y66141D02*
X1940163D01*
G01X1930419Y64541D02*
X1939500D01*
G01X1940163Y66141D02*
X1941502Y64802D01*
G01X1939500Y64541D02*
X1939902Y64139D01*
G01X1941502Y64802D02*
Y61665D01*
G01X1939902Y64139D02*
Y62328D01*
G01X1941502Y61665D02*
X1940163Y60326D01*
G01X1939902Y62328D02*
X1939500Y61926D01*
G01X1940163Y60326D02*
X1925624D01*
G01X1939500Y61926D02*
X1926287D01*
G01X1925624Y60326D02*
X1924285Y61665D01*
G01X1926287Y61926D02*
X1925885Y62328D01*
G01X1924285Y61665D02*
Y63540D01*
G01X1925885Y62328D02*
Y64203D01*
G01X1924285Y63540D02*
X1923883Y63942D01*
G01X1925885Y64203D02*
X1924546Y65542D01*
G01X1923883Y63942D02*
X1922185D01*
G01X1924546Y65542D02*
X1921522D01*
G01X1922185Y63942D02*
X1921783Y63540D01*
G01X1921522Y65542D02*
X1920183Y64203D01*
G01X1921783Y63540D02*
Y61665D01*
G01X1920183Y64203D02*
Y62328D01*
G01X1921783Y61665D02*
X1919859Y59741D01*
G01X1920183Y62328D02*
X1919196Y61341D01*
G01X1919859Y59741D02*
X1904434D01*
G01X1919196Y61341D02*
X1903771D01*
G01X1904434Y59741D02*
X1899501Y54808D01*
G01X1903771Y61341D02*
X1898838Y56408D01*
G01X1904434Y59741D02*
X1899501Y54808D01*
G01D02*
X1897607D01*
G01X1898838Y56408D02*
X1898270D01*
G01X1925354Y96250D02*
Y93226D01*
G01X1926954Y95587D02*
Y93889D01*
G01X1925354Y93226D02*
X1926693Y91887D01*
G01X1926954Y93889D02*
X1927356Y93487D01*
G01X1926693Y91887D02*
X1932121D01*
G01X1927356Y93487D02*
X1932784D01*
G01X1932121Y91887D02*
X1932523Y91485D01*
G01X1932784Y93487D02*
X1934123Y92148D01*
G01X1932523Y91485D02*
Y89787D01*
G01X1934123Y92148D02*
Y89124D01*
G01X1932523Y89787D02*
X1932121Y89385D01*
G01X1934123Y89124D02*
X1932784Y87785D01*
G01X1932121Y89385D02*
X1921747D01*
G01X1932784Y87785D02*
X1922410D01*
G01X1921747Y89385D02*
X1920408Y88046D01*
G01X1922410Y87785D02*
X1922008Y87383D01*
G01X1920408Y88046D02*
Y85225D01*
G01X1922008Y87383D02*
Y85888D01*
G01X1920408Y85225D02*
X1921950Y83683D01*
G01X1922008Y85888D02*
X1922613Y85283D01*
G01X1921950Y83683D02*
X1932121D01*
G01X1922613Y85283D02*
X1932784D01*
G01X1932121Y83683D02*
X1932523Y83281D01*
G01X1932784Y85283D02*
X1934123Y83944D01*
G01X1932523Y83281D02*
Y81583D01*
G01X1934123Y83944D02*
Y80920D01*
G01X1932523Y81583D02*
X1932121Y81181D01*
G01X1934123Y80920D02*
X1932784Y79581D01*
G01X1932121Y81181D02*
X1924853D01*
G01X1932784Y79581D02*
X1925516D01*
G01X1924853Y81181D02*
X1923259Y79587D01*
G01X1925516Y79581D02*
X1924859Y78924D01*
G01X1923259Y79587D02*
Y71701D01*
G01X1924859Y78924D02*
Y72364D01*
G01X1923259Y71701D02*
X1930419Y64541D01*
G01X1924859Y72364D02*
X1931082Y66141D01*
G01X1930419Y64541D02*
X1939500D01*
G01X1931082Y66141D02*
X1940163D01*
G01X1939500Y64541D02*
X1939902Y64139D01*
G01X1940163Y66141D02*
X1941502Y64802D01*
G01X1939902Y64139D02*
Y62328D01*
G01X1941502Y64802D02*
Y61665D01*
G01X1939902Y62328D02*
X1939500Y61926D01*
G01X1941502Y61665D02*
X1940163Y60326D01*
G01X1939500Y61926D02*
X1926287D01*
G01X1940163Y60326D02*
X1925624D01*
G01X1926287Y61926D02*
X1925885Y62328D01*
G01X1925624Y60326D02*
X1924285Y61665D01*
G01X1925885Y62328D02*
Y64203D01*
G01X1924285Y61665D02*
Y63540D01*
G01X1925885Y64203D02*
X1924546Y65542D01*
G01X1924285Y63540D02*
X1923883Y63942D01*
G01X1924546Y65542D02*
X1921522D01*
G01X1923883Y63942D02*
X1922185D01*
G01X1921522Y65542D02*
X1920183Y64203D01*
G01X1922185Y63942D02*
X1921783Y63540D01*
G01X1920183Y64203D02*
Y62328D01*
G01X1921783Y63540D02*
Y61665D01*
G01X1920183Y62328D02*
X1919196Y61341D01*
G01X1921783Y61665D02*
X1919859Y59741D01*
G01X1919196Y61341D02*
X1903771D01*
G01X1919859Y59741D02*
X1904434D01*
G01X1903771Y61341D02*
X1898838Y56408D01*
G01D02*
X1898270D01*
G01X1904434Y59741D02*
X1899501Y54808D01*
G01X1898838Y56408D02*
X1898270D01*
G01X1899501Y54808D02*
X1897607D01*
G01X1898838Y56408D02*
X1898270D01*
G01X1911291Y94823D02*
X1910889Y94421D01*
G01D02*
Y92723D01*
G01X1909289Y95084D02*
Y92060D01*
G01X1910889Y92723D02*
X1911291Y92321D01*
G01X1909289Y92060D02*
X1910628Y90721D01*
G01X1911291Y92321D02*
X1915127D01*
G01X1910628Y90721D02*
X1914464D01*
G01X1915127Y92321D02*
X1916516Y90932D01*
G01X1914464Y90721D02*
X1914916Y90269D01*
G01X1916516Y90932D02*
Y87958D01*
G01X1914916Y90269D02*
Y88621D01*
G01X1916516Y87958D02*
X1914747Y86189D01*
G01X1914916Y88621D02*
X1914084Y87789D01*
G01X1914747Y86189D02*
X1912032D01*
G01X1914084Y87789D02*
X1911369D01*
G01X1912032Y86189D02*
X1911298Y85455D01*
G01X1911369Y87789D02*
X1909698Y86118D01*
G01X1911298Y85455D02*
Y84421D01*
G01X1909698Y86118D02*
Y83758D01*
G01X1911298Y84421D02*
X1912032Y83687D01*
G01X1909698Y83758D02*
X1911369Y82087D01*
G01X1912032Y83687D02*
X1916618D01*
G01X1911369Y82087D02*
X1915955D01*
G01X1916618Y83687D02*
X1918093Y82212D01*
G01X1915955Y82087D02*
X1916493Y81549D01*
G01X1918093Y82212D02*
Y80318D01*
G01X1916493Y81549D02*
Y80981D01*
G01X1918093Y80318D02*
X1915224Y77449D01*
G01X1916493Y80981D02*
X1913624Y78112D01*
G01X1915224Y77449D02*
Y76315D01*
G01X1913624Y78112D02*
Y75652D01*
G01X1915224Y76315D02*
X1915626Y75913D01*
G01X1913624Y75652D02*
X1914963Y74313D01*
G01X1915626Y75913D02*
X1919176D01*
G01X1914963Y74313D02*
X1918513D01*
G01X1919176Y75913D02*
X1920757Y74332D01*
G01X1918513Y74313D02*
X1919157Y73669D01*
G01X1920757Y74332D02*
Y71792D01*
G01X1919157Y73669D02*
Y72455D01*
G01X1920757Y71792D02*
X1919176Y70211D01*
G01X1919157Y72455D02*
X1918513Y71811D01*
G01X1919176Y70211D02*
X1916190D01*
G01X1918513Y71811D02*
X1915527D01*
G01X1916190Y70211D02*
X1915788Y69809D01*
G01X1915527Y71811D02*
X1914188Y70472D01*
G01X1915788Y69809D02*
Y65150D01*
G01X1914188Y70472D02*
Y65813D01*
G01X1915788Y65150D02*
X1914481Y63843D01*
G01X1914188Y65813D02*
X1913818Y65443D01*
G01X1914481Y63843D02*
X1911393D01*
G01X1913818Y65443D02*
X1912056D01*
G01X1911393Y63843D02*
X1910053Y65183D01*
G01X1912056Y65443D02*
X1911653Y65846D01*
G01X1910053Y65183D02*
Y72944D01*
G01X1911653Y65846D02*
Y73607D01*
G01X1910053Y72944D02*
X1909455Y73542D01*
G01X1911653Y73607D02*
X1910118Y75142D01*
G01X1909455Y73542D02*
X1908149D01*
G01X1910118Y75142D02*
X1907486D01*
G01X1909455Y73542D02*
X1908149D01*
G01D02*
X1907551Y72944D01*
G01X1907486Y75142D02*
X1905951Y73607D01*
G01X1907551Y72944D02*
Y66425D01*
G01X1905951Y73607D02*
Y67088D01*
G01X1907551Y66425D02*
X1905827Y64701D01*
G01X1905951Y67088D02*
X1905164Y66301D01*
G01X1905827Y64701D02*
X1903324D01*
G01X1905164Y66301D02*
X1902661D01*
G01X1903324Y64701D02*
X1898783Y60160D01*
G01X1902661Y66301D02*
X1901808Y65448D01*
G01X1903324Y64701D02*
X1898783Y60160D01*
G01X1899332Y62972D02*
X1898120Y61760D01*
G01X1911291Y94823D02*
X1910889Y94421D01*
G01X1909289Y95084D02*
Y92060D01*
G01X1910889Y94421D02*
Y92723D01*
G01X1909289Y92060D02*
X1910628Y90721D01*
G01X1910889Y92723D02*
X1911291Y92321D01*
G01X1910628Y90721D02*
X1914464D01*
G01X1911291Y92321D02*
X1915127D01*
G01X1914464Y90721D02*
X1914916Y90269D01*
G01X1915127Y92321D02*
X1916516Y90932D01*
G01X1914916Y90269D02*
Y88621D01*
G01X1916516Y90932D02*
Y87958D01*
G01X1914916Y88621D02*
X1914084Y87789D01*
G01X1916516Y87958D02*
X1914747Y86189D01*
G01X1914084Y87789D02*
X1911369D01*
G01X1914747Y86189D02*
X1912032D01*
G01X1911369Y87789D02*
X1909698Y86118D01*
G01X1912032Y86189D02*
X1911298Y85455D01*
G01X1909698Y86118D02*
Y83758D01*
G01X1911298Y85455D02*
Y84421D01*
G01X1909698Y83758D02*
X1911369Y82087D01*
G01X1911298Y84421D02*
X1912032Y83687D01*
G01X1911369Y82087D02*
X1915955D01*
G01X1912032Y83687D02*
X1916618D01*
G01X1915955Y82087D02*
X1916493Y81549D01*
G01X1916618Y83687D02*
X1918093Y82212D01*
G01X1916493Y81549D02*
Y80981D01*
G01X1918093Y82212D02*
Y80318D01*
G01X1916493Y80981D02*
X1913624Y78112D01*
G01X1918093Y80318D02*
X1915224Y77449D01*
G01X1913624Y78112D02*
Y75652D01*
G01X1915224Y77449D02*
Y76315D01*
G01X1913624Y75652D02*
X1914963Y74313D01*
G01X1915224Y76315D02*
X1915626Y75913D01*
G01X1914963Y74313D02*
X1918513D01*
G01X1915626Y75913D02*
X1919176D01*
G01X1918513Y74313D02*
X1919157Y73669D01*
G01X1919176Y75913D02*
X1920757Y74332D01*
G01X1919157Y73669D02*
Y72455D01*
G01X1920757Y74332D02*
Y71792D01*
G01X1919157Y72455D02*
X1918513Y71811D01*
G01X1920757Y71792D02*
X1919176Y70211D01*
G01X1918513Y71811D02*
X1915527D01*
G01X1919176Y70211D02*
X1916190D01*
G01X1915527Y71811D02*
X1914188Y70472D01*
G01X1916190Y70211D02*
X1915788Y69809D01*
G01X1914188Y70472D02*
Y65813D01*
G01X1915788Y69809D02*
Y65150D01*
G01X1914188Y65813D02*
X1913818Y65443D01*
G01X1915788Y65150D02*
X1914481Y63843D01*
G01X1913818Y65443D02*
X1912056D01*
G01X1914481Y63843D02*
X1911393D01*
G01X1912056Y65443D02*
X1911653Y65846D01*
G01X1911393Y63843D02*
X1910053Y65183D01*
G01X1911653Y65846D02*
Y73607D01*
G01X1910053Y65183D02*
Y72944D01*
G01X1911653Y73607D02*
X1910118Y75142D01*
G01X1910053Y72944D02*
X1909455Y73542D01*
G01X1910118Y75142D02*
X1907486D01*
G01D02*
X1905951Y73607D01*
G01X1909455Y73542D02*
X1908149D01*
G01X1907486Y75142D02*
X1905951Y73607D01*
G01X1908149Y73542D02*
X1907551Y72944D01*
G01X1905951Y73607D02*
Y67088D01*
G01X1907551Y72944D02*
Y66425D01*
G01X1905951Y67088D02*
X1905164Y66301D01*
G01X1907551Y66425D02*
X1905827Y64701D01*
G01X1905164Y66301D02*
X1902661D01*
G01X1905827Y64701D02*
X1903324D01*
G01X1902661Y66301D02*
X1901808Y65448D01*
G01X1899332Y62972D02*
X1898120Y61760D01*
G01X1903324Y64701D02*
X1898783Y60160D01*
G01X1911738Y148871D02*
Y147901D01*
G01X1910138Y148838D02*
Y147238D01*
G01X1911738Y147901D02*
X1914487Y145152D01*
G01D02*
X1915348D01*
G01X1910138Y147238D02*
X1913824Y143552D01*
G01X1914487Y145152D02*
X1915348D01*
G01X1913824Y143552D02*
X1916011D01*
G01X1915348Y145152D02*
X1917846Y147650D01*
G01X1916011Y143552D02*
X1918509Y146050D01*
G01X1917846Y147650D02*
X1919737D01*
G01D02*
X1921880Y145507D01*
G01X1918509Y146050D02*
X1919074D01*
G01X1919737Y147650D02*
X1921880Y145507D01*
G01X1919074Y146050D02*
X1920280Y144844D01*
G01X1921880Y145507D02*
Y143614D01*
G01X1920280Y144844D02*
Y144277D01*
G01X1921880Y143614D02*
X1919168Y140902D01*
G01X1920280Y144277D02*
X1917568Y141565D01*
G01X1919168Y140902D02*
Y139982D01*
G01X1917568Y141565D02*
Y139319D01*
G01X1919168Y139982D02*
X1923356Y135794D01*
G01X1917568Y139319D02*
X1921756Y135131D01*
G01X1923356Y135794D02*
Y134151D01*
G01X1921756Y135131D02*
Y133488D01*
G01X1923356Y134151D02*
X1923758Y133749D01*
G01X1921756Y133488D02*
X1923095Y132149D01*
G01X1923758Y133749D02*
X1926422D01*
G01X1923095Y132149D02*
X1925759D01*
G01X1926422Y133749D02*
X1927761Y132410D01*
G01X1925759Y132149D02*
X1926161Y131747D01*
G01X1927761Y132410D02*
Y129386D01*
G01X1926161Y131747D02*
Y130049D01*
G01X1927761Y129386D02*
X1926422Y128047D01*
G01X1926161Y130049D02*
X1925759Y129647D01*
G01X1926422Y128047D02*
X1923758D01*
G01X1925759Y129647D02*
X1923095D01*
G01X1923758Y128047D02*
X1923356Y127645D01*
G01X1923095Y129647D02*
X1921756Y128308D01*
G01X1923356Y127645D02*
Y124417D01*
G01X1921756Y128308D02*
Y125080D01*
G01X1923356Y124417D02*
X1922036Y123097D01*
G01X1921756Y125080D02*
X1920436Y123760D01*
G01X1922036Y123097D02*
Y117491D01*
G01X1920436Y123760D02*
Y121536D01*
G01X1922036Y123097D02*
Y117491D01*
G01X1920436Y118034D02*
Y116828D01*
G01X1922036Y117491D02*
X1923816Y115711D01*
G01X1920436Y116828D02*
X1922216Y115048D01*
G01X1923816Y115711D02*
Y113818D01*
G01X1922216Y115048D02*
Y114481D01*
G01X1923816Y113818D02*
X1922729Y112731D01*
G01X1922216Y114481D02*
X1921129Y113394D01*
G01X1922729Y112731D02*
Y112163D01*
G01X1921129Y113394D02*
Y111500D01*
G01X1922729Y112163D02*
X1923931Y110961D01*
G01X1921129Y111500D02*
X1923268Y109361D01*
G01X1923931Y110961D02*
X1924499D01*
G01X1923268Y109361D02*
X1925162D01*
G01X1923931Y110961D02*
X1924499D01*
G01D02*
X1925586Y112048D01*
G01X1925162Y109361D02*
X1926249Y110448D01*
G01X1925586Y112048D02*
X1927479D01*
G01X1926249Y110448D02*
X1926816D01*
G01X1927479Y112048D02*
X1929632Y109895D01*
G01X1926816Y110448D02*
X1928969Y108295D01*
G01X1929632Y109895D02*
X1932586D01*
G01X1928969Y108295D02*
X1931923D01*
G01X1932586Y109895D02*
X1933970Y108511D01*
G01X1931923Y108295D02*
X1932370Y107848D01*
G01X1933970Y108511D02*
Y105532D01*
G01X1932370Y107848D02*
Y106195D01*
G01X1933970Y105532D02*
X1932631Y104193D01*
G01X1932370Y106195D02*
X1931968Y105793D01*
G01X1932631Y104193D02*
X1926164D01*
G01X1931968Y105793D02*
X1925501D01*
G01X1926164Y104193D02*
X1925762Y103791D01*
G01X1925501Y105793D02*
X1924162Y104454D01*
G01X1925762Y103791D02*
Y102138D01*
G01X1924162Y104454D02*
Y101475D01*
G01X1925762Y102138D02*
X1926209Y101691D01*
G01X1924162Y101475D02*
X1925546Y100091D01*
G01X1926209Y101691D02*
X1930360D01*
G01X1925546Y100091D02*
X1929697D01*
G01X1930360Y101691D02*
X1931699Y100352D01*
G01X1929697Y100091D02*
X1930099Y99689D01*
G01X1931699Y100352D02*
Y97328D01*
G01X1930099Y99689D02*
Y97991D01*
G01X1931699Y97328D02*
X1930360Y95989D01*
G01X1930099Y97991D02*
X1929697Y97589D01*
G01X1930360Y95989D02*
X1927356D01*
G01X1929697Y97589D02*
X1926693D01*
G01X1927356Y95989D02*
X1926954Y95587D01*
G01X1926693Y97589D02*
X1925354Y96250D01*
G01X1910138Y148838D02*
Y147238D01*
G01X1911738Y148871D02*
Y147901D01*
G01X1910138Y147238D02*
X1913824Y143552D01*
G01X1911738Y147901D02*
X1914487Y145152D01*
G01X1910138Y147238D02*
X1913824Y143552D01*
G01D02*
X1916011D01*
G01X1914487Y145152D02*
X1915348D01*
G01X1916011Y143552D02*
X1918509Y146050D01*
G01X1915348Y145152D02*
X1917846Y147650D01*
G01X1918509Y146050D02*
X1919074D01*
G01X1917846Y147650D02*
X1919737D01*
G01X1918509Y146050D02*
X1919074D01*
G01D02*
X1920280Y144844D01*
G01X1919737Y147650D02*
X1921880Y145507D01*
G01X1920280Y144844D02*
Y144277D01*
G01X1921880Y145507D02*
Y143614D01*
G01X1920280Y144277D02*
X1917568Y141565D01*
G01X1921880Y143614D02*
X1919168Y140902D01*
G01X1917568Y141565D02*
Y139319D01*
G01X1919168Y140902D02*
Y139982D01*
G01X1917568Y139319D02*
X1921756Y135131D01*
G01X1919168Y139982D02*
X1923356Y135794D01*
G01X1921756Y135131D02*
Y133488D01*
G01X1923356Y135794D02*
Y134151D01*
G01X1921756Y133488D02*
X1923095Y132149D01*
G01X1923356Y134151D02*
X1923758Y133749D01*
G01X1923095Y132149D02*
X1925759D01*
G01X1923758Y133749D02*
X1926422D01*
G01X1925759Y132149D02*
X1926161Y131747D01*
G01X1926422Y133749D02*
X1927761Y132410D01*
G01X1926161Y131747D02*
Y130049D01*
G01X1927761Y132410D02*
Y129386D01*
G01X1926161Y130049D02*
X1925759Y129647D01*
G01X1927761Y129386D02*
X1926422Y128047D01*
G01X1925759Y129647D02*
X1923095D01*
G01X1926422Y128047D02*
X1923758D01*
G01X1923095Y129647D02*
X1921756Y128308D01*
G01X1923758Y128047D02*
X1923356Y127645D01*
G01X1921756Y128308D02*
Y125080D01*
G01X1923356Y127645D02*
Y124417D01*
G01X1921756Y125080D02*
X1920436Y123760D01*
G01X1923356Y124417D02*
X1922036Y123097D01*
G01X1920436Y123760D02*
Y121536D01*
G01Y118034D02*
Y116828D01*
G01X1922036Y123097D02*
Y117491D01*
G01X1920436Y116828D02*
X1922216Y115048D01*
G01X1922036Y117491D02*
X1923816Y115711D01*
G01X1922216Y115048D02*
Y114481D01*
G01X1923816Y115711D02*
Y113818D01*
G01X1922216Y114481D02*
X1921129Y113394D01*
G01X1923816Y113818D02*
X1922729Y112731D01*
G01X1921129Y113394D02*
Y111500D01*
G01X1922729Y112731D02*
Y112163D01*
G01X1921129Y111500D02*
X1923268Y109361D01*
G01X1922729Y112163D02*
X1923931Y110961D01*
G01X1923268Y109361D02*
X1925162D01*
G01D02*
X1926249Y110448D01*
G01X1923931Y110961D02*
X1924499D01*
G01X1925162Y109361D02*
X1926249Y110448D01*
G01X1924499Y110961D02*
X1925586Y112048D01*
G01X1926249Y110448D02*
X1926816D01*
G01X1925586Y112048D02*
X1927479D01*
G01X1926816Y110448D02*
X1928969Y108295D01*
G01X1927479Y112048D02*
X1929632Y109895D01*
G01X1928969Y108295D02*
X1931923D01*
G01X1929632Y109895D02*
X1932586D01*
G01X1931923Y108295D02*
X1932370Y107848D01*
G01X1932586Y109895D02*
X1933970Y108511D01*
G01X1932370Y107848D02*
Y106195D01*
G01X1933970Y108511D02*
Y105532D01*
G01X1932370Y106195D02*
X1931968Y105793D01*
G01X1933970Y105532D02*
X1932631Y104193D01*
G01X1931968Y105793D02*
X1925501D01*
G01X1932631Y104193D02*
X1926164D01*
G01X1925501Y105793D02*
X1924162Y104454D01*
G01X1926164Y104193D02*
X1925762Y103791D01*
G01X1924162Y104454D02*
Y101475D01*
G01X1925762Y103791D02*
Y102138D01*
G01X1924162Y101475D02*
X1925546Y100091D01*
G01X1925762Y102138D02*
X1926209Y101691D01*
G01X1925546Y100091D02*
X1929697D01*
G01X1926209Y101691D02*
X1930360D01*
G01X1929697Y100091D02*
X1930099Y99689D01*
G01X1930360Y101691D02*
X1931699Y100352D01*
G01X1930099Y99689D02*
Y97991D01*
G01X1931699Y100352D02*
Y97328D01*
G01X1930099Y97991D02*
X1929697Y97589D01*
G01X1931699Y97328D02*
X1930360Y95989D01*
G01X1929697Y97589D02*
X1926693D01*
G01X1930360Y95989D02*
X1927356D01*
G01X1926693Y97589D02*
X1925354Y96250D01*
G01X1927356Y95989D02*
X1926954Y95587D01*
G01X1908028Y142432D02*
Y140933D01*
G01X1906428Y142312D02*
Y140270D01*
G01X1908028Y140933D02*
X1908450Y140511D01*
G01X1906428Y140270D02*
X1907787Y138911D01*
G01X1908450Y140511D02*
X1912809D01*
G01X1907787Y138911D02*
X1912146D01*
G01X1912809Y140511D02*
X1916594Y136726D01*
G01X1912146Y138911D02*
X1914994Y136063D01*
G01X1916594Y136726D02*
Y133582D01*
G01X1914994Y136063D02*
Y132919D01*
G01X1916594Y133582D02*
X1917672Y132504D01*
G01X1914994Y132919D02*
X1916072Y131841D01*
G01X1917672Y132504D02*
Y122332D01*
G01X1916072Y131841D02*
Y122995D01*
G01X1917672Y122332D02*
X1916760Y121420D01*
G01X1916072Y122995D02*
X1915160Y122083D01*
G01X1916760Y121420D02*
Y120380D01*
G01X1915160Y122083D02*
Y121043D01*
G01X1916760Y120380D02*
X1915343Y118963D01*
G01X1915160Y121043D02*
X1914680Y120563D01*
G01X1915343Y118963D02*
X1912745D01*
G01X1914680Y120563D02*
X1913408D01*
G01X1912745Y118963D02*
X1912030Y119678D01*
G01X1913408Y120563D02*
X1912693Y121278D01*
G01X1912030Y119678D02*
X1911104D01*
G01X1912693Y121278D02*
X1910441D01*
G01X1912030Y119678D02*
X1911104D01*
G01D02*
X1910260Y118834D01*
G01X1910441Y121278D02*
X1908660Y119497D01*
G01X1910260Y118834D02*
Y117908D01*
G01X1908660Y119497D02*
Y117245D01*
G01X1910260Y117908D02*
X1910975Y117193D01*
G01X1908660Y117245D02*
X1909375Y116530D01*
G01X1910975Y117193D02*
Y115299D01*
G01X1909375Y116530D02*
Y115962D01*
G01X1910975Y115299D02*
X1909964Y114288D01*
G01X1909375Y115962D02*
X1908364Y114951D01*
G01X1909964Y114288D02*
Y109229D01*
G01X1908364Y114951D02*
Y108566D01*
G01X1909964Y109229D02*
X1910464Y108729D01*
G01X1908364Y108566D02*
X1909801Y107129D01*
G01X1910464Y108729D02*
X1911681D01*
G01X1909801Y107129D02*
X1912344D01*
G01X1910464Y108729D02*
X1911681D01*
G01D02*
X1914292Y111340D01*
G01X1912344Y107129D02*
X1914955Y109740D01*
G01X1914292Y111340D02*
X1916693D01*
G01D02*
X1919304Y108729D01*
G01X1914955Y109740D02*
X1916030D01*
G01X1916693Y111340D02*
X1919304Y108729D01*
G01D02*
X1920236D01*
G01X1916030Y109740D02*
X1918641Y107129D01*
G01X1919304Y108729D02*
X1920236D01*
G01X1918641Y107129D02*
X1919573D01*
G01X1920236Y108729D02*
X1921607Y107358D01*
G01X1919573Y107129D02*
X1920007Y106695D01*
G01X1921607Y107358D02*
Y104398D01*
G01X1920007Y106695D02*
Y105061D01*
G01X1921607Y104398D02*
X1920236Y103027D01*
G01X1920007Y105061D02*
X1919573Y104627D01*
G01X1920236Y103027D02*
X1912395D01*
G01X1919573Y104627D02*
X1911732D01*
G01X1912395Y103027D02*
X1911993Y102625D01*
G01X1911732Y104627D02*
X1910393Y103288D01*
G01X1911993Y102625D02*
Y100927D01*
G01X1910393Y103288D02*
Y100264D01*
G01X1911993Y100927D02*
X1912395Y100525D01*
G01X1910393Y100264D02*
X1911732Y98925D01*
G01X1912395Y100525D02*
X1914808D01*
G01X1911732Y98925D02*
X1914145D01*
G01X1914808Y100525D02*
X1916187Y99146D01*
G01X1914145Y98925D02*
X1914587Y98483D01*
G01X1916187Y99146D02*
Y96162D01*
G01X1914587Y98483D02*
Y96825D01*
G01X1916187Y96162D02*
X1914848Y94823D01*
G01X1914587Y96825D02*
X1914185Y96423D01*
G01X1914848Y94823D02*
X1911291D01*
G01X1914185Y96423D02*
X1910628D01*
G01D02*
X1909289Y95084D01*
G01X1906428Y142312D02*
Y140270D01*
G01X1908028Y142432D02*
Y140933D01*
G01X1906428Y140270D02*
X1907787Y138911D01*
G01X1908028Y140933D02*
X1908450Y140511D01*
G01X1907787Y138911D02*
X1912146D01*
G01X1908450Y140511D02*
X1912809D01*
G01X1912146Y138911D02*
X1914994Y136063D01*
G01X1912809Y140511D02*
X1916594Y136726D01*
G01X1914994Y136063D02*
Y132919D01*
G01X1916594Y136726D02*
Y133582D01*
G01X1914994Y132919D02*
X1916072Y131841D01*
G01X1916594Y133582D02*
X1917672Y132504D01*
G01X1916072Y131841D02*
Y122995D01*
G01X1917672Y132504D02*
Y122332D01*
G01X1916072Y122995D02*
X1915160Y122083D01*
G01X1917672Y122332D02*
X1916760Y121420D01*
G01X1915160Y122083D02*
Y121043D01*
G01X1916760Y121420D02*
Y120380D01*
G01X1915160Y121043D02*
X1914680Y120563D01*
G01X1916760Y120380D02*
X1915343Y118963D01*
G01X1914680Y120563D02*
X1913408D01*
G01X1915343Y118963D02*
X1912745D01*
G01X1913408Y120563D02*
X1912693Y121278D01*
G01X1912745Y118963D02*
X1912030Y119678D01*
G01X1912693Y121278D02*
X1910441D01*
G01D02*
X1908660Y119497D01*
G01X1912030Y119678D02*
X1911104D01*
G01X1910441Y121278D02*
X1908660Y119497D01*
G01X1911104Y119678D02*
X1910260Y118834D01*
G01X1908660Y119497D02*
Y117245D01*
G01X1910260Y118834D02*
Y117908D01*
G01X1908660Y117245D02*
X1909375Y116530D01*
G01X1910260Y117908D02*
X1910975Y117193D01*
G01X1909375Y116530D02*
Y115962D01*
G01X1910975Y117193D02*
Y115299D01*
G01X1909375Y115962D02*
X1908364Y114951D01*
G01X1910975Y115299D02*
X1909964Y114288D01*
G01X1908364Y114951D02*
Y108566D01*
G01X1909964Y114288D02*
Y109229D01*
G01X1908364Y108566D02*
X1909801Y107129D01*
G01X1909964Y109229D02*
X1910464Y108729D01*
G01X1909801Y107129D02*
X1912344D01*
G01D02*
X1914955Y109740D01*
G01X1910464Y108729D02*
X1911681D01*
G01X1912344Y107129D02*
X1914955Y109740D01*
G01X1911681Y108729D02*
X1914292Y111340D01*
G01X1914955Y109740D02*
X1916030D01*
G01X1914292Y111340D02*
X1916693D01*
G01X1914955Y109740D02*
X1916030D01*
G01D02*
X1918641Y107129D01*
G01X1916693Y111340D02*
X1919304Y108729D01*
G01X1916030Y109740D02*
X1918641Y107129D01*
G01D02*
X1919573D01*
G01X1919304Y108729D02*
X1920236D01*
G01X1919573Y107129D02*
X1920007Y106695D01*
G01X1920236Y108729D02*
X1921607Y107358D01*
G01X1920007Y106695D02*
Y105061D01*
G01X1921607Y107358D02*
Y104398D01*
G01X1920007Y105061D02*
X1919573Y104627D01*
G01X1921607Y104398D02*
X1920236Y103027D01*
G01X1919573Y104627D02*
X1911732D01*
G01X1920236Y103027D02*
X1912395D01*
G01X1911732Y104627D02*
X1910393Y103288D01*
G01X1912395Y103027D02*
X1911993Y102625D01*
G01X1910393Y103288D02*
Y100264D01*
G01X1911993Y102625D02*
Y100927D01*
G01X1910393Y100264D02*
X1911732Y98925D01*
G01X1911993Y100927D02*
X1912395Y100525D01*
G01X1911732Y98925D02*
X1914145D01*
G01X1912395Y100525D02*
X1914808D01*
G01X1914145Y98925D02*
X1914587Y98483D01*
G01X1914808Y100525D02*
X1916187Y99146D01*
G01X1914587Y98483D02*
Y96825D01*
G01X1916187Y99146D02*
Y96162D01*
G01X1914587Y96825D02*
X1914185Y96423D01*
G01X1916187Y96162D02*
X1914848Y94823D01*
G01X1914185Y96423D02*
X1910628D01*
G01X1914848Y94823D02*
X1911291D01*
G01X1910628Y96423D02*
X1909289Y95084D01*
G54D13*
G01X26040Y100040D02*
Y98160D01*
G01X24890Y100031D02*
Y97683D01*
G01X26040Y98160D02*
X26490Y97710D01*
G01X24890Y97683D02*
X26013Y96560D01*
G01X26490Y97710D02*
X35048D01*
G01X26013Y96560D02*
X35525D01*
G01X35048Y97710D02*
X36713Y99375D01*
G01X37667Y101249D02*
X38587D01*
G01D02*
X39541Y102203D01*
G01X40496Y104077D02*
X41415D01*
G01D02*
X42370Y105032D01*
G01X43324Y106905D02*
X44243D01*
G01D02*
X45198Y107860D01*
G01X35525Y96560D02*
X45675Y106710D01*
G01X45198Y107860D02*
X50760D01*
G01X45675Y106710D02*
X50770D01*
G01X-12060Y108309D02*
Y107046D01*
G01X-13210Y108310D02*
Y106569D01*
G01X-12060Y107046D02*
X-10407Y105393D01*
G01X-13210Y106569D02*
X-10884Y104243D01*
G01X-10407Y105393D02*
X33265D01*
G01X-10884Y104243D02*
X33742D01*
G01X33265Y105393D02*
X34187Y106315D01*
G01X35141Y108189D02*
X36061D01*
G01D02*
X37015Y109143D01*
G01X37970Y111017D02*
X38889D01*
G01D02*
X39844Y111972D01*
G01X40798Y113845D02*
X41717D01*
G01D02*
X42672Y114800D01*
G01X33742Y104243D02*
X43149Y113650D01*
G01X42672Y114800D02*
X46400D01*
G01X43149Y113650D02*
X46400D01*
G01X19770Y109571D02*
Y111056D01*
G01X20920Y109580D02*
Y110579D01*
G01X19770Y111056D02*
X22321Y113607D01*
G01X20920Y110579D02*
X22798Y112457D01*
G01X22321Y113607D02*
X34578D01*
G01X22798Y112457D02*
X31055D01*
G01X22321Y113607D02*
X34578D01*
G01X33705Y112457D02*
X35055D01*
G01X34578Y113607D02*
X36341Y115370D01*
G01X35055Y112457D02*
X37491Y114893D01*
G01X36341Y115370D02*
Y122240D01*
G01X37491Y114893D02*
Y117763D01*
G01X36341Y115370D02*
Y122240D01*
G01X37491Y120413D02*
Y121763D01*
G01X36341Y122240D02*
X42901Y128800D01*
G01X37491Y121763D02*
X40550Y124822D01*
G01X36341Y122240D02*
X42901Y128800D01*
G01X40550Y124822D02*
X41469D01*
G01X36341Y122240D02*
X42901Y128800D01*
G01X42423Y126695D02*
X43378Y127650D01*
G01X42901Y128800D02*
X46160D01*
G01X43378Y127650D02*
X46150D01*
G01X24833Y117533D02*
Y119275D01*
G01X25983Y117917D02*
Y118798D01*
G01X24833Y119275D02*
X27339Y121781D01*
G01X25983Y118798D02*
X27816Y120631D01*
G01X27339Y121781D02*
X30754D01*
G01X27816Y120631D02*
X31231D01*
G01X30754Y121781D02*
X32596Y123623D01*
G01X31231Y120631D02*
X33746Y123146D01*
G01X32596Y123623D02*
Y127818D01*
G01X33746Y123146D02*
Y127341D01*
G01X32596Y127818D02*
X38800Y134022D01*
G01X33746Y127341D02*
X34701Y128296D01*
G01X32596Y127818D02*
X38800Y134022D01*
G01X34701Y128296D02*
X35620D01*
G01X32596Y127818D02*
X38800Y134022D01*
G01X36574Y130169D02*
X39950Y133545D01*
G01X38800Y134022D02*
Y140426D01*
G01X39950Y133545D02*
Y134895D01*
G01X38800Y134022D02*
Y140426D01*
G01X39950Y137545D02*
Y139949D01*
G01X38800Y140426D02*
X41354Y142980D01*
G01X39950Y139949D02*
X41831Y141830D01*
G01X41354Y142980D02*
X46280D01*
G01X41831Y141830D02*
X46276D01*
G01X24890Y100031D02*
Y97683D01*
G01X26040Y100040D02*
Y98160D01*
G01X24890Y97683D02*
X26013Y96560D01*
G01X26040Y98160D02*
X26490Y97710D01*
G01X26013Y96560D02*
X35525D01*
G01X26490Y97710D02*
X35048D01*
G01X35525Y96560D02*
X45675Y106710D01*
G01X35048Y97710D02*
X36713Y99375D01*
G01X35525Y96560D02*
X45675Y106710D01*
G01X37667Y101249D02*
X38587D01*
G01X35525Y96560D02*
X45675Y106710D01*
G01X38587Y101249D02*
X39541Y102203D01*
G01X35525Y96560D02*
X45675Y106710D01*
G01X40496Y104077D02*
X41415D01*
G01X35525Y96560D02*
X45675Y106710D01*
G01X41415Y104077D02*
X42370Y105032D01*
G01X35525Y96560D02*
X45675Y106710D01*
G01X43324Y106905D02*
X44243D01*
G01X35525Y96560D02*
X45675Y106710D01*
G01X44243Y106905D02*
X45198Y107860D01*
G01X45675Y106710D02*
X50770D01*
G01X45198Y107860D02*
X50760D01*
G01X-13210Y108310D02*
Y106569D01*
G01X-12060Y108309D02*
Y107046D01*
G01X-13210Y106569D02*
X-10884Y104243D01*
G01X-12060Y107046D02*
X-10407Y105393D01*
G01X-10884Y104243D02*
X33742D01*
G01X-10407Y105393D02*
X33265D01*
G01X33742Y104243D02*
X43149Y113650D01*
G01X33265Y105393D02*
X34187Y106315D01*
G01X33742Y104243D02*
X43149Y113650D01*
G01X35141Y108189D02*
X36061D01*
G01X33742Y104243D02*
X43149Y113650D01*
G01X36061Y108189D02*
X37015Y109143D01*
G01X33742Y104243D02*
X43149Y113650D01*
G01X37970Y111017D02*
X38889D01*
G01X33742Y104243D02*
X43149Y113650D01*
G01X38889Y111017D02*
X39844Y111972D01*
G01X33742Y104243D02*
X43149Y113650D01*
G01X40798Y113845D02*
X41717D01*
G01X33742Y104243D02*
X43149Y113650D01*
G01X41717Y113845D02*
X42672Y114800D01*
G01X43149Y113650D02*
X46400D01*
G01X42672Y114800D02*
X46400D01*
G01X20920Y109580D02*
Y110579D01*
G01X19770Y109571D02*
Y111056D01*
G01X20920Y110579D02*
X22798Y112457D01*
G01X19770Y111056D02*
X22321Y113607D01*
G01X22798Y112457D02*
X31055D01*
G01X33705D02*
X35055D01*
G01X22321Y113607D02*
X34578D01*
G01X35055Y112457D02*
X37491Y114893D01*
G01X34578Y113607D02*
X36341Y115370D01*
G01X37491Y114893D02*
Y117763D01*
G01Y120413D02*
Y121763D01*
G01X36341Y115370D02*
Y122240D01*
G01X37491Y121763D02*
X40550Y124822D01*
G01D02*
X41469D01*
G01X42423Y126695D02*
X43378Y127650D01*
G01X36341Y122240D02*
X42901Y128800D01*
G01X43378Y127650D02*
X46150D01*
G01X42901Y128800D02*
X46160D01*
G01X25983Y117917D02*
Y118798D01*
G01X24833Y117533D02*
Y119275D01*
G01X25983Y118798D02*
X27816Y120631D01*
G01X24833Y119275D02*
X27339Y121781D01*
G01X27816Y120631D02*
X31231D01*
G01X27339Y121781D02*
X30754D01*
G01X31231Y120631D02*
X33746Y123146D01*
G01X30754Y121781D02*
X32596Y123623D01*
G01X33746Y123146D02*
Y127341D01*
G01X32596Y123623D02*
Y127818D01*
G01X33746Y127341D02*
X34701Y128296D01*
G01D02*
X35620D01*
G01X36574Y130169D02*
X39950Y133545D01*
G01X32596Y127818D02*
X38800Y134022D01*
G01X39950Y133545D02*
Y134895D01*
G01Y137545D02*
Y139949D01*
G01X38800Y134022D02*
Y140426D01*
G01X39950Y139949D02*
X41831Y141830D01*
G01X38800Y140426D02*
X41354Y142980D01*
G01X41831Y141830D02*
X46276D01*
G01X41354Y142980D02*
X46280D01*
G01X1109035Y-49950D02*
X909850D01*
G01X1109035Y-51100D02*
X909373D01*
G01X909850Y-49950D02*
X906382Y-46482D01*
G01X909373Y-51100D02*
X905905Y-47632D01*
G01X906382Y-46482D02*
X883409D01*
G01X905905Y-47632D02*
X883409D01*
G01X1109035Y-51100D02*
X909373D01*
G01X1109035Y-49950D02*
X909850D01*
G01X909373Y-51100D02*
X905905Y-47632D01*
G01X909850Y-49950D02*
X906382Y-46482D01*
G01X905905Y-47632D02*
X883409D01*
G01X906382Y-46482D02*
X883409D01*
G01X1109156Y-42550D02*
X914500D01*
G01X1109156Y-43700D02*
X914500D01*
G01Y-42550D02*
G03Y-47400I0J-2425D01*
G01Y-43700D02*
G03Y-46250I0J-1275D01*
G01Y-47400D02*
X1109035D01*
G01X914500Y-46250D02*
X1109035D01*
G01X1109156Y-43700D02*
X914500D01*
G01X1109156Y-42550D02*
X914500D01*
G01Y-43700D02*
G03Y-46250I0J-1275D01*
G01Y-42550D02*
G03Y-47400I0J-2425D01*
G01Y-46250D02*
X1109035D01*
G01X914500Y-47400D02*
X1109035D01*
G01X954167Y649479D02*
X953101Y648669D01*
G01D02*
X952255D01*
G01X954167Y649479D02*
X953101Y648669D01*
G01X952713Y649819D02*
X953343Y650298D01*
G01X955164Y650808D02*
X954167Y649479D01*
G01X956172Y644902D02*
X957656Y653309D01*
G01X958872Y653578D02*
X957388Y645172D01*
G01X957085Y643598D02*
X956172Y644902D01*
G01X957388Y645172D02*
X957755Y644648D01*
G01X960358Y644159D02*
X959058Y643249D01*
G01D02*
X957085Y643598D01*
G01X957755Y644648D02*
X958789Y644465D01*
G01X960358Y644159D02*
X959058Y643249D01*
G01X958789Y644465D02*
X959308Y644828D01*
G01X962043Y653709D02*
X960358Y644159D01*
G01X959308Y644828D02*
X960992Y654378D01*
G01X962471Y644917D02*
X963963Y653371D01*
G01X965179Y653639D02*
X963687Y645186D01*
G01X963381Y643614D02*
X962471Y644917D01*
G01X963687Y645186D02*
X964051Y644665D01*
G01X966659Y644178D02*
X965355Y643268D01*
G01D02*
X963381Y643614D01*
G01X964051Y644665D02*
X965086Y644483D01*
G01X966659Y644178D02*
X965355Y643268D01*
G01X965086Y644483D02*
X965609Y644848D01*
G01X968338Y653712D02*
X966659Y644178D01*
G01X965609Y644848D02*
X967287Y654382D01*
G01X968767Y644918D02*
X970258Y653374D01*
G01X971474Y653643D02*
X969983Y645187D01*
G01X969677Y643615D02*
X968767Y644918D01*
G01X969983Y645187D02*
X970347Y644666D01*
G01X972955Y644179D02*
X971651Y643269D01*
G01D02*
X969677Y643615D01*
G01X970347Y644666D02*
X971381Y644484D01*
G01X972955Y644179D02*
X971651Y643269D01*
G01X971381Y644484D02*
X971904Y644849D01*
G01X970347Y644666D02*
X971381Y644484D01*
G01D02*
X971904Y644849D01*
G01X972955Y644179D02*
X971651Y643269D01*
G01X970347Y644666D02*
X971381Y644484D01*
G01X971651Y643269D02*
X969677Y643615D01*
G01X969983Y645187D02*
X970347Y644666D01*
G01X969677Y643615D02*
X968767Y644918D01*
G01X971474Y653643D02*
X969983Y645187D01*
G01X968767Y644918D02*
X970258Y653374D01*
G01X965609Y644848D02*
X967287Y654382D01*
G01X968338Y653712D02*
X966659Y644178D01*
G01X964051Y644665D02*
X965086Y644483D01*
G01D02*
X965609Y644848D01*
G01X966659Y644178D02*
X965355Y643268D01*
G01X964051Y644665D02*
X965086Y644483D01*
G01X965355Y643268D02*
X963381Y643614D01*
G01X963687Y645186D02*
X964051Y644665D01*
G01X963381Y643614D02*
X962471Y644917D01*
G01X965179Y653639D02*
X963687Y645186D01*
G01X962471Y644917D02*
X963963Y653371D01*
G01X959308Y644828D02*
X960992Y654378D01*
G01X962043Y653709D02*
X960358Y644159D01*
G01X957755Y644648D02*
X958789Y644465D01*
G01D02*
X959308Y644828D01*
G01X960358Y644159D02*
X959058Y643249D01*
G01X957755Y644648D02*
X958789Y644465D01*
G01X959058Y643249D02*
X957085Y643598D01*
G01X957388Y645172D02*
X957755Y644648D01*
G01X957085Y643598D02*
X956172Y644902D01*
G01X958872Y653578D02*
X957388Y645172D01*
G01X956172Y644902D02*
X957656Y653309D01*
G01X955164Y650808D02*
X954167Y649479D01*
G01X952713Y649819D02*
X953343Y650298D01*
G01X954167Y649479D02*
X953101Y648669D01*
G01D02*
X952255D01*
G01X952235Y649819D02*
X952713D01*
G01X953343Y650298D02*
X954105Y651314D01*
G01X955400Y651738D02*
X955164Y650808D01*
G01X954105Y651314D02*
X954274Y651980D01*
G01X955736Y653648D02*
X955400Y651738D01*
G01X954274Y651980D02*
X954686Y654317D01*
G01X957291Y653831D02*
X956257Y654013D01*
G01D02*
X955736Y653648D01*
G01X954686Y654317D02*
X955987Y655229D01*
G01X957291Y653831D02*
X956257Y654013D01*
G01X955987Y655229D02*
X957961Y654882D01*
G01X957656Y653309D02*
X957291Y653831D01*
G01X957961Y654882D02*
X958872Y653578D01*
G01X963599Y653894D02*
X962566Y654076D01*
G01D02*
X962043Y653709D01*
G01X960992Y654378D02*
X962296Y655292D01*
G01X963599Y653894D02*
X962566Y654076D01*
G01X962296Y655292D02*
X964270Y654944D01*
G01X963963Y653371D02*
X963599Y653894D01*
G01X964270Y654944D02*
X965179Y653639D01*
G01X969893Y653896D02*
X968860Y654077D01*
G01D02*
X968338Y653712D01*
G01X967287Y654382D02*
X968590Y655292D01*
G01X969893Y653896D02*
X968860Y654077D01*
G01X968590Y655292D02*
X970562Y654947D01*
G01X970258Y653374D02*
X969893Y653896D01*
G01X970562Y654947D02*
X971474Y653643D01*
G01X970562Y654947D02*
X971474Y653643D01*
G01X970258Y653374D02*
X969893Y653896D01*
G01X967287Y654382D02*
X968590Y655292D01*
G01D02*
X970562Y654947D01*
G01X969893Y653896D02*
X968860Y654077D01*
G01X967287Y654382D02*
X968590Y655292D01*
G01X968860Y654077D02*
X968338Y653712D01*
G01X964270Y654944D02*
X965179Y653639D01*
G01X963963Y653371D02*
X963599Y653894D01*
G01X960992Y654378D02*
X962296Y655292D01*
G01D02*
X964270Y654944D01*
G01X963599Y653894D02*
X962566Y654076D01*
G01X960992Y654378D02*
X962296Y655292D01*
G01X962566Y654076D02*
X962043Y653709D01*
G01X957961Y654882D02*
X958872Y653578D01*
G01X957656Y653309D02*
X957291Y653831D01*
G01X954686Y654317D02*
X955987Y655229D01*
G01D02*
X957961Y654882D01*
G01X957291Y653831D02*
X956257Y654013D01*
G01X954686Y654317D02*
X955987Y655229D01*
G01X956257Y654013D02*
X955736Y653648D01*
G01X954274Y651980D02*
X954686Y654317D01*
G01X955736Y653648D02*
X955400Y651738D01*
G01X954105Y651314D02*
X954274Y651980D01*
G01X955400Y651738D02*
X955164Y650808D01*
G01X953343Y650298D02*
X954105Y651314D01*
G01X952235Y649819D02*
X952713D01*
G01X952235D02*
X952713D01*
G01X974637Y653731D02*
X972955Y644179D01*
G01X971904Y644849D02*
X973587Y654401D01*
G01X975058Y644885D02*
X976558Y653394D01*
G01X977774Y653665D02*
X976274Y645154D01*
G01X975968Y643582D02*
X975058Y644885D01*
G01X976274Y645154D02*
X976638Y644633D01*
G01X979242Y644146D02*
X977942Y643235D01*
G01D02*
X975968Y643582D01*
G01X976638Y644633D02*
X977672Y644451D01*
G01X979242Y644146D02*
X977942Y643235D01*
G01X977672Y644451D02*
X978192Y644815D01*
G01X980933Y653728D02*
X979242Y644146D01*
G01X978192Y644815D02*
X979882Y654396D01*
G01X981355Y644884D02*
X982855Y653392D01*
G01X984071Y653662D02*
X982571Y645155D01*
G01X982264Y643583D02*
X981355Y644884D01*
G01X982571Y645155D02*
X982934Y644633D01*
G01X985540Y644145D02*
X984237Y643235D01*
G01D02*
X982264Y643583D01*
G01X982934Y644633D02*
X983968Y644450D01*
G01X985540Y644145D02*
X984237Y643235D01*
G01X983968Y644450D02*
X984490Y644815D01*
G01X987209Y653615D02*
X985540Y644145D01*
G01X984490Y644815D02*
X986158Y654284D01*
G01X987652Y644902D02*
X989129Y653279D01*
G01X990345Y653547D02*
X988868Y645171D01*
G01X988562Y643599D02*
X987652Y644902D01*
G01X988868Y645171D02*
X989232Y644650D01*
G01X991838Y644163D02*
X990535Y643254D01*
G01D02*
X988562Y643599D01*
G01X989232Y644650D02*
X990266Y644469D01*
G01X991838Y644163D02*
X990535Y643254D01*
G01X990266Y644469D02*
X990788Y644833D01*
G01X993507Y653619D02*
X991838Y644163D01*
G01X990788Y644833D02*
X992457Y654289D01*
G01X993947Y644904D02*
X995425Y653279D01*
G01X996641Y653548D02*
X995163Y645173D01*
G01X994858Y643600D02*
X993947Y644904D01*
G01X995163Y645173D02*
X995528Y644651D01*
G01X998135Y644163D02*
X996832Y643254D01*
G01D02*
X994858Y643600D01*
G01X995528Y644651D02*
X996563Y644469D01*
G01X998135Y644163D02*
X996832Y643254D01*
G01X996563Y644469D02*
X997085Y644833D01*
G01X999802Y653635D02*
X998135Y644163D01*
G01X997085Y644833D02*
X998751Y654306D01*
G01X1000237Y644871D02*
X1001723Y653296D01*
G01X1002939Y653564D02*
X1001453Y645140D01*
G01X1001148Y643567D02*
X1000237Y644871D01*
G01X1001453Y645140D02*
X1001818Y644618D01*
G01X1004425Y644130D02*
X1003122Y643221D01*
G01D02*
X1001148Y643567D01*
G01X1001818Y644618D02*
X1002853Y644436D01*
G01X1004425Y644130D02*
X1003122Y643221D01*
G01X1002853Y644436D02*
X1003375Y644800D01*
G01X1006091Y653587D02*
X1004425Y644130D01*
G01X1003375Y644800D02*
X1005041Y654256D01*
G01X1006533Y644871D02*
X1008010Y653249D01*
G01X1009226Y653518D02*
X1007749Y645140D01*
G01X1007443Y643568D02*
X1006533Y644871D01*
G01X1007749Y645140D02*
X1008113Y644618D01*
G01X1010719Y644131D02*
X1009416Y643221D01*
G01D02*
X1007443Y643568D01*
G01X1008113Y644618D02*
X1009147Y644436D01*
G01X1010719Y644131D02*
X1009416Y643221D01*
G01X1009147Y644436D02*
X1009669Y644801D01*
G01X1012357Y653390D02*
X1010719Y644131D01*
G01X1009669Y644801D02*
X1011307Y654060D01*
G01X1012851Y644965D02*
X1014277Y653051D01*
G01X1015493Y653319D02*
X1014067Y645234D01*
G01X1013788Y643623D02*
X1012851Y644965D01*
G01X1014067Y645234D02*
X1014457Y644674D01*
G01X1017036Y644227D02*
X1015696Y643288D01*
G01D02*
X1013788Y643623D01*
G01X1014457Y644674D02*
X1015426Y644504D01*
G01X1017036Y644227D02*
X1015696Y643288D01*
G01X1015426Y644504D02*
X1015986Y644896D01*
G01X1018651Y653392D02*
X1017036Y644227D01*
G01X1015986Y644896D02*
X1017601Y654062D01*
G01X1019141Y644936D02*
X1020573Y653052D01*
G01X1021789Y653321D02*
X1020357Y645204D01*
G01X1020052Y643629D02*
X1019141Y644936D01*
G01X1020357Y645204D02*
X1020722Y644680D01*
G01X1023329Y644194D02*
X1022023Y643285D01*
G01D02*
X1020052Y643629D01*
G01X1020722Y644680D02*
X1021754Y644500D01*
G01X1023329Y644194D02*
X1022023Y643285D01*
G01X1021754Y644500D02*
X1022278Y644865D01*
G01X1024941Y653359D02*
X1023329Y644194D01*
G01X1022278Y644865D02*
X1023891Y654029D01*
G01X1025436Y644935D02*
X1026863Y653019D01*
G01X1028079Y653288D02*
X1026652Y645204D01*
G01X1026347Y643631D02*
X1025436Y644935D01*
G01X1026652Y645204D02*
X1027017Y644682D01*
G01X1029620Y644194D02*
X1028318Y643284D01*
G01D02*
X1026347Y643631D01*
G01X1027017Y644682D02*
X1028049Y644500D01*
G01X1029620Y644194D02*
X1028318Y643284D01*
G01X1028049Y644500D02*
X1028570Y644864D01*
G01X1031238Y653359D02*
X1029620Y644194D01*
G01X1028570Y644864D02*
X1030188Y654029D01*
G01X1031732Y644936D02*
X1033158Y653021D01*
G01X1034374Y653290D02*
X1032948Y645204D01*
G01X1032642Y643631D02*
X1031732Y644936D01*
G01X1032948Y645204D02*
X1033312Y644682D01*
G01X1034616Y643285D02*
X1032642Y643631D01*
G01X1033312Y644682D02*
X1034345Y644501D01*
G01X1033312Y644682D02*
X1034345Y644501D01*
G01X1033312Y644682D02*
X1034345Y644501D01*
G01X1034616Y643285D02*
X1032642Y643631D01*
G01X1032948Y645204D02*
X1033312Y644682D01*
G01X1032642Y643631D02*
X1031732Y644936D01*
G01X1034374Y653290D02*
X1032948Y645204D01*
G01X1031732Y644936D02*
X1033158Y653021D01*
G01X1028570Y644864D02*
X1030188Y654029D01*
G01X1031238Y653359D02*
X1029620Y644194D01*
G01X1027017Y644682D02*
X1028049Y644500D01*
G01D02*
X1028570Y644864D01*
G01X1029620Y644194D02*
X1028318Y643284D01*
G01X1027017Y644682D02*
X1028049Y644500D01*
G01X1028318Y643284D02*
X1026347Y643631D01*
G01X1026652Y645204D02*
X1027017Y644682D01*
G01X1026347Y643631D02*
X1025436Y644935D01*
G01X1028079Y653288D02*
X1026652Y645204D01*
G01X1025436Y644935D02*
X1026863Y653019D01*
G01X1022278Y644865D02*
X1023891Y654029D01*
G01X1024941Y653359D02*
X1023329Y644194D01*
G01X1020722Y644680D02*
X1021754Y644500D01*
G01D02*
X1022278Y644865D01*
G01X1023329Y644194D02*
X1022023Y643285D01*
G01X1020722Y644680D02*
X1021754Y644500D01*
G01X1022023Y643285D02*
X1020052Y643629D01*
G01X1020357Y645204D02*
X1020722Y644680D01*
G01X1020052Y643629D02*
X1019141Y644936D01*
G01X1021789Y653321D02*
X1020357Y645204D01*
G01X1019141Y644936D02*
X1020573Y653052D01*
G01X1015986Y644896D02*
X1017601Y654062D01*
G01X1018651Y653392D02*
X1017036Y644227D01*
G01X1014457Y644674D02*
X1015426Y644504D01*
G01D02*
X1015986Y644896D01*
G01X1017036Y644227D02*
X1015696Y643288D01*
G01X1014457Y644674D02*
X1015426Y644504D01*
G01X1015696Y643288D02*
X1013788Y643623D01*
G01X1014067Y645234D02*
X1014457Y644674D01*
G01X1013788Y643623D02*
X1012851Y644965D01*
G01X1015493Y653319D02*
X1014067Y645234D01*
G01X1012851Y644965D02*
X1014277Y653051D01*
G01X1009669Y644801D02*
X1011307Y654060D01*
G01X1012357Y653390D02*
X1010719Y644131D01*
G01X1008113Y644618D02*
X1009147Y644436D01*
G01D02*
X1009669Y644801D01*
G01X1010719Y644131D02*
X1009416Y643221D01*
G01X1008113Y644618D02*
X1009147Y644436D01*
G01X1009416Y643221D02*
X1007443Y643568D01*
G01X1007749Y645140D02*
X1008113Y644618D01*
G01X1007443Y643568D02*
X1006533Y644871D01*
G01X1009226Y653518D02*
X1007749Y645140D01*
G01X1006533Y644871D02*
X1008010Y653249D01*
G01X1003375Y644800D02*
X1005041Y654256D01*
G01X1006091Y653587D02*
X1004425Y644130D01*
G01X1001818Y644618D02*
X1002853Y644436D01*
G01D02*
X1003375Y644800D01*
G01X1004425Y644130D02*
X1003122Y643221D01*
G01X1001818Y644618D02*
X1002853Y644436D01*
G01X1003122Y643221D02*
X1001148Y643567D01*
G01X1001453Y645140D02*
X1001818Y644618D01*
G01X1001148Y643567D02*
X1000237Y644871D01*
G01X1002939Y653564D02*
X1001453Y645140D01*
G01X1000237Y644871D02*
X1001723Y653296D01*
G01X997085Y644833D02*
X998751Y654306D01*
G01X999802Y653635D02*
X998135Y644163D01*
G01X995528Y644651D02*
X996563Y644469D01*
G01D02*
X997085Y644833D01*
G01X998135Y644163D02*
X996832Y643254D01*
G01X995528Y644651D02*
X996563Y644469D01*
G01X996832Y643254D02*
X994858Y643600D01*
G01X995163Y645173D02*
X995528Y644651D01*
G01X994858Y643600D02*
X993947Y644904D01*
G01X996641Y653548D02*
X995163Y645173D01*
G01X993947Y644904D02*
X995425Y653279D01*
G01X990788Y644833D02*
X992457Y654289D01*
G01X993507Y653619D02*
X991838Y644163D01*
G01X989232Y644650D02*
X990266Y644469D01*
G01D02*
X990788Y644833D01*
G01X991838Y644163D02*
X990535Y643254D01*
G01X989232Y644650D02*
X990266Y644469D01*
G01X990535Y643254D02*
X988562Y643599D01*
G01X988868Y645171D02*
X989232Y644650D01*
G01X988562Y643599D02*
X987652Y644902D01*
G01X990345Y653547D02*
X988868Y645171D01*
G01X987652Y644902D02*
X989129Y653279D01*
G01X984490Y644815D02*
X986158Y654284D01*
G01X987209Y653615D02*
X985540Y644145D01*
G01X982934Y644633D02*
X983968Y644450D01*
G01D02*
X984490Y644815D01*
G01X985540Y644145D02*
X984237Y643235D01*
G01X982934Y644633D02*
X983968Y644450D01*
G01X984237Y643235D02*
X982264Y643583D01*
G01X982571Y645155D02*
X982934Y644633D01*
G01X982264Y643583D02*
X981355Y644884D01*
G01X984071Y653662D02*
X982571Y645155D01*
G01X981355Y644884D02*
X982855Y653392D01*
G01X978192Y644815D02*
X979882Y654396D01*
G01X980933Y653728D02*
X979242Y644146D01*
G01X976638Y644633D02*
X977672Y644451D01*
G01D02*
X978192Y644815D01*
G01X979242Y644146D02*
X977942Y643235D01*
G01X976638Y644633D02*
X977672Y644451D01*
G01X977942Y643235D02*
X975968Y643582D01*
G01X976274Y645154D02*
X976638Y644633D01*
G01X975968Y643582D02*
X975058Y644885D01*
G01X977774Y653665D02*
X976274Y645154D01*
G01X975058Y644885D02*
X976558Y653394D01*
G01X971904Y644849D02*
X973587Y654401D01*
G01X974637Y653731D02*
X972955Y644179D01*
G01X976192Y653914D02*
X975159Y654095D01*
G01D02*
X974637Y653731D01*
G01X973587Y654401D02*
X974890Y655310D01*
G01X976192Y653914D02*
X975159Y654095D01*
G01X974890Y655310D02*
X976859Y654965D01*
G01X976558Y653394D02*
X976192Y653914D01*
G01X976859Y654965D02*
X977774Y653665D01*
G01X982490Y653913D02*
X981456Y654096D01*
G01D02*
X980933Y653728D01*
G01X979882Y654396D02*
X981185Y655312D01*
G01X982490Y653913D02*
X981456Y654096D01*
G01X981185Y655312D02*
X983159Y654963D01*
G01X982855Y653392D02*
X982490Y653913D01*
G01X983159Y654963D02*
X984071Y653662D01*
G01X988765Y653801D02*
X987732Y653982D01*
G01D02*
X987209Y653615D01*
G01X986158Y654284D02*
X987461Y655198D01*
G01X988765Y653801D02*
X987732Y653982D01*
G01X987461Y655198D02*
X989435Y654852D01*
G01X989129Y653279D02*
X988765Y653801D01*
G01X989435Y654852D02*
X990345Y653547D01*
G01X995060Y653801D02*
X994028Y653983D01*
G01D02*
X993507Y653619D01*
G01X992457Y654289D02*
X993759Y655199D01*
G01X995060Y653801D02*
X994028Y653983D01*
G01X993759Y655199D02*
X995730Y654852D01*
G01X995425Y653279D02*
X995060Y653801D01*
G01X995730Y654852D02*
X996641Y653548D01*
G01X1001358Y653820D02*
X1000326Y654000D01*
G01D02*
X999802Y653635D01*
G01X998751Y654306D02*
X1000057Y655215D01*
G01X1001358Y653820D02*
X1000326Y654000D01*
G01X1000057Y655215D02*
X1002028Y654871D01*
G01X1001723Y653296D02*
X1001358Y653820D01*
G01X1002028Y654871D02*
X1002939Y653564D01*
G01X1007619Y653809D02*
X1006651Y653979D01*
G01D02*
X1006091Y653587D01*
G01X1005041Y654256D02*
X1006381Y655195D01*
G01X1007619Y653809D02*
X1006651Y653979D01*
G01X1006381Y655195D02*
X1008289Y654860D01*
G01X1008010Y653249D02*
X1007619Y653809D01*
G01X1008289Y654860D02*
X1009226Y653518D01*
G01X1013913Y653573D02*
X1012879Y653755D01*
G01D02*
X1012357Y653390D01*
G01X1011307Y654060D02*
X1012610Y654971D01*
G01X1013913Y653573D02*
X1012879Y653755D01*
G01X1012610Y654971D02*
X1014583Y654623D01*
G01X1014277Y653051D02*
X1013913Y653573D01*
G01X1014583Y654623D02*
X1015493Y653319D01*
G01X1020208Y653574D02*
X1019173Y653756D01*
G01D02*
X1018651Y653392D01*
G01X1017601Y654062D02*
X1018904Y654971D01*
G01X1020208Y653574D02*
X1019173Y653756D01*
G01X1018904Y654971D02*
X1020878Y654625D01*
G01X1020573Y653052D02*
X1020208Y653574D01*
G01X1020878Y654625D02*
X1021789Y653321D01*
G01X1026498Y653541D02*
X1025463Y653723D01*
G01D02*
X1024941Y653359D01*
G01X1023891Y654029D02*
X1025194Y654938D01*
G01X1026498Y653541D02*
X1025463Y653723D01*
G01X1025194Y654938D02*
X1027168Y654592D01*
G01X1026863Y653019D02*
X1026498Y653541D01*
G01X1027168Y654592D02*
X1028079Y653288D01*
G01X1032794Y653542D02*
X1031760Y653723D01*
G01D02*
X1031238Y653359D01*
G01X1030188Y654029D02*
X1031491Y654938D01*
G01X1032794Y653542D02*
X1031760Y653723D01*
G01X1031491Y654938D02*
X1033464Y654593D01*
G01X1033158Y653021D02*
X1032794Y653542D01*
G01X1033464Y654593D02*
X1034374Y653290D01*
G01X1033464Y654593D02*
X1034374Y653290D01*
G01X1033158Y653021D02*
X1032794Y653542D01*
G01X1030188Y654029D02*
X1031491Y654938D01*
G01D02*
X1033464Y654593D01*
G01X1032794Y653542D02*
X1031760Y653723D01*
G01X1030188Y654029D02*
X1031491Y654938D01*
G01X1031760Y653723D02*
X1031238Y653359D01*
G01X1027168Y654592D02*
X1028079Y653288D01*
G01X1026863Y653019D02*
X1026498Y653541D01*
G01X1023891Y654029D02*
X1025194Y654938D01*
G01D02*
X1027168Y654592D01*
G01X1026498Y653541D02*
X1025463Y653723D01*
G01X1023891Y654029D02*
X1025194Y654938D01*
G01X1025463Y653723D02*
X1024941Y653359D01*
G01X1020878Y654625D02*
X1021789Y653321D01*
G01X1020573Y653052D02*
X1020208Y653574D01*
G01X1017601Y654062D02*
X1018904Y654971D01*
G01D02*
X1020878Y654625D01*
G01X1020208Y653574D02*
X1019173Y653756D01*
G01X1017601Y654062D02*
X1018904Y654971D01*
G01X1019173Y653756D02*
X1018651Y653392D01*
G01X1014583Y654623D02*
X1015493Y653319D01*
G01X1014277Y653051D02*
X1013913Y653573D01*
G01X1011307Y654060D02*
X1012610Y654971D01*
G01D02*
X1014583Y654623D01*
G01X1013913Y653573D02*
X1012879Y653755D01*
G01X1011307Y654060D02*
X1012610Y654971D01*
G01X1012879Y653755D02*
X1012357Y653390D01*
G01X1008289Y654860D02*
X1009226Y653518D01*
G01X1008010Y653249D02*
X1007619Y653809D01*
G01X1005041Y654256D02*
X1006381Y655195D01*
G01D02*
X1008289Y654860D01*
G01X1007619Y653809D02*
X1006651Y653979D01*
G01X1005041Y654256D02*
X1006381Y655195D01*
G01X1006651Y653979D02*
X1006091Y653587D01*
G01X1002028Y654871D02*
X1002939Y653564D01*
G01X1001723Y653296D02*
X1001358Y653820D01*
G01X998751Y654306D02*
X1000057Y655215D01*
G01D02*
X1002028Y654871D01*
G01X1001358Y653820D02*
X1000326Y654000D01*
G01X998751Y654306D02*
X1000057Y655215D01*
G01X1000326Y654000D02*
X999802Y653635D01*
G01X995730Y654852D02*
X996641Y653548D01*
G01X995425Y653279D02*
X995060Y653801D01*
G01X992457Y654289D02*
X993759Y655199D01*
G01D02*
X995730Y654852D01*
G01X995060Y653801D02*
X994028Y653983D01*
G01X992457Y654289D02*
X993759Y655199D01*
G01X994028Y653983D02*
X993507Y653619D01*
G01X989435Y654852D02*
X990345Y653547D01*
G01X989129Y653279D02*
X988765Y653801D01*
G01X986158Y654284D02*
X987461Y655198D01*
G01D02*
X989435Y654852D01*
G01X988765Y653801D02*
X987732Y653982D01*
G01X986158Y654284D02*
X987461Y655198D01*
G01X987732Y653982D02*
X987209Y653615D01*
G01X983159Y654963D02*
X984071Y653662D01*
G01X982855Y653392D02*
X982490Y653913D01*
G01X979882Y654396D02*
X981185Y655312D01*
G01D02*
X983159Y654963D01*
G01X982490Y653913D02*
X981456Y654096D01*
G01X979882Y654396D02*
X981185Y655312D01*
G01X981456Y654096D02*
X980933Y653728D01*
G01X976859Y654965D02*
X977774Y653665D01*
G01X976558Y653394D02*
X976192Y653914D01*
G01X973587Y654401D02*
X974890Y655310D01*
G01D02*
X976859Y654965D01*
G01X976192Y653914D02*
X975159Y654095D01*
G01X973587Y654401D02*
X974890Y655310D01*
G01X975159Y654095D02*
X974637Y653731D01*
G01X1035919Y644199D02*
X1034616Y643285D01*
G01X1035919Y644199D02*
X1034616Y643285D01*
G01X1034345Y644501D02*
X1034868Y644868D01*
G01X1037536Y653377D02*
X1035919Y644199D01*
G01X1034868Y644868D02*
X1036486Y654047D01*
G01X1038009Y644838D02*
X1039455Y653037D01*
G01X1040671Y653308D02*
X1039225Y645108D01*
G01X1038921Y643537D02*
X1038009Y644838D01*
G01X1039225Y645108D02*
X1039590Y644587D01*
G01X1042198Y644104D02*
X1040895Y643188D01*
G01D02*
X1038921Y643537D01*
G01X1039590Y644587D02*
X1040624Y644404D01*
G01X1042198Y644104D02*
X1040895Y643188D01*
G01X1040624Y644404D02*
X1041147Y644772D01*
G01X1043834Y653377D02*
X1042198Y644104D01*
G01X1041147Y644772D02*
X1042784Y654046D01*
G01X1044320Y644915D02*
X1045752Y653038D01*
G01X1046968Y653307D02*
X1045536Y645186D01*
G01X1045235Y643615D02*
X1044320Y644915D01*
G01X1045536Y645186D02*
X1045902Y644666D01*
G01X1048507Y644179D02*
X1047204Y643270D01*
G01D02*
X1045235Y643615D01*
G01X1045902Y644666D02*
X1046935Y644485D01*
G01X1048507Y644179D02*
X1047204Y643270D01*
G01X1046935Y644485D02*
X1047457Y644849D01*
G01X1050122Y653343D02*
X1048507Y644179D01*
G01X1047457Y644849D02*
X1049071Y654013D01*
G01X1050620Y644937D02*
X1052043Y653005D01*
G01X1053259Y653274D02*
X1051836Y645206D01*
G01X1051532Y643633D02*
X1050620Y644937D01*
G01X1051836Y645206D02*
X1052201Y644684D01*
G01X1054807Y644198D02*
X1053504Y643288D01*
G01D02*
X1051532Y643633D01*
G01X1052201Y644684D02*
X1053234Y644503D01*
G01X1054807Y644198D02*
X1053504Y643288D01*
G01X1053234Y644503D02*
X1053756Y644868D01*
G01X1056417Y653344D02*
X1054807Y644198D01*
G01X1053756Y644868D02*
X1055367Y654014D01*
G01X1056915Y644940D02*
X1058339Y653006D01*
G01X1059555Y653275D02*
X1058131Y645208D01*
G01X1057824Y643636D02*
X1056915Y644940D01*
G01X1058131Y645208D02*
X1058496Y644685D01*
G01X1061102Y644202D02*
X1059798Y643288D01*
G01D02*
X1057824Y643636D01*
G01X1058496Y644685D02*
X1059528Y644504D01*
G01X1061102Y644202D02*
X1059798Y643288D01*
G01X1059528Y644504D02*
X1060052Y644871D01*
G01X1062718Y653364D02*
X1061102Y644202D01*
G01X1060052Y644871D02*
X1061668Y654033D01*
G01X1063205Y644905D02*
X1064638Y653020D01*
G01X1065854Y653290D02*
X1064421Y645174D01*
G01X1064116Y643601D02*
X1063205Y644905D01*
G01X1064421Y645174D02*
X1064786Y644652D01*
G01X1067391Y644166D02*
X1066090Y643254D01*
G01D02*
X1064116Y643601D01*
G01X1064786Y644652D02*
X1065820Y644470D01*
G01X1067391Y644166D02*
X1066090Y643254D01*
G01X1065820Y644470D02*
X1066341Y644835D01*
G01X1069006Y653331D02*
X1067391Y644166D01*
G01X1066341Y644835D02*
X1067956Y654001D01*
G01X1069496Y644875D02*
X1070928Y652991D01*
G01X1072144Y653260D02*
X1070712Y645143D01*
G01X1070407Y643568D02*
X1069496Y644875D01*
G01X1070712Y645143D02*
X1071077Y644619D01*
G01X1073684Y644133D02*
X1072378Y643224D01*
G01D02*
X1070407Y643568D01*
G01X1071077Y644619D02*
X1072109Y644439D01*
G01X1073684Y644133D02*
X1072378Y643224D01*
G01X1072109Y644439D02*
X1072633Y644804D01*
G01X1075296Y653298D02*
X1073684Y644133D01*
G01X1072633Y644804D02*
X1074246Y653968D01*
G01X1075791Y644874D02*
X1077218Y652958D01*
G01X1078434Y653227D02*
X1077007Y645143D01*
G01X1076702Y643570D02*
X1075791Y644874D01*
G01X1077007Y645143D02*
X1077372Y644621D01*
G01X1079975Y644133D02*
X1078673Y643223D01*
G01D02*
X1076702Y643570D01*
G01X1077372Y644621D02*
X1078404Y644439D01*
G01X1079975Y644133D02*
X1078673Y643223D01*
G01X1078404Y644439D02*
X1078925Y644803D01*
G01X1081593Y653298D02*
X1079975Y644133D01*
G01X1078925Y644803D02*
X1080543Y653968D01*
G01X1082087Y644875D02*
X1083513Y652960D01*
G01X1084729Y653229D02*
X1083303Y645143D01*
G01X1082997Y643570D02*
X1082087Y644875D01*
G01X1083303Y645143D02*
X1083667Y644621D01*
G01X1086274Y644138D02*
X1084971Y643224D01*
G01D02*
X1082997Y643570D01*
G01X1083667Y644621D02*
X1084700Y644440D01*
G01X1086274Y644138D02*
X1084971Y643224D01*
G01X1084700Y644440D02*
X1085223Y644807D01*
G01X1087891Y653316D02*
X1086274Y644138D01*
G01X1085223Y644807D02*
X1086841Y653986D01*
G01X1088378Y644857D02*
X1089810Y652976D01*
G01X1091026Y653247D02*
X1089594Y645127D01*
G01X1089290Y643556D02*
X1088378Y644857D01*
G01X1089594Y645127D02*
X1089959Y644606D01*
G01X1092568Y644123D02*
X1091264Y643207D01*
G01D02*
X1089290Y643556D01*
G01X1089959Y644606D02*
X1090993Y644423D01*
G01X1092568Y644123D02*
X1091264Y643207D01*
G01X1090993Y644423D02*
X1091517Y644791D01*
G01X1094189Y653316D02*
X1092568Y644123D01*
G01X1091517Y644791D02*
X1093139Y653985D01*
G01X1094675Y644854D02*
X1096107Y652977D01*
G01X1095590Y643554D02*
X1094675Y644854D01*
G01X1095590Y643554D02*
X1094675Y644854D01*
G01D02*
X1096107Y652977D01*
G01X1091517Y644791D02*
X1093139Y653985D01*
G01X1094189Y653316D02*
X1092568Y644123D01*
G01X1089959Y644606D02*
X1090993Y644423D01*
G01D02*
X1091517Y644791D01*
G01X1092568Y644123D02*
X1091264Y643207D01*
G01X1089959Y644606D02*
X1090993Y644423D01*
G01X1091264Y643207D02*
X1089290Y643556D01*
G01X1089594Y645127D02*
X1089959Y644606D01*
G01X1089290Y643556D02*
X1088378Y644857D01*
G01X1091026Y653247D02*
X1089594Y645127D01*
G01X1088378Y644857D02*
X1089810Y652976D01*
G01X1085223Y644807D02*
X1086841Y653986D01*
G01X1087891Y653316D02*
X1086274Y644138D01*
G01X1083667Y644621D02*
X1084700Y644440D01*
G01D02*
X1085223Y644807D01*
G01X1086274Y644138D02*
X1084971Y643224D01*
G01X1083667Y644621D02*
X1084700Y644440D01*
G01X1084971Y643224D02*
X1082997Y643570D01*
G01X1083303Y645143D02*
X1083667Y644621D01*
G01X1082997Y643570D02*
X1082087Y644875D01*
G01X1084729Y653229D02*
X1083303Y645143D01*
G01X1082087Y644875D02*
X1083513Y652960D01*
G01X1078925Y644803D02*
X1080543Y653968D01*
G01X1081593Y653298D02*
X1079975Y644133D01*
G01X1077372Y644621D02*
X1078404Y644439D01*
G01D02*
X1078925Y644803D01*
G01X1079975Y644133D02*
X1078673Y643223D01*
G01X1077372Y644621D02*
X1078404Y644439D01*
G01X1078673Y643223D02*
X1076702Y643570D01*
G01X1077007Y645143D02*
X1077372Y644621D01*
G01X1076702Y643570D02*
X1075791Y644874D01*
G01X1078434Y653227D02*
X1077007Y645143D01*
G01X1075791Y644874D02*
X1077218Y652958D01*
G01X1072633Y644804D02*
X1074246Y653968D01*
G01X1075296Y653298D02*
X1073684Y644133D01*
G01X1071077Y644619D02*
X1072109Y644439D01*
G01D02*
X1072633Y644804D01*
G01X1073684Y644133D02*
X1072378Y643224D01*
G01X1071077Y644619D02*
X1072109Y644439D01*
G01X1072378Y643224D02*
X1070407Y643568D01*
G01X1070712Y645143D02*
X1071077Y644619D01*
G01X1070407Y643568D02*
X1069496Y644875D01*
G01X1072144Y653260D02*
X1070712Y645143D01*
G01X1069496Y644875D02*
X1070928Y652991D01*
G01X1066341Y644835D02*
X1067956Y654001D01*
G01X1069006Y653331D02*
X1067391Y644166D01*
G01X1064786Y644652D02*
X1065820Y644470D01*
G01D02*
X1066341Y644835D01*
G01X1067391Y644166D02*
X1066090Y643254D01*
G01X1064786Y644652D02*
X1065820Y644470D01*
G01X1066090Y643254D02*
X1064116Y643601D01*
G01X1064421Y645174D02*
X1064786Y644652D01*
G01X1064116Y643601D02*
X1063205Y644905D01*
G01X1065854Y653290D02*
X1064421Y645174D01*
G01X1063205Y644905D02*
X1064638Y653020D01*
G01X1060052Y644871D02*
X1061668Y654033D01*
G01X1062718Y653364D02*
X1061102Y644202D01*
G01X1058496Y644685D02*
X1059528Y644504D01*
G01D02*
X1060052Y644871D01*
G01X1061102Y644202D02*
X1059798Y643288D01*
G01X1058496Y644685D02*
X1059528Y644504D01*
G01X1059798Y643288D02*
X1057824Y643636D01*
G01X1058131Y645208D02*
X1058496Y644685D01*
G01X1057824Y643636D02*
X1056915Y644940D01*
G01X1059555Y653275D02*
X1058131Y645208D01*
G01X1056915Y644940D02*
X1058339Y653006D01*
G01X1053756Y644868D02*
X1055367Y654014D01*
G01X1056417Y653344D02*
X1054807Y644198D01*
G01X1052201Y644684D02*
X1053234Y644503D01*
G01D02*
X1053756Y644868D01*
G01X1054807Y644198D02*
X1053504Y643288D01*
G01X1052201Y644684D02*
X1053234Y644503D01*
G01X1053504Y643288D02*
X1051532Y643633D01*
G01X1051836Y645206D02*
X1052201Y644684D01*
G01X1051532Y643633D02*
X1050620Y644937D01*
G01X1053259Y653274D02*
X1051836Y645206D01*
G01X1050620Y644937D02*
X1052043Y653005D01*
G01X1047457Y644849D02*
X1049071Y654013D01*
G01X1050122Y653343D02*
X1048507Y644179D01*
G01X1045902Y644666D02*
X1046935Y644485D01*
G01D02*
X1047457Y644849D01*
G01X1048507Y644179D02*
X1047204Y643270D01*
G01X1045902Y644666D02*
X1046935Y644485D01*
G01X1047204Y643270D02*
X1045235Y643615D01*
G01X1045536Y645186D02*
X1045902Y644666D01*
G01X1045235Y643615D02*
X1044320Y644915D01*
G01X1046968Y653307D02*
X1045536Y645186D01*
G01X1044320Y644915D02*
X1045752Y653038D01*
G01X1041147Y644772D02*
X1042784Y654046D01*
G01X1043834Y653377D02*
X1042198Y644104D01*
G01X1039590Y644587D02*
X1040624Y644404D01*
G01D02*
X1041147Y644772D01*
G01X1042198Y644104D02*
X1040895Y643188D01*
G01X1039590Y644587D02*
X1040624Y644404D01*
G01X1040895Y643188D02*
X1038921Y643537D01*
G01X1039225Y645108D02*
X1039590Y644587D01*
G01X1038921Y643537D02*
X1038009Y644838D01*
G01X1040671Y653308D02*
X1039225Y645108D01*
G01X1038009Y644838D02*
X1039455Y653037D01*
G01X1034868Y644868D02*
X1036486Y654047D01*
G01X1037536Y653377D02*
X1035919Y644199D01*
G01X1034345Y644501D02*
X1034868Y644868D01*
G01X1035919Y644199D02*
X1034616Y643285D01*
G01X1039092Y653559D02*
X1038058Y653742D01*
G01D02*
X1037536Y653377D01*
G01X1036486Y654047D02*
X1037789Y654957D01*
G01X1039092Y653559D02*
X1038058Y653742D01*
G01X1037789Y654957D02*
X1039762Y654609D01*
G01X1039455Y653037D02*
X1039092Y653559D01*
G01X1039762Y654609D02*
X1040671Y653308D01*
G01X1045388Y653559D02*
X1044354Y653741D01*
G01D02*
X1043834Y653377D01*
G01X1042784Y654046D02*
X1044084Y654957D01*
G01X1045388Y653559D02*
X1044354Y653741D01*
G01X1044084Y654957D02*
X1046058Y654610D01*
G01X1045752Y653038D02*
X1045388Y653559D01*
G01X1046058Y654610D02*
X1046968Y653307D01*
G01X1051679Y653526D02*
X1050645Y653708D01*
G01D02*
X1050122Y653343D01*
G01X1049071Y654013D02*
X1050375Y654923D01*
G01X1051679Y653526D02*
X1050645Y653708D01*
G01X1050375Y654923D02*
X1052349Y654577D01*
G01X1052043Y653005D02*
X1051679Y653526D01*
G01X1052349Y654577D02*
X1053259Y653274D01*
G01X1057975Y653527D02*
X1056940Y653709D01*
G01D02*
X1056417Y653344D01*
G01X1055367Y654014D02*
X1056671Y654924D01*
G01X1057975Y653527D02*
X1056940Y653709D01*
G01X1056671Y654924D02*
X1058645Y654578D01*
G01X1058339Y653006D02*
X1057975Y653527D01*
G01X1058645Y654578D02*
X1059555Y653275D01*
G01X1064271Y653544D02*
X1063237Y653727D01*
G01D02*
X1062718Y653364D01*
G01X1061668Y654033D02*
X1062968Y654943D01*
G01X1064271Y653544D02*
X1063237Y653727D01*
G01X1062968Y654943D02*
X1064941Y654594D01*
G01X1064638Y653020D02*
X1064271Y653544D01*
G01X1064941Y654594D02*
X1065854Y653290D01*
G01X1070563Y653513D02*
X1069528Y653695D01*
G01D02*
X1069006Y653331D01*
G01X1067956Y654001D02*
X1069259Y654910D01*
G01X1070563Y653513D02*
X1069528Y653695D01*
G01X1069259Y654910D02*
X1071233Y654564D01*
G01X1070928Y652991D02*
X1070563Y653513D01*
G01X1071233Y654564D02*
X1072144Y653260D01*
G01X1076853Y653480D02*
X1075818Y653662D01*
G01D02*
X1075296Y653298D01*
G01X1074246Y653968D02*
X1075549Y654877D01*
G01X1076853Y653480D02*
X1075818Y653662D01*
G01X1075549Y654877D02*
X1077523Y654531D01*
G01X1077218Y652958D02*
X1076853Y653480D01*
G01X1077523Y654531D02*
X1078434Y653227D01*
G01X1083149Y653481D02*
X1082115Y653662D01*
G01D02*
X1081593Y653298D01*
G01X1080543Y653968D02*
X1081846Y654877D01*
G01X1083149Y653481D02*
X1082115Y653662D01*
G01X1081846Y654877D02*
X1083819Y654532D01*
G01X1083513Y652960D02*
X1083149Y653481D01*
G01X1083819Y654532D02*
X1084729Y653229D01*
G01X1089447Y653498D02*
X1088413Y653681D01*
G01D02*
X1087891Y653316D01*
G01X1086841Y653986D02*
X1088144Y654896D01*
G01X1089447Y653498D02*
X1088413Y653681D01*
G01X1088144Y654896D02*
X1090117Y654548D01*
G01X1089810Y652976D02*
X1089447Y653498D01*
G01X1090117Y654548D02*
X1091026Y653247D01*
G01X1095743Y653498D02*
X1094709Y653680D01*
G01D02*
X1094189Y653316D01*
G01X1093139Y653985D02*
X1094439Y654896D01*
G01X1095743Y653498D02*
X1094709Y653680D01*
G01X1094439Y654896D02*
X1096413Y654549D01*
G01X1093139Y653985D02*
X1094439Y654896D01*
G01D02*
X1096413Y654549D01*
G01X1095743Y653498D02*
X1094709Y653680D01*
G01X1093139Y653985D02*
X1094439Y654896D01*
G01X1094709Y653680D02*
X1094189Y653316D01*
G01X1090117Y654548D02*
X1091026Y653247D01*
G01X1089810Y652976D02*
X1089447Y653498D01*
G01X1086841Y653986D02*
X1088144Y654896D01*
G01D02*
X1090117Y654548D01*
G01X1089447Y653498D02*
X1088413Y653681D01*
G01X1086841Y653986D02*
X1088144Y654896D01*
G01X1088413Y653681D02*
X1087891Y653316D01*
G01X1083819Y654532D02*
X1084729Y653229D01*
G01X1083513Y652960D02*
X1083149Y653481D01*
G01X1080543Y653968D02*
X1081846Y654877D01*
G01D02*
X1083819Y654532D01*
G01X1083149Y653481D02*
X1082115Y653662D01*
G01X1080543Y653968D02*
X1081846Y654877D01*
G01X1082115Y653662D02*
X1081593Y653298D01*
G01X1077523Y654531D02*
X1078434Y653227D01*
G01X1077218Y652958D02*
X1076853Y653480D01*
G01X1074246Y653968D02*
X1075549Y654877D01*
G01D02*
X1077523Y654531D01*
G01X1076853Y653480D02*
X1075818Y653662D01*
G01X1074246Y653968D02*
X1075549Y654877D01*
G01X1075818Y653662D02*
X1075296Y653298D01*
G01X1071233Y654564D02*
X1072144Y653260D01*
G01X1070928Y652991D02*
X1070563Y653513D01*
G01X1067956Y654001D02*
X1069259Y654910D01*
G01D02*
X1071233Y654564D01*
G01X1070563Y653513D02*
X1069528Y653695D01*
G01X1067956Y654001D02*
X1069259Y654910D01*
G01X1069528Y653695D02*
X1069006Y653331D01*
G01X1064941Y654594D02*
X1065854Y653290D01*
G01X1064638Y653020D02*
X1064271Y653544D01*
G01X1061668Y654033D02*
X1062968Y654943D01*
G01D02*
X1064941Y654594D01*
G01X1064271Y653544D02*
X1063237Y653727D01*
G01X1061668Y654033D02*
X1062968Y654943D01*
G01X1063237Y653727D02*
X1062718Y653364D01*
G01X1058645Y654578D02*
X1059555Y653275D01*
G01X1058339Y653006D02*
X1057975Y653527D01*
G01X1055367Y654014D02*
X1056671Y654924D01*
G01D02*
X1058645Y654578D01*
G01X1057975Y653527D02*
X1056940Y653709D01*
G01X1055367Y654014D02*
X1056671Y654924D01*
G01X1056940Y653709D02*
X1056417Y653344D01*
G01X1052349Y654577D02*
X1053259Y653274D01*
G01X1052043Y653005D02*
X1051679Y653526D01*
G01X1049071Y654013D02*
X1050375Y654923D01*
G01D02*
X1052349Y654577D01*
G01X1051679Y653526D02*
X1050645Y653708D01*
G01X1049071Y654013D02*
X1050375Y654923D01*
G01X1050645Y653708D02*
X1050122Y653343D01*
G01X1046058Y654610D02*
X1046968Y653307D01*
G01X1045752Y653038D02*
X1045388Y653559D01*
G01X1042784Y654046D02*
X1044084Y654957D01*
G01D02*
X1046058Y654610D01*
G01X1045388Y653559D02*
X1044354Y653741D01*
G01X1042784Y654046D02*
X1044084Y654957D01*
G01X1044354Y653741D02*
X1043834Y653377D01*
G01X1039762Y654609D02*
X1040671Y653308D01*
G01X1039455Y653037D02*
X1039092Y653559D01*
G01X1036486Y654047D02*
X1037789Y654957D01*
G01D02*
X1039762Y654609D01*
G01X1039092Y653559D02*
X1038058Y653742D01*
G01X1036486Y654047D02*
X1037789Y654957D01*
G01X1038058Y653742D02*
X1037536Y653377D01*
G01X1109035Y-47400D02*
G02Y-49950I0J-1275D01*
G01Y-46250D02*
G02Y-51100I0J-2425D01*
G01Y-46250D02*
G02Y-51100I0J-2425D01*
G01Y-47400D02*
G02Y-49950I0J-1275D01*
G01X1097323Y653246D02*
X1095891Y645125D01*
G01D02*
X1096257Y644605D01*
G01X1098862Y644118D02*
X1097559Y643209D01*
G01D02*
X1095590Y643554D01*
G01X1096257Y644605D02*
X1097290Y644424D01*
G01X1098862Y644118D02*
X1097559Y643209D01*
G01X1097290Y644424D02*
X1097812Y644788D01*
G01X1100477Y653282D02*
X1098862Y644118D01*
G01X1097812Y644788D02*
X1099426Y653952D01*
G01X1100978Y644893D02*
X1102398Y652944D01*
G01X1103614Y653213D02*
X1102194Y645162D01*
G01X1101890Y643589D02*
X1100978Y644893D01*
G01X1102194Y645162D02*
X1102559Y644640D01*
G01X1105165Y644154D02*
X1103862Y643244D01*
G01D02*
X1101890Y643589D01*
G01X1102559Y644640D02*
X1103592Y644459D01*
G01X1105165Y644154D02*
X1103862Y643244D01*
G01X1103592Y644459D02*
X1104114Y644824D01*
G01X1106772Y653283D02*
X1105165Y644154D01*
G01X1104114Y644824D02*
X1105722Y653953D01*
G01X1107270Y644879D02*
X1108694Y652945D01*
G01X1109910Y653214D02*
X1108486Y645147D01*
G01X1108179Y643575D02*
X1107270Y644879D01*
G01X1108486Y645147D02*
X1108851Y644624D01*
G01X1111457Y644141D02*
X1110153Y643227D01*
G01D02*
X1108179Y643575D01*
G01X1108851Y644624D02*
X1109883Y644443D01*
G01X1111457Y644141D02*
X1110153Y643227D01*
G01X1109883Y644443D02*
X1110407Y644810D01*
G01X1113073Y653303D02*
X1111457Y644141D01*
G01X1110407Y644810D02*
X1112023Y653972D01*
G01X1113577Y644940D02*
X1114993Y652959D01*
G01X1116209Y653229D02*
X1114794Y645210D01*
G01X1114488Y643637D02*
X1113577Y644940D01*
G01X1114794Y645210D02*
X1115159Y644687D01*
G01X1117764Y644202D02*
X1116462Y643290D01*
G01D02*
X1114488Y643637D01*
G01X1115159Y644687D02*
X1116192Y644506D01*
G01X1117764Y644202D02*
X1116462Y643290D01*
G01X1116192Y644506D02*
X1116714Y644871D01*
G01X1119380Y653364D02*
X1117764Y644202D01*
G01X1116714Y644871D02*
X1118330Y654033D01*
G01X1119887Y645019D02*
X1121300Y653020D01*
G01X1122516Y653290D02*
X1121103Y645288D01*
G01X1120798Y643715D02*
X1119887Y645019D01*
G01X1121103Y645288D02*
X1121468Y644766D01*
G01X1124074Y644280D02*
X1122772Y643368D01*
G01D02*
X1120798Y643715D01*
G01X1121468Y644766D02*
X1122502Y644584D01*
G01X1124074Y644280D02*
X1122772Y643368D01*
G01X1122502Y644584D02*
X1123023Y644949D01*
G01X1125687Y653425D02*
X1124074Y644280D01*
G01X1123023Y644949D02*
X1124637Y654094D01*
G01X1126174Y644966D02*
X1127607Y653081D01*
G01X1128823Y653351D02*
X1127390Y645235D01*
G01X1127085Y643662D02*
X1126174Y644966D01*
G01X1127390Y645235D02*
X1127755Y644713D01*
G01X1130361Y644227D02*
X1129059Y643315D01*
G01D02*
X1127085Y643662D01*
G01X1127755Y644713D02*
X1128789Y644531D01*
G01X1130361Y644227D02*
X1129059Y643315D01*
G01X1128789Y644531D02*
X1129310Y644896D01*
G01X1131994Y653486D02*
X1130361Y644227D01*
G01X1129310Y644896D02*
X1130944Y654155D01*
G01X1132481Y645027D02*
X1133914Y653142D01*
G01X1135130Y653412D02*
X1133697Y645296D01*
G01X1133392Y643723D02*
X1132481Y645027D01*
G01X1133697Y645296D02*
X1134062Y644774D01*
G01X1136667Y644287D02*
X1135366Y643376D01*
G01D02*
X1133392Y643723D01*
G01X1134062Y644774D02*
X1135096Y644592D01*
G01X1136667Y644287D02*
X1135366Y643376D01*
G01X1135096Y644592D02*
X1135617Y644957D01*
G01X1138320Y653633D02*
X1136667Y644287D01*
G01X1135617Y644957D02*
X1137270Y654303D01*
G01X1138767Y644922D02*
X1140243Y653296D01*
G01X1141459Y653564D02*
X1139983Y645191D01*
G01X1139704Y643580D02*
X1138767Y644922D01*
G01X1139983Y645191D02*
X1140374Y644631D01*
G01X1142952Y644184D02*
X1141612Y643245D01*
G01D02*
X1139704Y643580D01*
G01X1140374Y644631D02*
X1141342Y644461D01*
G01X1142952Y644184D02*
X1141612Y643245D01*
G01X1141342Y644461D02*
X1141902Y644853D01*
G01X1144618Y653640D02*
X1142952Y644184D01*
G01X1141902Y644853D02*
X1143568Y654310D01*
G01X1145054Y644876D02*
X1146540Y653300D01*
G01X1147756Y653569D02*
X1146270Y645144D01*
G01X1145965Y643569D02*
X1145054Y644876D01*
G01X1146270Y645144D02*
X1146635Y644620D01*
G01X1149242Y644134D02*
X1147936Y643225D01*
G01D02*
X1145965Y643569D01*
G01X1146635Y644620D02*
X1147667Y644440D01*
G01X1149242Y644134D02*
X1147936Y643225D01*
G01X1147667Y644440D02*
X1148191Y644805D01*
G01X1150908Y653607D02*
X1149242Y644134D01*
G01X1148191Y644805D02*
X1149858Y654277D01*
G01X1151352Y644892D02*
X1152830Y653267D01*
G01X1154046Y653536D02*
X1152568Y645161D01*
G01X1152263Y643588D02*
X1151352Y644892D01*
G01X1152568Y645161D02*
X1152933Y644639D01*
G01X1155536Y644151D02*
X1154234Y643241D01*
G01D02*
X1152263Y643588D01*
G01X1152933Y644639D02*
X1153965Y644457D01*
G01X1155536Y644151D02*
X1154234Y643241D01*
G01X1153965Y644457D02*
X1154486Y644821D01*
G01X1157205Y653607D02*
X1155536Y644151D01*
G01X1154486Y644821D02*
X1156155Y654277D01*
G01X1154486Y644821D02*
X1156155Y654277D01*
G01X1157205Y653607D02*
X1155536Y644151D01*
G01X1152933Y644639D02*
X1153965Y644457D01*
G01D02*
X1154486Y644821D01*
G01X1155536Y644151D02*
X1154234Y643241D01*
G01X1152933Y644639D02*
X1153965Y644457D01*
G01X1154234Y643241D02*
X1152263Y643588D01*
G01X1152568Y645161D02*
X1152933Y644639D01*
G01X1152263Y643588D02*
X1151352Y644892D01*
G01X1154046Y653536D02*
X1152568Y645161D01*
G01X1151352Y644892D02*
X1152830Y653267D01*
G01X1148191Y644805D02*
X1149858Y654277D01*
G01X1150908Y653607D02*
X1149242Y644134D01*
G01X1146635Y644620D02*
X1147667Y644440D01*
G01D02*
X1148191Y644805D01*
G01X1149242Y644134D02*
X1147936Y643225D01*
G01X1146635Y644620D02*
X1147667Y644440D01*
G01X1147936Y643225D02*
X1145965Y643569D01*
G01X1146270Y645144D02*
X1146635Y644620D01*
G01X1145965Y643569D02*
X1145054Y644876D01*
G01X1147756Y653569D02*
X1146270Y645144D01*
G01X1145054Y644876D02*
X1146540Y653300D01*
G01X1141902Y644853D02*
X1143568Y654310D01*
G01X1144618Y653640D02*
X1142952Y644184D01*
G01X1140374Y644631D02*
X1141342Y644461D01*
G01D02*
X1141902Y644853D01*
G01X1142952Y644184D02*
X1141612Y643245D01*
G01X1140374Y644631D02*
X1141342Y644461D01*
G01X1141612Y643245D02*
X1139704Y643580D01*
G01X1139983Y645191D02*
X1140374Y644631D01*
G01X1139704Y643580D02*
X1138767Y644922D01*
G01X1141459Y653564D02*
X1139983Y645191D01*
G01X1138767Y644922D02*
X1140243Y653296D01*
G01X1135617Y644957D02*
X1137270Y654303D01*
G01X1138320Y653633D02*
X1136667Y644287D01*
G01X1134062Y644774D02*
X1135096Y644592D01*
G01D02*
X1135617Y644957D01*
G01X1136667Y644287D02*
X1135366Y643376D01*
G01X1134062Y644774D02*
X1135096Y644592D01*
G01X1135366Y643376D02*
X1133392Y643723D01*
G01X1133697Y645296D02*
X1134062Y644774D01*
G01X1133392Y643723D02*
X1132481Y645027D01*
G01X1135130Y653412D02*
X1133697Y645296D01*
G01X1132481Y645027D02*
X1133914Y653142D01*
G01X1129310Y644896D02*
X1130944Y654155D01*
G01X1131994Y653486D02*
X1130361Y644227D01*
G01X1127755Y644713D02*
X1128789Y644531D01*
G01D02*
X1129310Y644896D01*
G01X1130361Y644227D02*
X1129059Y643315D01*
G01X1127755Y644713D02*
X1128789Y644531D01*
G01X1129059Y643315D02*
X1127085Y643662D01*
G01X1127390Y645235D02*
X1127755Y644713D01*
G01X1127085Y643662D02*
X1126174Y644966D01*
G01X1128823Y653351D02*
X1127390Y645235D01*
G01X1126174Y644966D02*
X1127607Y653081D01*
G01X1123023Y644949D02*
X1124637Y654094D01*
G01X1125687Y653425D02*
X1124074Y644280D01*
G01X1121468Y644766D02*
X1122502Y644584D01*
G01D02*
X1123023Y644949D01*
G01X1124074Y644280D02*
X1122772Y643368D01*
G01X1121468Y644766D02*
X1122502Y644584D01*
G01X1122772Y643368D02*
X1120798Y643715D01*
G01X1121103Y645288D02*
X1121468Y644766D01*
G01X1120798Y643715D02*
X1119887Y645019D01*
G01X1122516Y653290D02*
X1121103Y645288D01*
G01X1119887Y645019D02*
X1121300Y653020D01*
G01X1116714Y644871D02*
X1118330Y654033D01*
G01X1119380Y653364D02*
X1117764Y644202D01*
G01X1115159Y644687D02*
X1116192Y644506D01*
G01D02*
X1116714Y644871D01*
G01X1117764Y644202D02*
X1116462Y643290D01*
G01X1115159Y644687D02*
X1116192Y644506D01*
G01X1116462Y643290D02*
X1114488Y643637D01*
G01X1114794Y645210D02*
X1115159Y644687D01*
G01X1114488Y643637D02*
X1113577Y644940D01*
G01X1116209Y653229D02*
X1114794Y645210D01*
G01X1113577Y644940D02*
X1114993Y652959D01*
G01X1110407Y644810D02*
X1112023Y653972D01*
G01X1113073Y653303D02*
X1111457Y644141D01*
G01X1108851Y644624D02*
X1109883Y644443D01*
G01D02*
X1110407Y644810D01*
G01X1111457Y644141D02*
X1110153Y643227D01*
G01X1108851Y644624D02*
X1109883Y644443D01*
G01X1110153Y643227D02*
X1108179Y643575D01*
G01X1108486Y645147D02*
X1108851Y644624D01*
G01X1108179Y643575D02*
X1107270Y644879D01*
G01X1109910Y653214D02*
X1108486Y645147D01*
G01X1107270Y644879D02*
X1108694Y652945D01*
G01X1104114Y644824D02*
X1105722Y653953D01*
G01X1106772Y653283D02*
X1105165Y644154D01*
G01X1102559Y644640D02*
X1103592Y644459D01*
G01D02*
X1104114Y644824D01*
G01X1105165Y644154D02*
X1103862Y643244D01*
G01X1102559Y644640D02*
X1103592Y644459D01*
G01X1103862Y643244D02*
X1101890Y643589D01*
G01X1102194Y645162D02*
X1102559Y644640D01*
G01X1101890Y643589D02*
X1100978Y644893D01*
G01X1103614Y653213D02*
X1102194Y645162D01*
G01X1100978Y644893D02*
X1102398Y652944D01*
G01X1097812Y644788D02*
X1099426Y653952D01*
G01X1100477Y653282D02*
X1098862Y644118D01*
G01X1096257Y644605D02*
X1097290Y644424D01*
G01D02*
X1097812Y644788D01*
G01X1098862Y644118D02*
X1097559Y643209D01*
G01X1096257Y644605D02*
X1097290Y644424D01*
G01X1097559Y643209D02*
X1095590Y643554D01*
G01X1095891Y645125D02*
X1096257Y644605D01*
G01X1097323Y653246D02*
X1095891Y645125D01*
G01X1096107Y652977D02*
X1095743Y653498D01*
G01X1096413Y654549D02*
X1097323Y653246D01*
G01X1102034Y653465D02*
X1101000Y653647D01*
G01D02*
X1100477Y653282D01*
G01X1099426Y653952D02*
X1100730Y654862D01*
G01X1102034Y653465D02*
X1101000Y653647D01*
G01X1100730Y654862D02*
X1102704Y654516D01*
G01X1102398Y652944D02*
X1102034Y653465D01*
G01X1102704Y654516D02*
X1103614Y653213D01*
G01X1108330Y653466D02*
X1107295Y653648D01*
G01D02*
X1106772Y653283D01*
G01X1105722Y653953D02*
X1107026Y654863D01*
G01X1108330Y653466D02*
X1107295Y653648D01*
G01X1107026Y654863D02*
X1109000Y654517D01*
G01X1108694Y652945D02*
X1108330Y653466D01*
G01X1109000Y654517D02*
X1109910Y653214D01*
G01X1114626Y653483D02*
X1113592Y653666D01*
G01D02*
X1113073Y653303D01*
G01X1112023Y653972D02*
X1113323Y654882D01*
G01X1114626Y653483D02*
X1113592Y653666D01*
G01X1113323Y654882D02*
X1115296Y654533D01*
G01X1114993Y652959D02*
X1114626Y653483D01*
G01X1115296Y654533D02*
X1116209Y653229D01*
G01X1120933Y653544D02*
X1119899Y653727D01*
G01D02*
X1119380Y653364D01*
G01X1118330Y654033D02*
X1119630Y654943D01*
G01X1120933Y653544D02*
X1119899Y653727D01*
G01X1119630Y654943D02*
X1121603Y654594D01*
G01X1121300Y653020D02*
X1120933Y653544D01*
G01X1121603Y654594D02*
X1122516Y653290D01*
G01X1127240Y653605D02*
X1126206Y653788D01*
G01D02*
X1125687Y653425D01*
G01X1124637Y654094D02*
X1125937Y655004D01*
G01X1127240Y653605D02*
X1126206Y653788D01*
G01X1125937Y655004D02*
X1127910Y654655D01*
G01X1127607Y653081D02*
X1127240Y653605D01*
G01X1127910Y654655D02*
X1128823Y653351D01*
G01X1133547Y653666D02*
X1132513Y653849D01*
G01D02*
X1131994Y653486D01*
G01X1130944Y654155D02*
X1132244Y655065D01*
G01X1133547Y653666D02*
X1132513Y653849D01*
G01X1132244Y655065D02*
X1134217Y654716D01*
G01X1133914Y653142D02*
X1133547Y653666D01*
G01X1134217Y654716D02*
X1135130Y653412D01*
G01X1139879Y653818D02*
X1138845Y654000D01*
G01D02*
X1138320Y653633D01*
G01X1137270Y654303D02*
X1138576Y655216D01*
G01X1139879Y653818D02*
X1138845Y654000D01*
G01X1138576Y655216D02*
X1140549Y654868D01*
G01X1140243Y653296D02*
X1139879Y653818D01*
G01X1140549Y654868D02*
X1141459Y653564D01*
G01X1146175Y653822D02*
X1145140Y654004D01*
G01D02*
X1144618Y653640D01*
G01X1143568Y654310D02*
X1144871Y655219D01*
G01X1146175Y653822D02*
X1145140Y654004D01*
G01X1144871Y655219D02*
X1146845Y654873D01*
G01X1146540Y653300D02*
X1146175Y653822D01*
G01X1146845Y654873D02*
X1147756Y653569D01*
G01X1152465Y653789D02*
X1151430Y653971D01*
G01D02*
X1150908Y653607D01*
G01X1149858Y654277D02*
X1151161Y655186D01*
G01X1152465Y653789D02*
X1151430Y653971D01*
G01X1151161Y655186D02*
X1153135Y654840D01*
G01X1152830Y653267D02*
X1152465Y653789D01*
G01X1153135Y654840D02*
X1154046Y653536D01*
G01X1156155Y654277D02*
X1157458Y655186D01*
G01X1156155Y654277D02*
X1157458Y655186D01*
G01X1156155Y654277D02*
X1157458Y655186D01*
G01X1153135Y654840D02*
X1154046Y653536D01*
G01X1152830Y653267D02*
X1152465Y653789D01*
G01X1149858Y654277D02*
X1151161Y655186D01*
G01D02*
X1153135Y654840D01*
G01X1152465Y653789D02*
X1151430Y653971D01*
G01X1149858Y654277D02*
X1151161Y655186D01*
G01X1151430Y653971D02*
X1150908Y653607D01*
G01X1146845Y654873D02*
X1147756Y653569D01*
G01X1146540Y653300D02*
X1146175Y653822D01*
G01X1143568Y654310D02*
X1144871Y655219D01*
G01D02*
X1146845Y654873D01*
G01X1146175Y653822D02*
X1145140Y654004D01*
G01X1143568Y654310D02*
X1144871Y655219D01*
G01X1145140Y654004D02*
X1144618Y653640D01*
G01X1140549Y654868D02*
X1141459Y653564D01*
G01X1140243Y653296D02*
X1139879Y653818D01*
G01X1137270Y654303D02*
X1138576Y655216D01*
G01D02*
X1140549Y654868D01*
G01X1139879Y653818D02*
X1138845Y654000D01*
G01X1137270Y654303D02*
X1138576Y655216D01*
G01X1138845Y654000D02*
X1138320Y653633D01*
G01X1134217Y654716D02*
X1135130Y653412D01*
G01X1133914Y653142D02*
X1133547Y653666D01*
G01X1130944Y654155D02*
X1132244Y655065D01*
G01D02*
X1134217Y654716D01*
G01X1133547Y653666D02*
X1132513Y653849D01*
G01X1130944Y654155D02*
X1132244Y655065D01*
G01X1132513Y653849D02*
X1131994Y653486D01*
G01X1127910Y654655D02*
X1128823Y653351D01*
G01X1127607Y653081D02*
X1127240Y653605D01*
G01X1124637Y654094D02*
X1125937Y655004D01*
G01D02*
X1127910Y654655D01*
G01X1127240Y653605D02*
X1126206Y653788D01*
G01X1124637Y654094D02*
X1125937Y655004D01*
G01X1126206Y653788D02*
X1125687Y653425D01*
G01X1121603Y654594D02*
X1122516Y653290D01*
G01X1121300Y653020D02*
X1120933Y653544D01*
G01X1118330Y654033D02*
X1119630Y654943D01*
G01D02*
X1121603Y654594D01*
G01X1120933Y653544D02*
X1119899Y653727D01*
G01X1118330Y654033D02*
X1119630Y654943D01*
G01X1119899Y653727D02*
X1119380Y653364D01*
G01X1115296Y654533D02*
X1116209Y653229D01*
G01X1114993Y652959D02*
X1114626Y653483D01*
G01X1112023Y653972D02*
X1113323Y654882D01*
G01D02*
X1115296Y654533D01*
G01X1114626Y653483D02*
X1113592Y653666D01*
G01X1112023Y653972D02*
X1113323Y654882D01*
G01X1113592Y653666D02*
X1113073Y653303D01*
G01X1109000Y654517D02*
X1109910Y653214D01*
G01X1108694Y652945D02*
X1108330Y653466D01*
G01X1105722Y653953D02*
X1107026Y654863D01*
G01D02*
X1109000Y654517D01*
G01X1108330Y653466D02*
X1107295Y653648D01*
G01X1105722Y653953D02*
X1107026Y654863D01*
G01X1107295Y653648D02*
X1106772Y653283D01*
G01X1102704Y654516D02*
X1103614Y653213D01*
G01X1102398Y652944D02*
X1102034Y653465D01*
G01X1099426Y653952D02*
X1100730Y654862D01*
G01D02*
X1102704Y654516D01*
G01X1102034Y653465D02*
X1101000Y653647D01*
G01X1099426Y653952D02*
X1100730Y654862D01*
G01X1101000Y653647D02*
X1100477Y653282D01*
G01X1096413Y654549D02*
X1097323Y653246D01*
G01X1096107Y652977D02*
X1095743Y653498D01*
G01X1225714Y328900D02*
X1214360D01*
G01X1225917Y327750D02*
X1214360D01*
G01X1213545Y331800D02*
X1223935D01*
G01X1213545Y330650D02*
X1224138D01*
G01X1213087Y325971D02*
X1224952D01*
G01X1225155Y324821D02*
X1213087D01*
G01X1225917Y327750D02*
X1214360D01*
G01X1225714Y328900D02*
X1214360D01*
G01X1213545Y330650D02*
X1224138D01*
G01X1213545Y331800D02*
X1223935D01*
G01X1225155Y324821D02*
X1213087D01*
G01Y325971D02*
X1224952D01*
G01X1226181Y335750D02*
X1216000D01*
G01X1226295Y334600D02*
X1216000D01*
G01X1224557Y338518D02*
X1215194D01*
G01X1224668Y337368D02*
X1215194D01*
G01X1226295Y334600D02*
X1216000D01*
G01X1226181Y335750D02*
X1216000D01*
G01X1224668Y337368D02*
X1215194D01*
G01X1224557Y338518D02*
X1215194D01*
G01X1233136Y347900D02*
X1214500D01*
G01X1233345Y346750D02*
X1214500D01*
G01X1233345D02*
X1214500D01*
G01X1233136Y347900D02*
X1214500D01*
G01X1205288Y393710D02*
X1206341Y394764D01*
G01X1204474Y394523D02*
X1205676Y395726D01*
G01X1206341Y394764D02*
X1227279Y404189D01*
G01X1205676Y395726D02*
X1226614Y405152D01*
G01X1202006Y394394D02*
X1205516Y397904D01*
G01X1201192Y395208D02*
X1204864Y398880D01*
G01X1205516Y397904D02*
X1224788Y405887D01*
G01X1204864Y398880D02*
X1224136Y406863D01*
G01X1200323Y396878D02*
X1203489Y400044D01*
G01X1199509Y397692D02*
X1202837Y401020D01*
G01X1203489Y400044D02*
X1221511Y407510D01*
G01X1202837Y401020D02*
X1220859Y408486D01*
G01X1204474Y394523D02*
X1205676Y395726D01*
G01X1205288Y393710D02*
X1206341Y394764D01*
G01X1205676Y395726D02*
X1226614Y405152D01*
G01X1206341Y394764D02*
X1227279Y404189D01*
G01X1201192Y395208D02*
X1204864Y398880D01*
G01X1202006Y394394D02*
X1205516Y397904D01*
G01X1204864Y398880D02*
X1224136Y406863D01*
G01X1205516Y397904D02*
X1224788Y405887D01*
G01X1199509Y397692D02*
X1202837Y401020D01*
G01X1200323Y396878D02*
X1203489Y400044D01*
G01X1202837Y401020D02*
X1220859Y408486D01*
G01X1203489Y400044D02*
X1221511Y407510D01*
G01X1227555Y379626D02*
X1218335Y370407D01*
G01X1226610Y380309D02*
X1217683Y371382D01*
G01X1218335Y370407D02*
X1211716Y367664D01*
G01X1217683Y371382D02*
X1211487Y368814D01*
G01X1211716Y367664D02*
X1209992D01*
G01X1211487Y368814D02*
X1209992D01*
G01X1220322Y364935D02*
X1209157D01*
G01X1220208Y366085D02*
X1209157D01*
G01X1240359Y365784D02*
X1217320Y361200D01*
G01X1240024Y366890D02*
X1217206Y362350D01*
G01X1217320Y361200D02*
X1208300D01*
G01X1217206Y362350D02*
X1208300D01*
G01X1218856Y358200D02*
X1214210D01*
G01X1218742Y359350D02*
X1214210D01*
G01X1213285Y354050D02*
X1214969D01*
G01X1213309Y355200D02*
X1214855D01*
G01X1214969Y354050D02*
X1246734Y360367D01*
G01X1214855Y355200D02*
X1246399Y361473D01*
G01X1238269Y410003D02*
X1214870Y381187D01*
G01X1237559Y410955D02*
X1213977Y381912D01*
G01X1226610Y380309D02*
X1217683Y371382D01*
G01X1227555Y379626D02*
X1218335Y370407D01*
G01X1217683Y371382D02*
X1211487Y368814D01*
G01X1218335Y370407D02*
X1211716Y367664D01*
G01X1211487Y368814D02*
X1209992D01*
G01X1211716Y367664D02*
X1209992D01*
G01X1220208Y366085D02*
X1209157D01*
G01X1220322Y364935D02*
X1209157D01*
G01X1240024Y366890D02*
X1217206Y362350D01*
G01X1240359Y365784D02*
X1217320Y361200D01*
G01X1217206Y362350D02*
X1208300D01*
G01X1217320Y361200D02*
X1208300D01*
G01X1218742Y359350D02*
X1214210D01*
G01X1218856Y358200D02*
X1214210D01*
G01X1213309Y355200D02*
X1214855D01*
G01X1213285Y354050D02*
X1214969D01*
G01X1214855Y355200D02*
X1246399Y361473D01*
G01X1214969Y354050D02*
X1246734Y360367D01*
G01X1237559Y410955D02*
X1213977Y381912D01*
G01X1238269Y410003D02*
X1214870Y381187D01*
G01X1200900Y408950D02*
X1206963D01*
G01X1200900Y410100D02*
X1206734D01*
G01X1206963Y408950D02*
X1219116Y413988D01*
G01X1206734Y410100D02*
X1218464Y414963D01*
G01D02*
X1247001Y443511D01*
G01X1242350Y450350D02*
X1205250Y413250D01*
G01X1242827Y449200D02*
X1217324Y423697D01*
G01X1242350Y450350D02*
X1205250Y413250D01*
G01X1215414Y421787D02*
X1214424Y420797D01*
G01X1242350Y450350D02*
X1205250Y413250D01*
G01X1212515Y418888D02*
X1211525Y417898D01*
G01X1242350Y450350D02*
X1205250Y413250D01*
G01X1209616Y415989D02*
X1208626Y414999D01*
G01X1242350Y450350D02*
X1205250Y413250D01*
G01X1206717Y413090D02*
X1205727Y412100D01*
G01X1205250Y413250D02*
X1193631D01*
G01X1205727Y412100D02*
X1193860D01*
G01X1193631Y413250D02*
X1190762Y412062D01*
G01X1193860Y412100D02*
X1191414Y411086D01*
G01X1190762Y412062D02*
X1188200Y409500D01*
G01X1191414Y411086D02*
X1189350Y409022D01*
G01X1188200Y409500D02*
Y407627D01*
G01X1189350Y409022D02*
Y407627D01*
G01X1186622Y410415D02*
X1191657Y415450D01*
G01X1185979Y411400D02*
X1191180Y416600D01*
G01X1191657Y415450D02*
X1203850D01*
G01X1191180Y416600D02*
X1203373D01*
G01X1203850Y415450D02*
X1250250Y461850D01*
G01X1203373Y416600D02*
X1249773Y463000D01*
G01X1182197Y412313D02*
X1189034Y419150D01*
G01X1183011Y411500D02*
X1189511Y418000D01*
G01X1189034Y419150D02*
X1201573D01*
G01X1189511Y418000D02*
X1202050D01*
G01X1201573Y419150D02*
X1248800Y466377D01*
G01X1202050Y418000D02*
X1249950Y465900D01*
G01X1203287Y405050D02*
X1207306D01*
G01X1203287Y406200D02*
X1207077D01*
G01X1207306Y405050D02*
X1219372Y410046D01*
G01X1207077Y406200D02*
X1208324Y406717D01*
G01X1207306Y405050D02*
X1219372Y410046D01*
G01X1210773Y407731D02*
X1212020Y408247D01*
G01X1207306Y405050D02*
X1219372Y410046D01*
G01X1214468Y409261D02*
X1218720Y411022D01*
G01X1200900Y410100D02*
X1206734D01*
G01X1200900Y408950D02*
X1206963D01*
G01X1206734Y410100D02*
X1218464Y414963D01*
G01X1206963Y408950D02*
X1219116Y413988D01*
G01X1218464Y414963D02*
X1247001Y443511D01*
G01X1242827Y449200D02*
X1217324Y423697D01*
G01X1215414Y421787D02*
X1214424Y420797D01*
G01X1212515Y418888D02*
X1211525Y417898D01*
G01X1209616Y415989D02*
X1208626Y414999D01*
G01X1206717Y413090D02*
X1205727Y412100D01*
G01X1242350Y450350D02*
X1205250Y413250D01*
G01X1205727Y412100D02*
X1193860D01*
G01X1205250Y413250D02*
X1193631D01*
G01X1193860Y412100D02*
X1191414Y411086D01*
G01X1193631Y413250D02*
X1190762Y412062D01*
G01X1191414Y411086D02*
X1189350Y409022D01*
G01X1190762Y412062D02*
X1188200Y409500D01*
G01X1189350Y409022D02*
Y407627D01*
G01X1188200Y409500D02*
Y407627D01*
G01X1185979Y411400D02*
X1191180Y416600D01*
G01X1186622Y410415D02*
X1191657Y415450D01*
G01X1191180Y416600D02*
X1203373D01*
G01X1191657Y415450D02*
X1203850D01*
G01X1203373Y416600D02*
X1249773Y463000D01*
G01X1203850Y415450D02*
X1250250Y461850D01*
G01X1183011Y411500D02*
X1189511Y418000D01*
G01X1182197Y412313D02*
X1189034Y419150D01*
G01X1189511Y418000D02*
X1202050D01*
G01X1189034Y419150D02*
X1201573D01*
G01X1202050Y418000D02*
X1249950Y465900D01*
G01X1201573Y419150D02*
X1248800Y466377D01*
G01X1203287Y406200D02*
X1207077D01*
G01X1203287Y405050D02*
X1207306D01*
G01X1207077Y406200D02*
X1208324Y406717D01*
G01X1210773Y407731D02*
X1212020Y408247D01*
G01X1214468Y409261D02*
X1218720Y411022D01*
G01X1207306Y405050D02*
X1219372Y410046D01*
G01X1157648Y644893D02*
X1159125Y653269D01*
G01X1160341Y653538D02*
X1158864Y645161D01*
G01X1158558Y643588D02*
X1157648Y644893D01*
G01X1158864Y645161D02*
X1159228Y644639D01*
G01X1161835Y644156D02*
X1160532Y643242D01*
G01D02*
X1158558Y643588D01*
G01X1159228Y644639D02*
X1160261Y644458D01*
G01X1161835Y644156D02*
X1160532Y643242D01*
G01X1160261Y644458D02*
X1160784Y644825D01*
G01X1163503Y653625D02*
X1161835Y644156D01*
G01X1160784Y644825D02*
X1162453Y654295D01*
G01X1163922Y644778D02*
X1165422Y653285D01*
G01X1166638Y653556D02*
X1165138Y645048D01*
G01X1164834Y643477D02*
X1163922Y644778D01*
G01X1165138Y645048D02*
X1165503Y644527D01*
G01X1168111Y644044D02*
X1166808Y643128D01*
G01D02*
X1164834Y643477D01*
G01X1165503Y644527D02*
X1166537Y644344D01*
G01X1168111Y644044D02*
X1166808Y643128D01*
G01X1166537Y644344D02*
X1167060Y644712D01*
G01X1169801Y653625D02*
X1168111Y644044D01*
G01X1167060Y644712D02*
X1168751Y654294D01*
G01X1170219Y644775D02*
X1171719Y653286D01*
G01X1172935Y653555D02*
X1171435Y645046D01*
G01X1171134Y643475D02*
X1170219Y644775D01*
G01X1171435Y645046D02*
X1171801Y644526D01*
G01X1174406Y644039D02*
X1173103Y643130D01*
G01D02*
X1171134Y643475D01*
G01X1171801Y644526D02*
X1172834Y644345D01*
G01X1174406Y644039D02*
X1173103Y643130D01*
G01X1172834Y644345D02*
X1173356Y644709D01*
G01X1176089Y653591D02*
X1174406Y644039D01*
G01X1173356Y644709D02*
X1175038Y654261D01*
G01X1176519Y644797D02*
X1178010Y653253D01*
G01X1179226Y653522D02*
X1177735Y645066D01*
G01X1177431Y643493D02*
X1176519Y644797D01*
G01X1177735Y645066D02*
X1178100Y644544D01*
G01X1180706Y644058D02*
X1179403Y643148D01*
G01D02*
X1177431Y643493D01*
G01X1178100Y644544D02*
X1179133Y644363D01*
G01X1180706Y644058D02*
X1179403Y643148D01*
G01X1179133Y644363D02*
X1179655Y644728D01*
G01X1182384Y653592D02*
X1180706Y644058D01*
G01X1179655Y644728D02*
X1181334Y654262D01*
G01X1182814Y644801D02*
X1184306Y653254D01*
G01X1185522Y653523D02*
X1184030Y645069D01*
G01X1183723Y643496D02*
X1182814Y644801D01*
G01X1184030Y645069D02*
X1184394Y644546D01*
G01X1187001Y644062D02*
X1185697Y643148D01*
G01D02*
X1183723Y643496D01*
G01X1184394Y644546D02*
X1185427Y644364D01*
G01X1187001Y644062D02*
X1185697Y643148D01*
G01X1185427Y644364D02*
X1185950Y644731D01*
G01X1188685Y653612D02*
X1187001Y644062D01*
G01X1185950Y644731D02*
X1187635Y654281D01*
G01X1189121Y644862D02*
X1190605Y653268D01*
G01X1191821Y653538D02*
X1190337Y645131D01*
G01X1190032Y643558D02*
X1189121Y644862D01*
G01X1190337Y645131D02*
X1190702Y644609D01*
G01X1193308Y644123D02*
X1192006Y643211D01*
G01D02*
X1190032Y643558D01*
G01X1190702Y644609D02*
X1191736Y644427D01*
G01X1193308Y644123D02*
X1192006Y643211D01*
G01X1191736Y644427D02*
X1192258Y644792D01*
G01X1193719Y646460D02*
X1193308Y644123D01*
G01X1192258Y644792D02*
X1192593Y646702D01*
G01X1194027Y647672D02*
X1193719Y646460D01*
G01X1192593Y646702D02*
X1192968Y648179D01*
G01X1194384Y648148D02*
X1194027Y647672D01*
G01X1192968Y648179D02*
X1193545Y648948D01*
G01X1195700Y648679D02*
X1195063Y648709D01*
G01D02*
X1194384Y648148D01*
G01X1193545Y648948D02*
X1194673Y649879D01*
G01X1195700Y648679D02*
X1195063Y648709D01*
G01X1193545Y648948D02*
X1194673Y649879D01*
G01X1195700Y648679D02*
X1195063Y648709D01*
G01X1193545Y648948D02*
X1194673Y649879D01*
G01X1195063Y648709D02*
X1194384Y648148D01*
G01X1192968Y648179D02*
X1193545Y648948D01*
G01X1194384Y648148D02*
X1194027Y647672D01*
G01X1192593Y646702D02*
X1192968Y648179D01*
G01X1194027Y647672D02*
X1193719Y646460D01*
G01X1192258Y644792D02*
X1192593Y646702D01*
G01X1193719Y646460D02*
X1193308Y644123D01*
G01X1190702Y644609D02*
X1191736Y644427D01*
G01D02*
X1192258Y644792D01*
G01X1193308Y644123D02*
X1192006Y643211D01*
G01X1190702Y644609D02*
X1191736Y644427D01*
G01X1192006Y643211D02*
X1190032Y643558D01*
G01X1190337Y645131D02*
X1190702Y644609D01*
G01X1190032Y643558D02*
X1189121Y644862D01*
G01X1191821Y653538D02*
X1190337Y645131D01*
G01X1189121Y644862D02*
X1190605Y653268D01*
G01X1185950Y644731D02*
X1187635Y654281D01*
G01X1188685Y653612D02*
X1187001Y644062D01*
G01X1184394Y644546D02*
X1185427Y644364D01*
G01D02*
X1185950Y644731D01*
G01X1187001Y644062D02*
X1185697Y643148D01*
G01X1184394Y644546D02*
X1185427Y644364D01*
G01X1185697Y643148D02*
X1183723Y643496D01*
G01X1184030Y645069D02*
X1184394Y644546D01*
G01X1183723Y643496D02*
X1182814Y644801D01*
G01X1185522Y653523D02*
X1184030Y645069D01*
G01X1182814Y644801D02*
X1184306Y653254D01*
G01X1179655Y644728D02*
X1181334Y654262D01*
G01X1182384Y653592D02*
X1180706Y644058D01*
G01X1178100Y644544D02*
X1179133Y644363D01*
G01D02*
X1179655Y644728D01*
G01X1180706Y644058D02*
X1179403Y643148D01*
G01X1178100Y644544D02*
X1179133Y644363D01*
G01X1179403Y643148D02*
X1177431Y643493D01*
G01X1177735Y645066D02*
X1178100Y644544D01*
G01X1177431Y643493D02*
X1176519Y644797D01*
G01X1179226Y653522D02*
X1177735Y645066D01*
G01X1176519Y644797D02*
X1178010Y653253D01*
G01X1173356Y644709D02*
X1175038Y654261D01*
G01X1176089Y653591D02*
X1174406Y644039D01*
G01X1171801Y644526D02*
X1172834Y644345D01*
G01D02*
X1173356Y644709D01*
G01X1174406Y644039D02*
X1173103Y643130D01*
G01X1171801Y644526D02*
X1172834Y644345D01*
G01X1173103Y643130D02*
X1171134Y643475D01*
G01X1171435Y645046D02*
X1171801Y644526D01*
G01X1171134Y643475D02*
X1170219Y644775D01*
G01X1172935Y653555D02*
X1171435Y645046D01*
G01X1170219Y644775D02*
X1171719Y653286D01*
G01X1167060Y644712D02*
X1168751Y654294D01*
G01X1169801Y653625D02*
X1168111Y644044D01*
G01X1165503Y644527D02*
X1166537Y644344D01*
G01D02*
X1167060Y644712D01*
G01X1168111Y644044D02*
X1166808Y643128D01*
G01X1165503Y644527D02*
X1166537Y644344D01*
G01X1166808Y643128D02*
X1164834Y643477D01*
G01X1165138Y645048D02*
X1165503Y644527D01*
G01X1164834Y643477D02*
X1163922Y644778D01*
G01X1166638Y653556D02*
X1165138Y645048D01*
G01X1163922Y644778D02*
X1165422Y653285D01*
G01X1160784Y644825D02*
X1162453Y654295D01*
G01X1163503Y653625D02*
X1161835Y644156D01*
G01X1159228Y644639D02*
X1160261Y644458D01*
G01D02*
X1160784Y644825D01*
G01X1161835Y644156D02*
X1160532Y643242D01*
G01X1159228Y644639D02*
X1160261Y644458D01*
G01X1160532Y643242D02*
X1158558Y643588D01*
G01X1158864Y645161D02*
X1159228Y644639D01*
G01X1158558Y643588D02*
X1157648Y644893D01*
G01X1160341Y653538D02*
X1158864Y645161D01*
G01X1157648Y644893D02*
X1159125Y653269D01*
G01X1158761Y653790D02*
X1157727Y653971D01*
G01D02*
X1157205Y653607D01*
G01X1158761Y653790D02*
X1157727Y653971D01*
G01X1157458Y655186D02*
X1159431Y654841D01*
G01X1159125Y653269D02*
X1158761Y653790D01*
G01X1159431Y654841D02*
X1160341Y653538D01*
G01X1165059Y653807D02*
X1164025Y653990D01*
G01D02*
X1163503Y653625D01*
G01X1162453Y654295D02*
X1163756Y655205D01*
G01X1165059Y653807D02*
X1164025Y653990D01*
G01X1163756Y655205D02*
X1165729Y654857D01*
G01X1165422Y653285D02*
X1165059Y653807D01*
G01X1165729Y654857D02*
X1166638Y653556D01*
G01X1171355Y653807D02*
X1170321Y653989D01*
G01D02*
X1169801Y653625D01*
G01X1168751Y654294D02*
X1170051Y655205D01*
G01X1171355Y653807D02*
X1170321Y653989D01*
G01X1170051Y655205D02*
X1172025Y654858D01*
G01X1171719Y653286D02*
X1171355Y653807D01*
G01X1172025Y654858D02*
X1172935Y653555D01*
G01X1177646Y653774D02*
X1176612Y653956D01*
G01D02*
X1176089Y653591D01*
G01X1175038Y654261D02*
X1176342Y655171D01*
G01X1177646Y653774D02*
X1176612Y653956D01*
G01X1176342Y655171D02*
X1178316Y654825D01*
G01X1178010Y653253D02*
X1177646Y653774D01*
G01X1178316Y654825D02*
X1179226Y653522D01*
G01X1183942Y653775D02*
X1182907Y653957D01*
G01D02*
X1182384Y653592D01*
G01X1181334Y654262D02*
X1182638Y655172D01*
G01X1183942Y653775D02*
X1182907Y653957D01*
G01X1182638Y655172D02*
X1184612Y654826D01*
G01X1184306Y653254D02*
X1183942Y653775D01*
G01X1184612Y654826D02*
X1185522Y653523D01*
G01X1190238Y653792D02*
X1189204Y653975D01*
G01D02*
X1188685Y653612D01*
G01X1187635Y654281D02*
X1188935Y655191D01*
G01X1190238Y653792D02*
X1189204Y653975D01*
G01X1188935Y655191D02*
X1190908Y654842D01*
G01X1190605Y653268D02*
X1190238Y653792D01*
G01X1190908Y654842D02*
X1191821Y653538D01*
G01X1194673Y649879D02*
X1195793Y649827D01*
G01X1194673Y649879D02*
X1195793Y649827D01*
G01X1190908Y654842D02*
X1191821Y653538D01*
G01X1190605Y653268D02*
X1190238Y653792D01*
G01X1187635Y654281D02*
X1188935Y655191D01*
G01D02*
X1190908Y654842D01*
G01X1190238Y653792D02*
X1189204Y653975D01*
G01X1187635Y654281D02*
X1188935Y655191D01*
G01X1189204Y653975D02*
X1188685Y653612D01*
G01X1184612Y654826D02*
X1185522Y653523D01*
G01X1184306Y653254D02*
X1183942Y653775D01*
G01X1181334Y654262D02*
X1182638Y655172D01*
G01D02*
X1184612Y654826D01*
G01X1183942Y653775D02*
X1182907Y653957D01*
G01X1181334Y654262D02*
X1182638Y655172D01*
G01X1182907Y653957D02*
X1182384Y653592D01*
G01X1178316Y654825D02*
X1179226Y653522D01*
G01X1178010Y653253D02*
X1177646Y653774D01*
G01X1175038Y654261D02*
X1176342Y655171D01*
G01D02*
X1178316Y654825D01*
G01X1177646Y653774D02*
X1176612Y653956D01*
G01X1175038Y654261D02*
X1176342Y655171D01*
G01X1176612Y653956D02*
X1176089Y653591D01*
G01X1172025Y654858D02*
X1172935Y653555D01*
G01X1171719Y653286D02*
X1171355Y653807D01*
G01X1168751Y654294D02*
X1170051Y655205D01*
G01D02*
X1172025Y654858D01*
G01X1171355Y653807D02*
X1170321Y653989D01*
G01X1168751Y654294D02*
X1170051Y655205D01*
G01X1170321Y653989D02*
X1169801Y653625D01*
G01X1165729Y654857D02*
X1166638Y653556D01*
G01X1165422Y653285D02*
X1165059Y653807D01*
G01X1162453Y654295D02*
X1163756Y655205D01*
G01D02*
X1165729Y654857D01*
G01X1165059Y653807D02*
X1164025Y653990D01*
G01X1162453Y654295D02*
X1163756Y655205D01*
G01X1164025Y653990D02*
X1163503Y653625D01*
G01X1159431Y654841D02*
X1160341Y653538D01*
G01X1159125Y653269D02*
X1158761Y653790D01*
G01X1157458Y655186D02*
X1159431Y654841D01*
G01X1158761Y653790D02*
X1157727Y653971D01*
G01D02*
X1157205Y653607D01*
G01X1302135Y329343D02*
X1265031Y336763D01*
G01X1301686Y328260D02*
X1265031Y335590D01*
G01Y336763D02*
X1225714Y328900D01*
G01X1265031Y335590D02*
X1225939Y327772D01*
G01X1223935Y331800D02*
X1263757Y339766D01*
G01X1224160Y330672D02*
X1263757Y338593D01*
G01Y339766D02*
X1340844Y324348D01*
G01X1263757Y338593D02*
X1340844Y323175D01*
G01X1221613Y322476D02*
X1224801D01*
G01X1221613Y321326D02*
X1224915D01*
G01X1224801Y322476D02*
X1265369Y330587D01*
G01X1224915Y321326D02*
X1265369Y329414D01*
G01Y330587D02*
X1298544Y323951D01*
G01X1265369Y329414D02*
X1298095Y322868D01*
G01X1264442Y333868D02*
X1300820Y326592D01*
G01X1300371Y325509D02*
X1264442Y332695D01*
G01X1224952Y325971D02*
X1264442Y333868D01*
G01Y332695D02*
X1225177Y324843D01*
G01X1301686Y328260D02*
X1265031Y335590D01*
G01X1302135Y329343D02*
X1265031Y336763D01*
G01Y335590D02*
X1225939Y327772D01*
G01X1265031Y336763D02*
X1225714Y328900D01*
G01X1224160Y330672D02*
X1263757Y338593D01*
G01X1223935Y331800D02*
X1263757Y339766D01*
G01Y338593D02*
X1340844Y323175D01*
G01X1263757Y339766D02*
X1340844Y324348D01*
G01X1221613Y321326D02*
X1224915D01*
G01X1221613Y322476D02*
X1224801D01*
G01X1224915Y321326D02*
X1265369Y329414D01*
G01X1224801Y322476D02*
X1265369Y330587D01*
G01Y329414D02*
X1298095Y322868D01*
G01X1265369Y330587D02*
X1298544Y323951D01*
G01X1264442Y332695D02*
X1225177Y324843D01*
G01X1224952Y325971D02*
X1264442Y333868D01*
G01X1300371Y325509D02*
X1264442Y332695D01*
G01Y333868D02*
X1300820Y326592D01*
G01X1340206Y327684D02*
X1263018Y343117D01*
G01X1340206Y326511D02*
X1263018Y341944D01*
G01Y343117D02*
X1226181Y335750D01*
G01X1263018Y341944D02*
X1226295Y334600D01*
G01X1339531Y329350D02*
X1262559Y344742D01*
G01X1262562Y345915D02*
X1224557Y338518D01*
G01X1262559Y344742D02*
X1224668Y337368D01*
G01X1340206Y326511D02*
X1263018Y341944D01*
G01X1340206Y327684D02*
X1263018Y343117D01*
G01Y341944D02*
X1226295Y334600D01*
G01X1263018Y343117D02*
X1226181Y335750D01*
G01X1339531Y329350D02*
X1262559Y344742D01*
G01D02*
X1224668Y337368D01*
G01X1262562Y345915D02*
X1224557Y338518D01*
G01X1339531Y330523D02*
X1262562Y345915D01*
G01X1309533Y339219D02*
X1261857Y348756D01*
G01X1309533Y338046D02*
X1261854Y347583D01*
G01X1261857Y348756D02*
X1233940Y343328D01*
G01X1261854Y347583D02*
X1234159Y342199D01*
G01X1233940Y343328D02*
X1226543D01*
G01X1234138Y342178D02*
X1226543D01*
G01X1339531Y330523D02*
X1262562Y345915D01*
G01X1309533Y338046D02*
X1261854Y347583D01*
G01X1309533Y339219D02*
X1261857Y348756D01*
G01X1261854Y347583D02*
X1234159Y342199D01*
G01X1261857Y348756D02*
X1233940Y343328D01*
G01X1234138Y342178D02*
X1226543D01*
G01X1233940Y343328D02*
X1226543D01*
G01X1308423Y342185D02*
X1256107Y352649D01*
G01X1308423Y341012D02*
X1256111Y351475D01*
G01X1256107Y352649D02*
X1233136Y347900D01*
G01X1256111Y351475D02*
X1233368Y346773D01*
G01X1308423Y341012D02*
X1256111Y351475D01*
G01X1308423Y342185D02*
X1256107Y352649D01*
G01X1256111Y351475D02*
X1233368Y346773D01*
G01X1256107Y352649D02*
X1233136Y347900D01*
G01X1224416Y382496D02*
X1220492Y378572D01*
G01X1221306Y377759D02*
X1225364Y381817D01*
G01X1227363Y388475D02*
X1224416Y382496D01*
G01X1225364Y381817D02*
X1228338Y387850D01*
G01X1241700Y406129D02*
X1227363Y388475D01*
G01X1228338Y387850D02*
X1242410Y405177D01*
G01X1297189Y424200D02*
X1243090Y401784D01*
G01X1296960Y425350D02*
X1242380Y402736D01*
G01X1243090Y401784D02*
X1231544Y387567D01*
G01X1242380Y402736D02*
X1230572Y388195D01*
G01X1231544Y387567D02*
X1227555Y379626D01*
G01X1230572Y388195D02*
X1226610Y380309D01*
G01X1317988Y411685D02*
X1271368Y392379D01*
G01X1317672Y412799D02*
X1270649Y393327D01*
G01X1271368Y392379D02*
X1258930Y376542D01*
G01X1270649Y393327D02*
X1258211Y377489D01*
G01X1258930Y376542D02*
X1240716Y368990D01*
G01X1258211Y377490D02*
X1240380Y370096D01*
G01X1240716Y368990D02*
X1220322Y364935D01*
G01X1240380Y370096D02*
X1220208Y366085D01*
G01X1318968Y409159D02*
X1274998Y390952D01*
G01X1318652Y410273D02*
X1274279Y391900D01*
G01X1274998Y390952D02*
X1262399Y374908D01*
G01X1274279Y391900D02*
X1261682Y375857D01*
G01X1262399Y374908D02*
X1240359Y365784D01*
G01X1261682Y375857D02*
X1250854Y371375D01*
G01X1262399Y374908D02*
X1240359Y365784D01*
G01X1250854Y371374D02*
X1240024Y366890D01*
G01X1305577Y395676D02*
X1272502Y381977D01*
G01X1305256Y396788D02*
X1271783Y382924D01*
G01X1272502Y381977D02*
X1264470Y371743D01*
G01X1271627Y382726D02*
X1263751Y372690D01*
G01X1264470Y371743D02*
X1243708Y363143D01*
G01X1263751Y372690D02*
X1243373Y364249D01*
G01X1243708Y363143D02*
X1218856Y358200D01*
G01X1243373Y364249D02*
X1218742Y359350D01*
G01X1246734Y360367D02*
X1265604Y368182D01*
G01X1246399Y361473D02*
X1264885Y369130D01*
G01X1265604Y368182D02*
X1274563Y379592D01*
G01X1264885Y369130D02*
X1273844Y380540D01*
G01X1274563Y379592D02*
X1305744Y392509D01*
G01X1273844Y380540D02*
X1305423Y393621D01*
G01X1225129Y390651D02*
X1239311Y408114D01*
G01X1240021Y407162D02*
X1226085Y390002D01*
G01X1221965Y384995D02*
X1225129Y390651D01*
G01X1226085Y390002D02*
X1222891Y384294D01*
G01X1219512Y382542D02*
X1221965Y384995D01*
G01X1222891Y384294D02*
X1220325Y381728D01*
G01X1228338Y387850D02*
X1242410Y405177D01*
G01X1241700Y406129D02*
X1227363Y388475D01*
G01X1225364Y381817D02*
X1228338Y387850D01*
G01X1227363Y388475D02*
X1224416Y382496D01*
G01X1221306Y377759D02*
X1225364Y381817D01*
G01X1224416Y382496D02*
X1220492Y378572D01*
G01X1296960Y425350D02*
X1242380Y402736D01*
G01X1297189Y424200D02*
X1243090Y401784D01*
G01X1242380Y402736D02*
X1230572Y388195D01*
G01X1243090Y401784D02*
X1231544Y387567D01*
G01X1230572Y388195D02*
X1226610Y380309D01*
G01X1231544Y387567D02*
X1227555Y379626D01*
G01X1317672Y412799D02*
X1270649Y393327D01*
G01X1317988Y411685D02*
X1271368Y392379D01*
G01X1270649Y393327D02*
X1258211Y377489D01*
G01X1271368Y392379D02*
X1258930Y376542D01*
G01X1258211Y377490D02*
X1240380Y370096D01*
G01X1258930Y376542D02*
X1240716Y368990D01*
G01X1240380Y370096D02*
X1220208Y366085D01*
G01X1240716Y368990D02*
X1220322Y364935D01*
G01X1318652Y410273D02*
X1274279Y391900D01*
G01X1318968Y409159D02*
X1274998Y390952D01*
G01X1274279Y391900D02*
X1261682Y375857D01*
G01X1274998Y390952D02*
X1262399Y374908D01*
G01X1261682Y375857D02*
X1250854Y371375D01*
G01Y371374D02*
X1240024Y366890D01*
G01X1262399Y374908D02*
X1240359Y365784D01*
G01X1305256Y396788D02*
X1271783Y382924D01*
G01X1305577Y395676D02*
X1272502Y381977D01*
G01X1271627Y382726D02*
X1263751Y372690D01*
G01X1272502Y381977D02*
X1264470Y371743D01*
G01X1263751Y372690D02*
X1243373Y364249D01*
G01X1264470Y371743D02*
X1243708Y363143D01*
G01X1243373Y364249D02*
X1218742Y359350D01*
G01X1243708Y363143D02*
X1218856Y358200D01*
G01X1246399Y361473D02*
X1264885Y369130D01*
G01X1246734Y360367D02*
X1265604Y368182D01*
G01X1264885Y369130D02*
X1273844Y380540D01*
G01X1265604Y368182D02*
X1274563Y379592D01*
G01X1273844Y380540D02*
X1305423Y393621D01*
G01X1274563Y379592D02*
X1305744Y392509D01*
G01X1222891Y384294D02*
X1220325Y381728D01*
G01X1219512Y382542D02*
X1221965Y384995D01*
G01X1226085Y390002D02*
X1222891Y384294D01*
G01X1221965Y384995D02*
X1225129Y390651D01*
G01X1240021Y407162D02*
X1226085Y390002D01*
G01X1225129Y390651D02*
X1239311Y408114D01*
G01X1227279Y404189D02*
X1252249Y429160D01*
G01X1226614Y405152D02*
X1251772Y430310D01*
G01X1252249Y429160D02*
X1265528D01*
G01X1251772Y430310D02*
X1265051D01*
G01X1265528Y429160D02*
X1283410Y447042D01*
G01X1265051Y430310D02*
X1282260Y447519D01*
G01X1224788Y405887D02*
X1251610Y432710D01*
G01X1224136Y406863D02*
X1251133Y433860D01*
G01X1251610Y432710D02*
X1265030D01*
G01X1251133Y433860D02*
X1264553D01*
G01X1265030Y432710D02*
X1280910Y448590D01*
G01X1264553Y433860D02*
X1279760Y449067D01*
G01D02*
Y456983D01*
G01D02*
X1295802Y473025D01*
G01X1219116Y413988D02*
X1247478Y442361D01*
G01D02*
X1256088D01*
G01X1247001Y443511D02*
X1255611D01*
G01X1256088Y442361D02*
X1284000Y470273D01*
G01X1255611Y443511D02*
X1282850Y470750D01*
G01X1279000Y469673D02*
X1273177Y463850D01*
G01D02*
X1268977D01*
G01X1268500Y465000D02*
X1253850Y450350D01*
G01X1268977Y463850D02*
X1254327Y449200D01*
G01X1253850Y450350D02*
X1242350D01*
G01X1254327Y449200D02*
X1242827D01*
G01X1250250Y461850D02*
X1254977D01*
G01X1249773Y463000D02*
X1254500D01*
G01X1254977Y461850D02*
X1261752Y468625D01*
G01X1254500Y463000D02*
X1261275Y469775D01*
G01X1219372Y410046D02*
X1248587Y439261D01*
G01X1218720Y411022D02*
X1248110Y440411D01*
G01X1248587Y439261D02*
X1256588D01*
G01X1248110Y440411D02*
X1256111D01*
G01X1256588Y439261D02*
X1298207Y480880D01*
G01X1256111Y440411D02*
X1297730Y482030D01*
G01X1221511Y407510D02*
X1250432Y436432D01*
G01X1220859Y408486D02*
X1249955Y437582D01*
G01X1250432Y436432D02*
X1265215D01*
G01X1249955Y437582D02*
X1264738D01*
G01X1265215Y436432D02*
X1278410Y449627D01*
G01X1264738Y437582D02*
X1277260Y450104D01*
G01X1278410Y449627D02*
Y457543D01*
G01X1277260Y450104D02*
Y458020D01*
G01X1278410Y457543D02*
X1299133Y478266D01*
G01X1277260Y458020D02*
X1298656Y479416D01*
G01X1226614Y405152D02*
X1251772Y430310D01*
G01X1227279Y404189D02*
X1252249Y429160D01*
G01X1251772Y430310D02*
X1265051D01*
G01X1252249Y429160D02*
X1265528D01*
G01X1265051Y430310D02*
X1282260Y447519D01*
G01X1265528Y429160D02*
X1283410Y447042D01*
G01X1224136Y406863D02*
X1251133Y433860D01*
G01X1224788Y405887D02*
X1251610Y432710D01*
G01X1251133Y433860D02*
X1264553D01*
G01X1251610Y432710D02*
X1265030D01*
G01X1264553Y433860D02*
X1279760Y449067D01*
G01X1265030Y432710D02*
X1280910Y448590D01*
G01X1279760Y449067D02*
Y456983D01*
G01D02*
X1295802Y473025D01*
G01X1219116Y413988D02*
X1247478Y442361D01*
G01X1247001Y443511D02*
X1255611D01*
G01X1247478Y442361D02*
X1256088D01*
G01X1255611Y443511D02*
X1282850Y470750D01*
G01X1256088Y442361D02*
X1284000Y470273D01*
G01X1279000Y469673D02*
X1273177Y463850D01*
G01D02*
X1268977D01*
G01D02*
X1254327Y449200D01*
G01X1268500Y465000D02*
X1253850Y450350D01*
G01X1254327Y449200D02*
X1242827D01*
G01X1253850Y450350D02*
X1242350D01*
G01X1249773Y463000D02*
X1254500D01*
G01X1250250Y461850D02*
X1254977D01*
G01X1254500Y463000D02*
X1261275Y469775D01*
G01X1254977Y461850D02*
X1261752Y468625D01*
G01X1218720Y411022D02*
X1248110Y440411D01*
G01X1219372Y410046D02*
X1248587Y439261D01*
G01X1248110Y440411D02*
X1256111D01*
G01X1248587Y439261D02*
X1256588D01*
G01X1256111Y440411D02*
X1297730Y482030D01*
G01X1256588Y439261D02*
X1298207Y480880D01*
G01X1220859Y408486D02*
X1249955Y437582D01*
G01X1221511Y407510D02*
X1250432Y436432D01*
G01X1249955Y437582D02*
X1264738D01*
G01X1250432Y436432D02*
X1265215D01*
G01X1264738Y437582D02*
X1277260Y450104D01*
G01X1265215Y436432D02*
X1278410Y449627D01*
G01X1277260Y450104D02*
Y458020D01*
G01X1278410Y449627D02*
Y457543D01*
G01X1277260Y458020D02*
X1298656Y479416D01*
G01X1278410Y457543D02*
X1299133Y478266D01*
G01X1291360Y426721D02*
X1241700Y406129D01*
G01X1242410Y405177D02*
X1245660Y406524D01*
G01X1291360Y426721D02*
X1241700Y406129D01*
G01X1248107Y407540D02*
X1249354Y408057D01*
G01X1291360Y426721D02*
X1241700Y406129D01*
G01X1251802Y409072D02*
X1292225Y425834D01*
G01X1287415Y430379D02*
X1254196Y416606D01*
G01X1286510Y431250D02*
X1270134Y424460D01*
G01X1287415Y430379D02*
X1254196Y416606D01*
G01X1270134Y424460D02*
X1270133D01*
G01X1251748Y415591D02*
X1250501Y415074D01*
G01X1248053Y414060D02*
X1238269Y410003D01*
G01X1270133Y424460D02*
X1237559Y410955D01*
G01X1239311Y408114D02*
X1288279Y428395D01*
G01X1289184Y427524D02*
X1240021Y407162D01*
G01X1242410Y405177D02*
X1245660Y406524D01*
G01X1248107Y407540D02*
X1249354Y408057D01*
G01X1251802Y409072D02*
X1292225Y425834D01*
G01X1291360Y426721D02*
X1241700Y406129D01*
G01X1286510Y431250D02*
X1270134Y424460D01*
G01D02*
X1270133D01*
G01X1287415Y430379D02*
X1254196Y416606D01*
G01X1270133Y424460D02*
X1237559Y410955D01*
G01X1251748Y415591D02*
X1250501Y415074D01*
G01X1270133Y424460D02*
X1237559Y410955D01*
G01X1248053Y414060D02*
X1238269Y410003D01*
G01X1289184Y427524D02*
X1240021Y407162D01*
G01X1239311Y408114D02*
X1288279Y428395D01*
G01X1294283Y497682D02*
X1277850Y481249D01*
G01X1294760Y496532D02*
X1279000Y480772D01*
G01X1277850Y481249D02*
Y470150D01*
G01X1279000Y480772D02*
Y469673D01*
G01X1277850Y470150D02*
X1272700Y465000D01*
G01D02*
X1268500D01*
G01X1261752Y468625D02*
X1274101D01*
G01X1261275Y469775D02*
X1273624D01*
G01X1274101Y468625D02*
X1276210Y470734D01*
G01X1273624Y469775D02*
X1275060Y471211D01*
G01X1276210Y470734D02*
Y481682D01*
G01X1275060Y471211D02*
Y482159D01*
G01X1276210Y481682D02*
X1293716Y499188D01*
G01X1275060Y482159D02*
X1293239Y500338D01*
G01X1248800Y466377D02*
Y475300D01*
G01X1249950Y465900D02*
Y474823D01*
G01X1248800Y475300D02*
X1251100Y477600D01*
G01X1249950Y474823D02*
X1251577Y476450D01*
G01X1251100Y477600D02*
X1260623D01*
G01X1251577Y476450D02*
X1261100D01*
G01X1260623Y477600D02*
X1265750Y482727D01*
G01X1261100Y476450D02*
X1266900Y482250D01*
G01X1265750Y482727D02*
Y487391D01*
G01X1266900Y482250D02*
Y486914D01*
G01X1265750Y487391D02*
X1268048Y489689D01*
G01X1266900Y486914D02*
X1268525Y488539D01*
G01X1268048Y489689D02*
X1269776D01*
G01X1268525Y488539D02*
X1270253D01*
G01X1269776Y489689D02*
X1270437Y490350D01*
G01X1270253Y488539D02*
X1270914Y489200D01*
G01X1270437Y490350D02*
X1273988D01*
G01X1270914Y489200D02*
X1273511D01*
G01X1273988Y490350D02*
X1274642Y489696D01*
G01X1273511Y489200D02*
X1274165Y488546D01*
G01X1274642Y489696D02*
X1278685D01*
G01X1274165Y488546D02*
X1279162D01*
G01X1278685Y489696D02*
X1292070Y503081D01*
G01X1279162Y488546D02*
X1292547Y501931D01*
G01X1294760Y496532D02*
X1279000Y480772D01*
G01X1294283Y497682D02*
X1277850Y481249D01*
G01X1279000Y480772D02*
Y469673D01*
G01X1277850Y481249D02*
Y470150D01*
G01D02*
X1272700Y465000D01*
G01D02*
X1268500D01*
G01X1261275Y469775D02*
X1273624D01*
G01X1261752Y468625D02*
X1274101D01*
G01X1273624Y469775D02*
X1275060Y471211D01*
G01X1274101Y468625D02*
X1276210Y470734D01*
G01X1275060Y471211D02*
Y482159D01*
G01X1276210Y470734D02*
Y481682D01*
G01X1275060Y482159D02*
X1293239Y500338D01*
G01X1276210Y481682D02*
X1293716Y499188D01*
G01X1249950Y465900D02*
Y474823D01*
G01X1248800Y466377D02*
Y475300D01*
G01X1249950Y474823D02*
X1251577Y476450D01*
G01X1248800Y475300D02*
X1251100Y477600D01*
G01X1251577Y476450D02*
X1261100D01*
G01X1251100Y477600D02*
X1260623D01*
G01X1261100Y476450D02*
X1266900Y482250D01*
G01X1260623Y477600D02*
X1265750Y482727D01*
G01X1266900Y482250D02*
Y486914D01*
G01X1265750Y482727D02*
Y487391D01*
G01X1266900Y486914D02*
X1268525Y488539D01*
G01X1265750Y487391D02*
X1268048Y489689D01*
G01X1268525Y488539D02*
X1270253D01*
G01X1268048Y489689D02*
X1269776D01*
G01X1270253Y488539D02*
X1270914Y489200D01*
G01X1269776Y489689D02*
X1270437Y490350D01*
G01X1270914Y489200D02*
X1273511D01*
G01X1270437Y490350D02*
X1273988D01*
G01X1273511Y489200D02*
X1274165Y488546D01*
G01X1273988Y490350D02*
X1274642Y489696D01*
G01X1274165Y488546D02*
X1279162D01*
G01X1274642Y489696D02*
X1278685D01*
G01X1279162Y488546D02*
X1292547Y501931D01*
G01X1278685Y489696D02*
X1292070Y503081D01*
G01X1343695Y296004D02*
X1334323Y299889D01*
G01X1343359Y294898D02*
X1333560Y298959D01*
G01X1334323Y299888D02*
X1324727Y314284D01*
G01X1333560Y298959D02*
X1323897Y313454D01*
G01X1324727Y314284D02*
X1302135Y329343D01*
G01X1323897Y313454D02*
X1301686Y328260D01*
G01X1340844Y324348D02*
X1352662Y326711D01*
G01X1340844Y323175D02*
X1352662Y325538D01*
G01X1298544Y323951D02*
X1305276Y319464D01*
G01X1307482Y317995D02*
X1308605Y317246D01*
G01X1310811Y315776D02*
X1311934Y315027D01*
G01D02*
X1312835Y315207D01*
G01X1314139Y313557D02*
X1315262Y312808D01*
G01X1317467Y311339D02*
X1318590Y310590D01*
G01X1320795Y309121D02*
X1321918Y308372D01*
G01X1298095Y322868D02*
X1321088Y307542D01*
G01X1321918Y308372D02*
X1329598Y296851D01*
G01X1321088Y307542D02*
X1328588Y296292D01*
G01X1329598Y296851D02*
X1329636Y296768D01*
G01D02*
X1332522Y290444D01*
G01X1328588Y296289D02*
X1331612Y289668D01*
G01X1332522Y290444D02*
X1333809Y289587D01*
G01X1331612Y289668D02*
X1333360Y288503D01*
G01X1333809Y289587D02*
X1337431Y288861D01*
G01X1333360Y288503D02*
X1333583Y288458D01*
G01X1333809Y289587D02*
X1337431Y288861D01*
G01X1333583Y288459D02*
X1337431Y287688D01*
G01Y288861D02*
X1341605Y289696D01*
G01X1337431Y287688D02*
X1341605Y288523D01*
G01Y289696D02*
X1346141Y288788D01*
G01X1341605Y288523D02*
X1346141Y287615D01*
G01X1331996Y297935D02*
X1343622Y293112D01*
G01X1343286Y292006D02*
X1331232Y297006D01*
G01X1322551Y312106D02*
X1331996Y297935D01*
G01X1331232Y297006D02*
X1330963Y297410D01*
G01X1322551Y312106D02*
X1331996Y297935D01*
G01X1330963Y297410D02*
X1321721Y311276D01*
G01X1300820Y326592D02*
X1322551Y312106D01*
G01X1321721Y311276D02*
X1300371Y325509D01*
G01X1343359Y294898D02*
X1333560Y298959D01*
G01X1343695Y296004D02*
X1334323Y299889D01*
G01X1333560Y298959D02*
X1323897Y313454D01*
G01X1334323Y299888D02*
X1324727Y314284D01*
G01X1323897Y313454D02*
X1301686Y328260D01*
G01X1324727Y314284D02*
X1302135Y329343D01*
G01X1340844Y323175D02*
X1352662Y325538D01*
G01X1340844Y324348D02*
X1352662Y326711D01*
G01X1298095Y322868D02*
X1321088Y307542D01*
G01X1298544Y323951D02*
X1305276Y319464D01*
G01X1298095Y322868D02*
X1321088Y307542D01*
G01X1307482Y317995D02*
X1308605Y317246D01*
G01X1298095Y322868D02*
X1321088Y307542D01*
G01X1310811Y315776D02*
X1311934Y315027D01*
G01X1298095Y322868D02*
X1321088Y307542D01*
G01X1311934Y315027D02*
X1312835Y315207D01*
G01X1298095Y322868D02*
X1321088Y307542D01*
G01X1314139Y313557D02*
X1315262Y312808D01*
G01X1298095Y322868D02*
X1321088Y307542D01*
G01X1317467Y311339D02*
X1318590Y310590D01*
G01X1298095Y322868D02*
X1321088Y307542D01*
G01X1320795Y309121D02*
X1321918Y308372D01*
G01X1321088Y307542D02*
X1328588Y296292D01*
G01X1321918Y308372D02*
X1329598Y296851D01*
G01X1328588Y296289D02*
X1331612Y289668D01*
G01X1329598Y296851D02*
X1329636Y296768D01*
G01X1328588Y296289D02*
X1331612Y289668D01*
G01X1329636Y296768D02*
X1332522Y290444D01*
G01X1331612Y289668D02*
X1333360Y288503D01*
G01X1332522Y290444D02*
X1333809Y289587D01*
G01X1333360Y288503D02*
X1333583Y288458D01*
G01Y288459D02*
X1337431Y287688D01*
G01X1333809Y289587D02*
X1337431Y288861D01*
G01Y287688D02*
X1341605Y288523D01*
G01X1337431Y288861D02*
X1341605Y289696D01*
G01Y288523D02*
X1346141Y287615D01*
G01X1341605Y289696D02*
X1346141Y288788D01*
G01X1321721Y311276D02*
X1300371Y325509D01*
G01X1300820Y326592D02*
X1322551Y312106D01*
G01X1331232Y297006D02*
X1330963Y297410D01*
G01D02*
X1321721Y311276D01*
G01X1322551Y312106D02*
X1331996Y297935D01*
G01X1343286Y292006D02*
X1331232Y297006D01*
G01X1331996Y297935D02*
X1343622Y293112D01*
G01X1352856Y330218D02*
X1340206Y327684D01*
G01X1352856Y330218D02*
X1340206Y327684D01*
G01X1352856Y329043D02*
X1340206Y326511D01*
G01X1356772Y333973D02*
X1339531Y330523D01*
G01X1357221Y332889D02*
X1339531Y329350D01*
G01X1348070Y341315D02*
X1330963Y337895D01*
G01D02*
X1329985Y337699D01*
G01X1348070Y340142D02*
X1329904Y336509D01*
G01X1329985Y337699D02*
X1319725Y341258D01*
G01X1329904Y336509D02*
X1319644Y340068D01*
G01X1319725Y341258D02*
X1309533Y339219D01*
G01X1319644Y340068D02*
X1309533Y338046D01*
G01X1352856Y329043D02*
X1340206Y326511D01*
G01X1352856Y330218D02*
X1340206Y327684D01*
G01X1357221Y332889D02*
X1339531Y329350D01*
G01X1356772Y333973D02*
X1339531Y330523D01*
G01X1348070Y340142D02*
X1329904Y336509D01*
G01X1348070Y341315D02*
X1330963Y337895D01*
G01X1348070Y340142D02*
X1329904Y336509D01*
G01X1330963Y337895D02*
X1329985Y337699D01*
G01X1329904Y336509D02*
X1319644Y340068D01*
G01X1329985Y337699D02*
X1319725Y341258D01*
G01X1319644Y340068D02*
X1309533Y338046D01*
G01X1319725Y341258D02*
X1309533Y339219D01*
G01X1354219Y344546D02*
X1335554Y340811D01*
G01D02*
X1326342Y344595D01*
G01D02*
X1308423Y341012D01*
G01X1354219Y344546D02*
X1335554Y340811D01*
G01X1354219Y344546D02*
X1335554Y340811D01*
G01X1354219Y344546D02*
X1335554Y340811D01*
G01D02*
X1326342Y344595D01*
G01D02*
X1308423Y341012D01*
G01X1344720Y343819D02*
X1335669Y342008D01*
G01D02*
X1326457Y345792D01*
G01D02*
X1308423Y342185D01*
G01X1344720Y343819D02*
X1335669Y342008D01*
G01D02*
X1326457Y345792D01*
G01D02*
X1308423Y342185D01*
G01X1344085Y410704D02*
X1340049Y400955D01*
G01X1343147Y411447D02*
X1339052Y401554D01*
G01X1340049Y400955D02*
X1337493Y397851D01*
G01X1339052Y401554D02*
X1336780Y398795D01*
G01X1337493Y397851D02*
X1332022Y395462D01*
G01X1336780Y398795D02*
X1331853Y396644D01*
G01X1332022Y395462D02*
X1327761Y396011D01*
G01X1331853Y396644D02*
X1327758Y397172D01*
G01X1327761Y396011D02*
X1323009Y395369D01*
G01X1327758Y397172D02*
X1323028Y396533D01*
G01X1323009Y395369D02*
X1313312Y397003D01*
G01X1323028Y396533D02*
X1313311Y398170D01*
G01X1313312Y397003D02*
X1305577Y395676D01*
G01X1313311Y398170D02*
X1305256Y396788D01*
G01X1305744Y392509D02*
X1313319Y393807D01*
G01X1305423Y393621D02*
X1313317Y394974D01*
G01X1313319Y393807D02*
X1322575Y392247D01*
G01X1313317Y394974D02*
X1322594Y393411D01*
G01X1322575Y392247D02*
X1327329Y392891D01*
G01X1322594Y393411D02*
X1327325Y394052D01*
G01X1327329Y392891D02*
X1332484Y392226D01*
G01X1327325Y394052D02*
X1332315Y393408D01*
G01X1332484Y392226D02*
X1338795Y394982D01*
G01X1332315Y393408D02*
X1338082Y395927D01*
G01X1338795Y394982D02*
X1341981Y398849D01*
G01X1338082Y395927D02*
X1340984Y399448D01*
G01X1341981Y398849D02*
X1345791Y408049D01*
G01X1340984Y399448D02*
X1344853Y408792D01*
G01X1343147Y411447D02*
X1339052Y401554D01*
G01X1344085Y410704D02*
X1340049Y400955D01*
G01X1339052Y401554D02*
X1336780Y398795D01*
G01X1340049Y400955D02*
X1337493Y397851D01*
G01X1336780Y398795D02*
X1331853Y396644D01*
G01X1337493Y397851D02*
X1332022Y395462D01*
G01X1331853Y396644D02*
X1327758Y397172D01*
G01X1332022Y395462D02*
X1327761Y396011D01*
G01X1327758Y397172D02*
X1323028Y396533D01*
G01X1327761Y396011D02*
X1323009Y395369D01*
G01X1323028Y396533D02*
X1313311Y398170D01*
G01X1323009Y395369D02*
X1313312Y397003D01*
G01X1313311Y398170D02*
X1305256Y396788D01*
G01X1313312Y397003D02*
X1305577Y395676D01*
G01X1305423Y393621D02*
X1313317Y394974D01*
G01X1305744Y392509D02*
X1313319Y393807D01*
G01X1313317Y394974D02*
X1322594Y393411D01*
G01X1313319Y393807D02*
X1322575Y392247D01*
G01X1322594Y393411D02*
X1327325Y394052D01*
G01X1322575Y392247D02*
X1327329Y392891D01*
G01X1327325Y394052D02*
X1332315Y393408D01*
G01X1327329Y392891D02*
X1332484Y392226D01*
G01X1332315Y393408D02*
X1338082Y395927D01*
G01X1332484Y392226D02*
X1338795Y394982D01*
G01X1338082Y395927D02*
X1340984Y399448D01*
G01X1338795Y394982D02*
X1341981Y398849D01*
G01X1340984Y399448D02*
X1344853Y408792D01*
G01X1341981Y398849D02*
X1345791Y408049D01*
G01X1283410Y447042D02*
Y455469D01*
G01X1282260Y447519D02*
Y455946D01*
G01X1283410Y455469D02*
X1296437Y468496D01*
G01X1282260Y455946D02*
X1295960Y469646D01*
G01X1280910Y448590D02*
Y456506D01*
G01D02*
X1296279Y471875D01*
G01X1282260Y447519D02*
Y455946D01*
G01X1283410Y447042D02*
Y455469D01*
G01X1282260Y455946D02*
X1295960Y469646D01*
G01X1283410Y455469D02*
X1296437Y468496D01*
G01X1280910Y448590D02*
Y456506D01*
G01D02*
X1296279Y471875D01*
G01X1293794Y432199D02*
X1291360Y426721D01*
G01X1292225Y425834D02*
X1294710Y431428D01*
G01X1306157Y440470D02*
X1293794Y432199D01*
G01X1294710Y431428D02*
X1306507Y439320D01*
G01X1355953Y440470D02*
X1306157D01*
G01X1306507Y439320D02*
X1356302D01*
G01X1356834Y434725D02*
X1309575D01*
G01X1356485Y435875D02*
X1309098D01*
G01X1309575Y434725D02*
X1308250Y433400D01*
G01X1309098Y435875D02*
X1307100Y433877D01*
G01X1308250Y433400D02*
Y426300D01*
G01X1307100Y433877D02*
Y426777D01*
G01X1308250Y426300D02*
X1306150Y424200D01*
G01X1307100Y426777D02*
X1305673Y425350D01*
G01X1306150Y424200D02*
X1297189D01*
G01X1305673Y425350D02*
X1296960D01*
G01X1345989Y424365D02*
X1340257Y414635D01*
G01X1345109Y425137D02*
X1339388Y415427D01*
G01X1340257Y414635D02*
X1337711Y412799D01*
G01X1339388Y415427D02*
X1337256Y413889D01*
G01X1337711Y412799D02*
X1330100Y411520D01*
G01X1337256Y413889D02*
X1330112Y412689D01*
G01X1330100Y411520D02*
X1324085Y412666D01*
G01X1330112Y412689D02*
X1324102Y413834D01*
G01X1324085Y412666D02*
X1317988Y411685D01*
G01X1324102Y413834D02*
X1317672Y412799D01*
G01X1346290Y421921D02*
X1341452Y413708D01*
G01X1342321Y412916D02*
X1338651Y410270D01*
G01X1341452Y413708D02*
X1338196Y411360D01*
G01X1338651Y410270D02*
X1330274Y408862D01*
G01Y408861D02*
X1330071Y408828D01*
G01Y408829D02*
X1329869Y408867D01*
G01D02*
X1329860Y408869D01*
G01X1338196Y411360D02*
X1330084Y409997D01*
G01X1330071Y408829D02*
X1329869Y408867D01*
G01X1329860Y408869D02*
X1324048Y409976D01*
G01X1330084Y409997D02*
X1330075Y409999D01*
G01X1330274Y408861D02*
X1330071Y408828D01*
G01Y408829D02*
X1329869Y408867D01*
G01D02*
X1329860Y408869D01*
G01D02*
X1324048Y409976D01*
G01X1330075Y409999D02*
X1324065Y411144D01*
G01X1324048Y409976D02*
X1318968Y409159D01*
G01X1324065Y411144D02*
X1318652Y410273D01*
G01X1346202Y455600D02*
X1341928Y451326D01*
G01X1342580Y450351D02*
X1340358Y449430D01*
G01X1341928Y451326D02*
X1340129Y450580D01*
G01X1340358Y449430D02*
X1333714D01*
G01X1340129Y450580D02*
X1333600D01*
G01X1333714Y449430D02*
X1320852Y446856D01*
G01X1333600Y450580D02*
X1320852Y448029D01*
G01Y446856D02*
X1315441Y447938D01*
G01X1320852Y448029D02*
X1315441Y449111D01*
G01Y447938D02*
X1307715Y446392D01*
G01X1315441Y449111D02*
X1307739Y447570D01*
G01X1307715Y446392D02*
X1302822Y447577D01*
G01X1307739Y447570D02*
X1302846Y448755D01*
G01X1302822Y447577D02*
X1300030Y447020D01*
G01X1302846Y448755D02*
X1299695Y448126D01*
G01X1300030Y447019D02*
X1294302Y444647D01*
G01X1299695Y448126D02*
X1293584Y445595D01*
G01X1294302Y444647D02*
X1291280Y440813D01*
G01X1293584Y445595D02*
X1291888Y443443D01*
G01X1294302Y444647D02*
X1291280Y440813D01*
G01X1291887Y443441D02*
X1290264Y441383D01*
G01X1291280Y440813D02*
X1287415Y430379D01*
G01X1290264Y441383D02*
X1286510Y431250D01*
G01X1340194Y445600D02*
X1344404Y447344D01*
G01X1345056Y446368D02*
X1340423Y444450D01*
G01X1326202Y445600D02*
X1340194D01*
G01X1340423Y444450D02*
X1326316D01*
G01X1322842Y444928D02*
X1326202Y445600D01*
G01X1326316Y444450D02*
X1322842Y443755D01*
G01X1315441Y446408D02*
X1322842Y444928D01*
G01Y443755D02*
X1315441Y445235D01*
G01X1307684Y444857D02*
X1315441Y446408D01*
G01Y445235D02*
X1307660Y443679D01*
G01X1302791Y446042D02*
X1307684Y444857D01*
G01X1307660Y443679D02*
X1302767Y444864D01*
G01X1299859Y445456D02*
X1302791Y446042D01*
G01X1302767Y444864D02*
X1300195Y444350D01*
G01X1295389Y443604D02*
X1299859Y445456D01*
G01X1300195Y444350D02*
X1296107Y442656D01*
G01X1292605Y440071D02*
X1295389Y443604D01*
G01X1296107Y442656D02*
X1293621Y439501D01*
G01X1288279Y428395D02*
X1292605Y440071D01*
G01X1293621Y439501D02*
X1290574Y431275D01*
G01X1288279Y428395D02*
X1292605Y440071D01*
G01X1289653Y428790D02*
X1289184Y427524D01*
G01X1306507Y439320D02*
X1356302D01*
G01X1355953Y440470D02*
X1306157D01*
G01X1294710Y431428D02*
X1306507Y439320D01*
G01X1306157Y440470D02*
X1293794Y432199D01*
G01X1292225Y425834D02*
X1294710Y431428D01*
G01X1293794Y432199D02*
X1291360Y426721D01*
G01X1356485Y435875D02*
X1309098D01*
G01X1356834Y434725D02*
X1309575D01*
G01X1309098Y435875D02*
X1307100Y433877D01*
G01X1309575Y434725D02*
X1308250Y433400D01*
G01X1307100Y433877D02*
Y426777D01*
G01X1308250Y433400D02*
Y426300D01*
G01X1307100Y426777D02*
X1305673Y425350D01*
G01X1308250Y426300D02*
X1306150Y424200D01*
G01X1305673Y425350D02*
X1296960D01*
G01X1306150Y424200D02*
X1297189D01*
G01X1345109Y425137D02*
X1339388Y415427D01*
G01X1345989Y424365D02*
X1340257Y414635D01*
G01X1339388Y415427D02*
X1337256Y413889D01*
G01X1340257Y414635D02*
X1337711Y412799D01*
G01X1337256Y413889D02*
X1330112Y412689D01*
G01X1337711Y412799D02*
X1330100Y411520D01*
G01X1330112Y412689D02*
X1324102Y413834D01*
G01X1330100Y411520D02*
X1324085Y412666D01*
G01X1324102Y413834D02*
X1317672Y412799D01*
G01X1324085Y412666D02*
X1317988Y411685D01*
G01X1346290Y421921D02*
X1341452Y413708D01*
G01D02*
X1338196Y411360D01*
G01X1342321Y412916D02*
X1338651Y410270D01*
G01X1338196Y411360D02*
X1330084Y409997D01*
G01X1338651Y410270D02*
X1330274Y408862D01*
G01X1338196Y411360D02*
X1330084Y409997D01*
G01X1330075Y409999D02*
X1324065Y411144D01*
G01X1330274Y408861D02*
X1330071Y408828D01*
G01X1338196Y411360D02*
X1330084Y409997D01*
G01D02*
X1330075Y409999D01*
G01D02*
X1324065Y411144D01*
G01X1330071Y408829D02*
X1329869Y408867D01*
G01X1338196Y411360D02*
X1330084Y409997D01*
G01X1330075Y409999D02*
X1324065Y411144D01*
G01X1329869Y408867D02*
X1329860Y408869D01*
G01X1330084Y409997D02*
X1330075Y409999D01*
G01D02*
X1324065Y411144D01*
G01X1329860Y408869D02*
X1324048Y409976D01*
G01X1324065Y411144D02*
X1318652Y410273D01*
G01X1324048Y409976D02*
X1318968Y409159D01*
G01X1346202Y455600D02*
X1341928Y451326D01*
G01D02*
X1340129Y450580D01*
G01X1342580Y450351D02*
X1340358Y449430D01*
G01X1340129Y450580D02*
X1333600D01*
G01X1340358Y449430D02*
X1333714D01*
G01X1333600Y450580D02*
X1320852Y448029D01*
G01X1333714Y449430D02*
X1320852Y446856D01*
G01Y448029D02*
X1315441Y449111D01*
G01X1320852Y446856D02*
X1315441Y447938D01*
G01Y449111D02*
X1307739Y447570D01*
G01X1315441Y447938D02*
X1307715Y446392D01*
G01X1307739Y447570D02*
X1302846Y448755D01*
G01X1307715Y446392D02*
X1302822Y447577D01*
G01X1302846Y448755D02*
X1299695Y448126D01*
G01X1302822Y447577D02*
X1300030Y447020D01*
G01X1299695Y448126D02*
X1293584Y445595D01*
G01X1300030Y447019D02*
X1294302Y444647D01*
G01X1293584Y445595D02*
X1291888Y443443D01*
G01X1291887Y443441D02*
X1290264Y441383D01*
G01X1294302Y444647D02*
X1291280Y440813D01*
G01X1290264Y441383D02*
X1286510Y431250D01*
G01X1291280Y440813D02*
X1287415Y430379D01*
G01X1293621Y439501D02*
X1290574Y431275D01*
G01X1289653Y428790D02*
X1289184Y427524D01*
G01X1288279Y428395D02*
X1292605Y440071D01*
G01X1296107Y442656D02*
X1293621Y439501D01*
G01X1292605Y440071D02*
X1295389Y443604D01*
G01X1300195Y444350D02*
X1296107Y442656D01*
G01X1295389Y443604D02*
X1299859Y445456D01*
G01X1302767Y444864D02*
X1300195Y444350D01*
G01X1299859Y445456D02*
X1302791Y446042D01*
G01X1307660Y443679D02*
X1302767Y444864D01*
G01X1302791Y446042D02*
X1307684Y444857D01*
G01X1315441Y445235D02*
X1307660Y443679D01*
G01X1307684Y444857D02*
X1315441Y446408D01*
G01X1322842Y443755D02*
X1315441Y445235D01*
G01Y446408D02*
X1322842Y444928D01*
G01X1326316Y444450D02*
X1322842Y443755D01*
G01Y444928D02*
X1326202Y445600D01*
G01X1340423Y444450D02*
X1326316D01*
G01X1326202Y445600D02*
X1340194D01*
G01X1345056Y446368D02*
X1340423Y444450D01*
G01X1340194Y445600D02*
X1344404Y447344D01*
G01X1296437Y468496D02*
X1302707D01*
G01X1295960Y469646D02*
X1302230D01*
G01X1302707Y468496D02*
X1316929Y482718D01*
G01X1302230Y469646D02*
X1316452Y483868D01*
G01X1316929Y482718D02*
X1337768D01*
G01X1316452Y483868D02*
X1337650D01*
G01X1337768Y482718D02*
X1345774Y484370D01*
G01X1337650Y483868D02*
X1345767Y485543D01*
G01X1296279Y471875D02*
X1302417D01*
G01X1295802Y473025D02*
X1301940D01*
G01X1302417Y471875D02*
X1315764Y485218D01*
G01X1301940Y473025D02*
X1315286Y486368D01*
G01X1315764Y485218D02*
X1336330D01*
G01X1315286Y486368D02*
X1336214D01*
G01X1336330Y485218D02*
X1357331Y489487D01*
G01X1336214Y486368D02*
X1357213Y490637D01*
G01X1284000Y470273D02*
Y480540D01*
G01X1282850Y470750D02*
Y481017D01*
G01X1284000Y480540D02*
X1291299Y487839D01*
G01X1282850Y481017D02*
X1285076Y483243D01*
G01X1284000Y480540D02*
X1291299Y487839D01*
G01X1286950Y485117D02*
X1287905Y486072D01*
G01X1284000Y480540D02*
X1291299Y487839D01*
G01X1289778Y487945D02*
X1290733Y488900D01*
G01X1291299Y487839D02*
X1297794Y489117D01*
G01D02*
X1297853Y489135D01*
G01X1290733Y488900D02*
X1297510Y490234D01*
G01X1297794Y489117D02*
X1297853Y489135D01*
G01Y489136D02*
X1315636Y494695D01*
G01X1297510Y490234D02*
X1315460Y495845D01*
G01X1315636Y494695D02*
X1343110D01*
G01X1315460Y495845D02*
X1342999D01*
G01X1347974Y505148D02*
X1336830Y502982D01*
G01X1348424Y504063D02*
X1336840Y501811D01*
G01X1336830Y502982D02*
X1320998Y505845D01*
G01X1336838Y501811D02*
X1320942Y504686D01*
G01X1320998Y505845D02*
X1311187Y505028D01*
G01X1320941Y504685D02*
X1311628Y503910D01*
G01X1311187Y505028D02*
X1304402Y499681D01*
G01X1311627Y503910D02*
X1305113Y498777D01*
G01X1304402Y499681D02*
X1302403Y497682D01*
G01X1305113Y498765D02*
X1302880Y496532D01*
G01X1302403Y497682D02*
X1294283D01*
G01X1302880Y496532D02*
X1294760D01*
G01X1293716Y499188D02*
X1300986D01*
G01X1293239Y500338D02*
X1300509D01*
G01X1300986Y499188D02*
X1307600Y505800D01*
G01X1300509Y500338D02*
X1306948Y506776D01*
G01X1307600Y505800D02*
X1326647Y513685D01*
G01X1306948Y506776D02*
X1325819Y514587D01*
G01X1326647Y513685D02*
X1330907Y521898D01*
G01X1325819Y514587D02*
X1330105Y522850D01*
G01X1330907Y521898D02*
X1346894Y526986D01*
G01X1330105Y522850D02*
X1346715Y528136D01*
G01X1292070Y503081D02*
X1299678D01*
G01X1292547Y501931D02*
X1300155D01*
G01X1299678Y503081D02*
X1305470Y508873D01*
G01X1300155Y501931D02*
X1306122Y507897D01*
G01X1305470Y508873D02*
X1323981Y516538D01*
G01X1306122Y507897D02*
X1324813Y515635D01*
G01X1323984Y516536D02*
X1328426Y525094D01*
G01X1324813Y515635D02*
X1329228Y524142D01*
G01X1328426Y525094D02*
X1346245Y530765D01*
G01X1329228Y524142D02*
X1346424Y529615D01*
G01X1298207Y480880D02*
X1303662D01*
G01X1297730Y482030D02*
X1303185D01*
G01X1303662Y480880D02*
X1313000Y490218D01*
G01X1303185Y482030D02*
X1312523Y491368D01*
G01X1313000Y490218D02*
X1335239D01*
G01X1312523Y491368D02*
X1335122D01*
G01X1335239Y490218D02*
X1353738Y493997D01*
G01X1335122Y491368D02*
X1353047Y495030D01*
G01X1299133Y478266D02*
X1304909D01*
G01X1298656Y479416D02*
X1304432D01*
G01X1304909Y478266D02*
X1314364Y487718D01*
G01X1304432Y479416D02*
X1313887Y488868D01*
G01X1314364Y487718D02*
X1335879D01*
G01X1313887Y488868D02*
X1335763D01*
G01X1335879Y487718D02*
X1355999Y491817D01*
G01X1335763Y488868D02*
X1355308Y492851D01*
G01X1295960Y469646D02*
X1302230D01*
G01X1296437Y468496D02*
X1302707D01*
G01X1302230Y469646D02*
X1316452Y483868D01*
G01X1302707Y468496D02*
X1316929Y482718D01*
G01X1316452Y483868D02*
X1337650D01*
G01X1316929Y482718D02*
X1337768D01*
G01X1337650Y483868D02*
X1345767Y485543D01*
G01X1337768Y482718D02*
X1345774Y484370D01*
G01X1295802Y473025D02*
X1301940D01*
G01X1296279Y471875D02*
X1302417D01*
G01X1301940Y473025D02*
X1315286Y486368D01*
G01X1302417Y471875D02*
X1315764Y485218D01*
G01X1315286Y486368D02*
X1336214D01*
G01X1315764Y485218D02*
X1336330D01*
G01X1336214Y486368D02*
X1357213Y490637D01*
G01X1336330Y485218D02*
X1357331Y489487D01*
G01X1282850Y470750D02*
Y481017D01*
G01X1284000Y470273D02*
Y480540D01*
G01X1282850Y481017D02*
X1285076Y483243D01*
G01X1286950Y485117D02*
X1287905Y486072D01*
G01X1289778Y487945D02*
X1290733Y488900D01*
G01X1284000Y480540D02*
X1291299Y487839D01*
G01X1290733Y488900D02*
X1297510Y490234D01*
G01X1291299Y487839D02*
X1297794Y489117D01*
G01X1290733Y488900D02*
X1297510Y490234D01*
G01D02*
X1315460Y495845D01*
G01X1297794Y489117D02*
X1297853Y489135D01*
G01X1297510Y490234D02*
X1315460Y495845D01*
G01X1297853Y489136D02*
X1315636Y494695D01*
G01X1315460Y495845D02*
X1342999D01*
G01X1315636Y494695D02*
X1343110D01*
G01X1348424Y504063D02*
X1336840Y501811D01*
G01X1347974Y505148D02*
X1336830Y502982D01*
G01X1336838Y501811D02*
X1320942Y504686D01*
G01X1336830Y502982D02*
X1320998Y505845D01*
G01X1320941Y504685D02*
X1311628Y503910D01*
G01X1320998Y505845D02*
X1311187Y505028D01*
G01X1311627Y503910D02*
X1305113Y498777D01*
G01X1311187Y505028D02*
X1304402Y499681D01*
G01X1305113Y498765D02*
X1302880Y496532D01*
G01X1304402Y499681D02*
X1302403Y497682D01*
G01X1302880Y496532D02*
X1294760D01*
G01X1302403Y497682D02*
X1294283D01*
G01X1293239Y500338D02*
X1300509D01*
G01X1293716Y499188D02*
X1300986D01*
G01X1300509Y500338D02*
X1306948Y506776D01*
G01X1300986Y499188D02*
X1307600Y505800D01*
G01X1306948Y506776D02*
X1325819Y514587D01*
G01X1307600Y505800D02*
X1326647Y513685D01*
G01X1325819Y514587D02*
X1330105Y522850D01*
G01X1326647Y513685D02*
X1330907Y521898D01*
G01X1330105Y522850D02*
X1346715Y528136D01*
G01X1330907Y521898D02*
X1346894Y526986D01*
G01X1292547Y501931D02*
X1300155D01*
G01X1292070Y503081D02*
X1299678D01*
G01X1300155Y501931D02*
X1306122Y507897D01*
G01X1299678Y503081D02*
X1305470Y508873D01*
G01X1306122Y507897D02*
X1324813Y515635D01*
G01X1305470Y508873D02*
X1323981Y516538D01*
G01X1324813Y515635D02*
X1329228Y524142D01*
G01X1323984Y516536D02*
X1328426Y525094D01*
G01X1329228Y524142D02*
X1346424Y529615D01*
G01X1328426Y525094D02*
X1346245Y530765D01*
G01X1297730Y482030D02*
X1303185D01*
G01X1298207Y480880D02*
X1303662D01*
G01X1303185Y482030D02*
X1312523Y491368D01*
G01X1303662Y480880D02*
X1313000Y490218D01*
G01X1312523Y491368D02*
X1335122D01*
G01X1313000Y490218D02*
X1335239D01*
G01X1335122Y491368D02*
X1353047Y495030D01*
G01X1335239Y490218D02*
X1353738Y493997D01*
G01X1298656Y479416D02*
X1304432D01*
G01X1299133Y478266D02*
X1304909D01*
G01X1304432Y479416D02*
X1313887Y488868D01*
G01X1304909Y478266D02*
X1314364Y487718D01*
G01X1313887Y488868D02*
X1335763D01*
G01X1314364Y487718D02*
X1335879D01*
G01X1335763Y488868D02*
X1355308Y492851D01*
G01X1335879Y487718D02*
X1355999Y491817D01*
G01X1404498Y298280D02*
X1395346Y296449D01*
G01X1404498Y297107D02*
X1395346Y295276D01*
G01Y296449D02*
X1386147Y298289D01*
G01X1395346Y295276D02*
X1386147Y297116D01*
G01Y298289D02*
X1371250Y295310D01*
G01X1386147Y297116D02*
X1371250Y294137D01*
G01Y295310D02*
X1360062Y297548D01*
G01X1371250Y294137D02*
X1360062Y296375D01*
G01Y297548D02*
X1348018Y295139D01*
G01X1360062Y296375D02*
X1348018Y293966D01*
G01Y295139D02*
X1343695Y296004D01*
G01X1348018Y293966D02*
X1343359Y294898D01*
G01X1352662Y326711D02*
X1361038Y325037D01*
G01X1352662Y325538D02*
X1361038Y323864D01*
G01Y325037D02*
X1367234Y326277D01*
G01X1361038Y323864D02*
X1367234Y325104D01*
G01Y326277D02*
X1370466Y325630D01*
G01X1367234Y325104D02*
X1370466Y324457D01*
G01Y325630D02*
X1381365Y327810D01*
G01X1370466Y324457D02*
X1381365Y326637D01*
G01Y327810D02*
X1383054Y327471D01*
G01X1381365Y326637D02*
X1382605Y326388D01*
G01X1383054Y327471D02*
X1383243Y327346D01*
G01Y327345D02*
X1388147Y324076D01*
G01X1382605Y326388D02*
X1387698Y322993D01*
G01X1388147Y324076D02*
X1392184Y323268D01*
G01X1387698Y322993D02*
X1392184Y322095D01*
G01Y323268D02*
X1399749Y324781D01*
G01X1392184Y322095D02*
X1400198Y323698D01*
G01X1399749Y324781D02*
X1409589Y331347D01*
G01X1400198Y323698D02*
X1410419Y330518D01*
G01X1346141Y288788D02*
X1359832Y291526D01*
G01X1346141Y287615D02*
X1359832Y290353D01*
G01Y291526D02*
X1371891Y289114D01*
G01X1359832Y290353D02*
X1371891Y287941D01*
G01Y289114D02*
X1387120Y292160D01*
G01X1371891Y287941D02*
X1387120Y290987D01*
G01Y292160D02*
X1394545Y290675D01*
G01X1387120Y290987D02*
X1394545Y289502D01*
G01Y290675D02*
X1405279Y292823D01*
G01X1394545Y289502D02*
X1405279Y291650D01*
G01X1394736Y293585D02*
X1404644Y295568D01*
G01Y294395D02*
X1394736Y292412D01*
G01X1387037Y295125D02*
X1394736Y293585D01*
G01Y292412D02*
X1387037Y293952D01*
G01X1371956Y292110D02*
X1387037Y295125D01*
G01Y293952D02*
X1371956Y290937D01*
G01X1360067Y294489D02*
X1371956Y292110D01*
G01Y290937D02*
X1360067Y293316D01*
G01X1348403Y292157D02*
X1360067Y294489D01*
G01Y293316D02*
X1348403Y290984D01*
G01X1343622Y293112D02*
X1348403Y292157D01*
G01Y290984D02*
X1343286Y292006D01*
G01X1404498Y297107D02*
X1395346Y295276D01*
G01X1404498Y298280D02*
X1395346Y296449D01*
G01Y295276D02*
X1386147Y297116D01*
G01X1395346Y296449D02*
X1386147Y298289D01*
G01Y297116D02*
X1371250Y294137D01*
G01X1386147Y298289D02*
X1371250Y295310D01*
G01Y294137D02*
X1360062Y296375D01*
G01X1371250Y295310D02*
X1360062Y297548D01*
G01Y296375D02*
X1348018Y293966D01*
G01X1360062Y297548D02*
X1348018Y295139D01*
G01Y293966D02*
X1343359Y294898D01*
G01X1348018Y295139D02*
X1343695Y296004D01*
G01X1352662Y325538D02*
X1361038Y323864D01*
G01X1352662Y326711D02*
X1361038Y325037D01*
G01Y323864D02*
X1367234Y325104D01*
G01X1361038Y325037D02*
X1367234Y326277D01*
G01Y325104D02*
X1370466Y324457D01*
G01X1367234Y326277D02*
X1370466Y325630D01*
G01Y324457D02*
X1381365Y326637D01*
G01X1370466Y325630D02*
X1381365Y327810D01*
G01Y326637D02*
X1382605Y326388D01*
G01X1381365Y327810D02*
X1383054Y327471D01*
G01X1382605Y326388D02*
X1387698Y322993D01*
G01X1383054Y327471D02*
X1383243Y327346D01*
G01X1382605Y326388D02*
X1387698Y322993D01*
G01X1383243Y327345D02*
X1388147Y324076D01*
G01X1387698Y322993D02*
X1392184Y322095D01*
G01X1388147Y324076D02*
X1392184Y323268D01*
G01Y322095D02*
X1400198Y323698D01*
G01X1392184Y323268D02*
X1399749Y324781D01*
G01X1400198Y323698D02*
X1410419Y330518D01*
G01X1399749Y324781D02*
X1409589Y331347D01*
G01X1346141Y287615D02*
X1359832Y290353D01*
G01X1346141Y288788D02*
X1359832Y291526D01*
G01Y290353D02*
X1371891Y287941D01*
G01X1359832Y291526D02*
X1371891Y289114D01*
G01Y287941D02*
X1387120Y290987D01*
G01X1371891Y289114D02*
X1387120Y292160D01*
G01Y290987D02*
X1394545Y289502D01*
G01X1387120Y292160D02*
X1394545Y290675D01*
G01Y289502D02*
X1405279Y291650D01*
G01X1394545Y290675D02*
X1405279Y292823D01*
G01X1348403Y290984D02*
X1343286Y292006D01*
G01X1343622Y293112D02*
X1348403Y292157D01*
G01X1360067Y293316D02*
X1348403Y290984D01*
G01Y292157D02*
X1360067Y294489D01*
G01X1371956Y290937D02*
X1360067Y293316D01*
G01Y294489D02*
X1371956Y292110D01*
G01X1387037Y293952D02*
X1371956Y290937D01*
G01Y292110D02*
X1387037Y295125D01*
G01X1394736Y292412D02*
X1387037Y293952D01*
G01Y295125D02*
X1394736Y293585D01*
G01X1404644Y294395D02*
X1394736Y292412D01*
G01Y293585D02*
X1404644Y295568D01*
G01X1403739Y333950D02*
X1401705Y330898D01*
G01X1404822Y333501D02*
X1402535Y330068D01*
G01X1401705Y330898D02*
X1396407Y327365D01*
G01X1402535Y330068D02*
X1396856Y326282D01*
G01X1396407Y327365D02*
X1392782Y326640D01*
G01X1396856Y326282D02*
X1392783Y325467D01*
G01X1392782Y326640D02*
X1388882Y327417D01*
G01X1392783Y325467D02*
X1388433Y326333D01*
G01X1388882Y327417D02*
X1384131Y330585D01*
G01X1388433Y326333D02*
X1383682Y329502D01*
G01X1384131Y330585D02*
X1381651Y331082D01*
G01X1383682Y329502D02*
X1381651Y329909D01*
G01Y331082D02*
X1370390Y328828D01*
G01X1381651Y329909D02*
X1370390Y327655D01*
G01Y328828D02*
X1366521Y329602D01*
G01X1370390Y327655D02*
X1366521Y328429D01*
G01Y329602D02*
X1361948Y328688D01*
G01X1366521Y328429D02*
X1361948Y327515D01*
G01Y328688D02*
X1353577Y330362D01*
G01D02*
X1352856Y330218D01*
G01X1361948Y327515D02*
X1353579Y329188D01*
G01X1353577Y330362D02*
X1352856Y330218D01*
G01X1353579Y329188D02*
X1352856Y329043D01*
G01X1405020Y350851D02*
X1400092Y338949D01*
G01X1406217Y350734D02*
X1401020Y338184D01*
G01X1400092Y338949D02*
X1393319Y334468D01*
G01X1401020Y338184D02*
X1393766Y333384D01*
G01X1393319Y334468D02*
X1390751Y333954D01*
G01X1393766Y333384D02*
X1390749Y332780D01*
G01X1390751Y333954D02*
X1373399Y337483D01*
G01X1390749Y332780D02*
X1373515Y336285D01*
G01X1373399Y337483D02*
X1370012Y336075D01*
G01X1373515Y336285D02*
X1370130Y334878D01*
G01X1370012Y336075D02*
X1366336Y336809D01*
G01X1370130Y334878D02*
X1366336Y335636D01*
G01Y336809D02*
X1358765Y335299D01*
G01X1366336Y335636D02*
X1359213Y334215D01*
G01X1358765Y335299D02*
X1356772Y333973D01*
G01X1359213Y334215D02*
X1357221Y332889D01*
G01X1402348Y351103D02*
X1398035Y340690D01*
G01X1403544Y350985D02*
X1398963Y339925D01*
G01X1398035Y340690D02*
X1392692Y337153D01*
G01X1398963Y339925D02*
X1393141Y336071D01*
G01X1392692Y337153D02*
X1390195Y336642D01*
G01X1393141Y336071D02*
X1390196Y335468D01*
G01X1390195Y336642D02*
X1377252Y339277D01*
G01X1390196Y335468D02*
X1376803Y338194D01*
G01X1377252Y339277D02*
X1374057Y341393D01*
G01X1376803Y338194D02*
X1373610Y340309D01*
G01D02*
X1371398Y340751D01*
G01D02*
X1369243Y340355D01*
G01D02*
X1360995Y341661D01*
G01X1360909Y342840D02*
X1352932Y340343D01*
G01D02*
X1352856Y340358D01*
G01X1360995Y341661D02*
X1352995Y339157D01*
G01X1352932Y340343D02*
X1352856Y340358D01*
G01D02*
X1348070Y341315D01*
G01X1352995Y339157D02*
X1348070Y340142D01*
G01X1404822Y333501D02*
X1402535Y330068D01*
G01X1403739Y333950D02*
X1401705Y330898D01*
G01X1402535Y330068D02*
X1396856Y326282D01*
G01X1401705Y330898D02*
X1396407Y327365D01*
G01X1396856Y326282D02*
X1392783Y325467D01*
G01X1396407Y327365D02*
X1392782Y326640D01*
G01X1392783Y325467D02*
X1388433Y326333D01*
G01X1392782Y326640D02*
X1388882Y327417D01*
G01X1388433Y326333D02*
X1383682Y329502D01*
G01X1388882Y327417D02*
X1384131Y330585D01*
G01X1383682Y329502D02*
X1381651Y329909D01*
G01X1384131Y330585D02*
X1381651Y331082D01*
G01Y329909D02*
X1370390Y327655D01*
G01X1381651Y331082D02*
X1370390Y328828D01*
G01Y327655D02*
X1366521Y328429D01*
G01X1370390Y328828D02*
X1366521Y329602D01*
G01Y328429D02*
X1361948Y327515D01*
G01X1366521Y329602D02*
X1361948Y328688D01*
G01Y327515D02*
X1353579Y329188D01*
G01X1361948Y328688D02*
X1353577Y330362D01*
G01X1361948Y327515D02*
X1353579Y329188D01*
G01D02*
X1352856Y329043D01*
G01X1353577Y330362D02*
X1352856Y330218D01*
G01X1353579Y329188D02*
X1352856Y329043D01*
G01X1406217Y350734D02*
X1401020Y338184D01*
G01X1405020Y350851D02*
X1400092Y338949D01*
G01X1401020Y338184D02*
X1393766Y333384D01*
G01X1400092Y338949D02*
X1393319Y334468D01*
G01X1393766Y333384D02*
X1390749Y332780D01*
G01X1393319Y334468D02*
X1390751Y333954D01*
G01X1390749Y332780D02*
X1373515Y336285D01*
G01X1390751Y333954D02*
X1373399Y337483D01*
G01X1373515Y336285D02*
X1370130Y334878D01*
G01X1373399Y337483D02*
X1370012Y336075D01*
G01X1370130Y334878D02*
X1366336Y335636D01*
G01X1370012Y336075D02*
X1366336Y336809D01*
G01Y335636D02*
X1359213Y334215D01*
G01X1366336Y336809D02*
X1358765Y335299D01*
G01X1359213Y334215D02*
X1357221Y332889D01*
G01X1358765Y335299D02*
X1356772Y333973D01*
G01X1403544Y350985D02*
X1398963Y339925D01*
G01X1402348Y351103D02*
X1398035Y340690D01*
G01X1398963Y339925D02*
X1393141Y336071D01*
G01X1398035Y340690D02*
X1392692Y337153D01*
G01X1393141Y336071D02*
X1390196Y335468D01*
G01X1392692Y337153D02*
X1390195Y336642D01*
G01X1390196Y335468D02*
X1376803Y338194D01*
G01X1390195Y336642D02*
X1377252Y339277D01*
G01X1376803Y338194D02*
X1373610Y340309D01*
G01X1377252Y339277D02*
X1374057Y341393D01*
G01X1373610Y340309D02*
X1371398Y340751D01*
G01D02*
X1369243Y340355D01*
G01D02*
X1360995Y341661D01*
G01D02*
X1352995Y339157D01*
G01X1360909Y342840D02*
X1352932Y340343D01*
G01X1360995Y341661D02*
X1352995Y339157D01*
G01D02*
X1348070Y340142D01*
G01X1352932Y340343D02*
X1352856Y340358D01*
G01X1352995Y339157D02*
X1348070Y340142D01*
G01X1352856Y340358D02*
X1348070Y341315D01*
G01X1396131Y342775D02*
X1391895Y339970D01*
G01X1397064Y342012D02*
X1394648Y340412D01*
G01X1396131Y342775D02*
X1391895Y339970D01*
G01X1394648Y340413D02*
X1392345Y338888D01*
G01X1391895Y339970D02*
X1389224Y339420D01*
G01X1392345Y338888D02*
X1389226Y338246D01*
G01X1389224Y339420D02*
X1379343Y341424D01*
G01X1389226Y338246D02*
X1378895Y340341D01*
G01D02*
X1370685Y345774D01*
G01X1397064Y342012D02*
X1394648Y340412D01*
G01Y340413D02*
X1392345Y338888D01*
G01X1396131Y342775D02*
X1391895Y339970D01*
G01X1392345Y338888D02*
X1389226Y338246D01*
G01X1391895Y339970D02*
X1389224Y339420D01*
G01X1389226Y338246D02*
X1378895Y340341D01*
G01X1389224Y339420D02*
X1379343Y341424D01*
G01X1378895Y340341D02*
X1370685Y345774D01*
G01X1405458Y395986D02*
X1403615Y386777D01*
G01D02*
X1404635Y381680D01*
G01D02*
X1402585Y368664D01*
G01D02*
X1405466Y361715D01*
G01X1402585Y368664D02*
X1405466Y361715D01*
G01X1420416Y409859D02*
X1403130Y397449D01*
G01X1403040Y397004D02*
X1403041D01*
G01D02*
X1400967Y386631D01*
G01X1404169Y396779D02*
X1402140Y386631D01*
G01X1400967D02*
X1401803Y382452D01*
G01X1402140Y386631D02*
X1402972Y382476D01*
G01X1401803Y382452D02*
X1399626Y368632D01*
G01X1402972Y382476D02*
X1400813Y368773D01*
G01X1399626Y368632D02*
X1403180Y360057D01*
G01X1400813Y368773D02*
X1404286Y360393D01*
G01X1403180Y360057D02*
X1405020Y350851D01*
G01X1417983Y411379D02*
X1400752Y399011D01*
G01X1419429Y411000D02*
X1401791Y398341D01*
G01X1400683Y398666D02*
X1398312Y386804D01*
G01X1401791Y398341D02*
X1399485Y386804D01*
G01X1398312D02*
X1398979Y383467D01*
G01X1399485Y386804D02*
X1400147Y383491D01*
G01X1398979Y383467D02*
X1396710Y369064D01*
G01X1400147Y383491D02*
X1397897Y369205D01*
G01X1396710Y369064D02*
X1400681Y359485D01*
G01X1397897Y369205D02*
X1401787Y359821D01*
G01X1400681Y359485D02*
X1402348Y351103D01*
G01X1401787Y359821D02*
X1403544Y350985D01*
G01X1374057Y341393D02*
X1371407Y341922D01*
G01D02*
X1369229Y341522D01*
G01D02*
X1360909Y342840D01*
G01X1405458Y395986D02*
X1403615Y386777D01*
G01D02*
X1404635Y381680D01*
G01D02*
X1402585Y368664D01*
G01D02*
X1405466Y361715D01*
G01X1420416Y409859D02*
X1403130Y397449D01*
G01X1403040Y397004D02*
X1403041D01*
G01X1404169Y396779D02*
X1402140Y386631D01*
G01X1403041Y397004D02*
X1400967Y386631D01*
G01X1402140D02*
X1402972Y382476D01*
G01X1400967Y386631D02*
X1401803Y382452D01*
G01X1402972Y382476D02*
X1400813Y368773D01*
G01X1401803Y382452D02*
X1399626Y368632D01*
G01X1400813Y368773D02*
X1404286Y360393D01*
G01X1399626Y368632D02*
X1403180Y360057D01*
G01D02*
X1405020Y350851D01*
G01X1419429Y411000D02*
X1401791Y398341D01*
G01X1419429Y411000D02*
X1401791Y398341D01*
G01X1417983Y411379D02*
X1400752Y399011D01*
G01X1401791Y398341D02*
X1399485Y386804D01*
G01X1400683Y398666D02*
X1398312Y386804D01*
G01X1399485D02*
X1400147Y383491D01*
G01X1398312Y386804D02*
X1398979Y383467D01*
G01X1400147Y383491D02*
X1397897Y369205D01*
G01X1398979Y383467D02*
X1396710Y369064D01*
G01X1397897Y369205D02*
X1401787Y359821D01*
G01X1396710Y369064D02*
X1400681Y359485D01*
G01X1401787Y359821D02*
X1403544Y350985D01*
G01X1400681Y359485D02*
X1402348Y351103D01*
G01X1374057Y341393D02*
X1371407Y341922D01*
G01D02*
X1369229Y341522D01*
G01D02*
X1360909Y342840D01*
G01X1416296Y413488D02*
X1398088Y400418D01*
G01X1417215Y412731D02*
X1399127Y399748D01*
G01X1398088Y400418D02*
X1397737Y398666D01*
G01X1399127Y399748D02*
X1398910Y398666D01*
G01X1397737D02*
X1395551Y387740D01*
G01X1398910Y398666D02*
X1396724Y387740D01*
G01X1395551D02*
X1396263Y384180D01*
G01X1396724Y387740D02*
X1397436Y384180D01*
G01X1396263D02*
X1393388Y369798D01*
G01X1397436Y384180D02*
X1394585Y369915D01*
G01X1393388Y369798D02*
X1398073Y358493D01*
G01X1394585Y369915D02*
X1399179Y358830D01*
G01X1398073Y358493D02*
X1399537Y351187D01*
G01X1399201Y358718D02*
X1400733Y351075D01*
G01X1399537Y351187D02*
X1396131Y342775D01*
G01X1400733Y351075D02*
X1397064Y342012D01*
G01X1379343Y341424D02*
X1371132Y346858D01*
G01D02*
X1369804Y347124D01*
G01X1370685Y345774D02*
X1369803Y345951D01*
G01X1369804Y347124D02*
X1365752Y346317D01*
G01X1369803Y345951D02*
X1367776Y345547D01*
G01X1369804Y347124D02*
X1365752Y346317D01*
G01X1367776Y345546D02*
X1365752Y345144D01*
G01Y346317D02*
X1358665Y347734D01*
G01X1365752Y345144D02*
X1358665Y346561D01*
G01Y347734D02*
X1356182Y347237D01*
G01X1358665Y346561D02*
X1356631Y346154D01*
G01X1356182Y347237D02*
X1353770Y345629D01*
G01X1356631Y346154D02*
X1354219Y344546D01*
G01X1353770Y345629D02*
X1344721Y343819D01*
G01D02*
X1344720D01*
G01X1417215Y412731D02*
X1399127Y399748D01*
G01X1416296Y413488D02*
X1398088Y400418D01*
G01X1399127Y399748D02*
X1398910Y398666D01*
G01X1398088Y400418D02*
X1397737Y398666D01*
G01X1398910D02*
X1396724Y387740D01*
G01X1397737Y398666D02*
X1395551Y387740D01*
G01X1396724D02*
X1397436Y384180D01*
G01X1395551Y387740D02*
X1396263Y384180D01*
G01X1397436D02*
X1394585Y369915D01*
G01X1396263Y384180D02*
X1393388Y369798D01*
G01X1394585Y369915D02*
X1399179Y358830D01*
G01X1393388Y369798D02*
X1398073Y358493D01*
G01X1399201Y358718D02*
X1400733Y351075D01*
G01X1398073Y358493D02*
X1399537Y351187D01*
G01X1400733Y351075D02*
X1397064Y342012D01*
G01X1399537Y351187D02*
X1396131Y342775D01*
G01X1379343Y341424D02*
X1371132Y346858D01*
G01X1370685Y345774D02*
X1369803Y345951D01*
G01X1371132Y346858D02*
X1369804Y347124D01*
G01X1369803Y345951D02*
X1367776Y345547D01*
G01Y345546D02*
X1365752Y345144D01*
G01X1369804Y347124D02*
X1365752Y346317D01*
G01Y345144D02*
X1358665Y346561D01*
G01X1365752Y346317D02*
X1358665Y347734D01*
G01Y346561D02*
X1356631Y346154D01*
G01X1358665Y347734D02*
X1356182Y347237D01*
G01X1356631Y346154D02*
X1354219Y344546D01*
G01X1356182Y347237D02*
X1353770Y345629D01*
G01D02*
X1344721Y343819D01*
G01D02*
X1344720D01*
G01X1363478Y445500D02*
X1355953Y440470D01*
G01X1356302Y439320D02*
X1363827Y444349D01*
G01X1396736Y445500D02*
X1363478D01*
G01X1363828Y444350D02*
X1397213D01*
G01X1399610Y448374D02*
X1396736Y445500D01*
G01X1397213Y444350D02*
X1400262Y447398D01*
G01X1405322Y450741D02*
X1399610Y448374D01*
G01X1400262Y447398D02*
X1405974Y449765D01*
G01X1404373Y437300D02*
X1398126D01*
G01X1404850Y438450D02*
X1398603D01*
G01X1398126Y437300D02*
X1395998Y439428D01*
G01X1398603Y438450D02*
X1396475Y440578D01*
G01X1395998Y439428D02*
X1363872D01*
G01X1396475Y440578D02*
X1363520D01*
G01X1363872Y439428D02*
X1356834Y434725D01*
G01X1363520Y440578D02*
X1361618Y439307D01*
G01X1363872Y439428D02*
X1356834Y434725D01*
G01X1361618Y439306D02*
X1356485Y435875D01*
G01X1400948Y431700D02*
X1399072D01*
G01X1400948Y432850D02*
X1399549D01*
G01X1399072Y431700D02*
X1396362Y434410D01*
G01X1399549Y432850D02*
X1396839Y435560D01*
G01X1396362Y434410D02*
X1383686D01*
G01X1396839Y435560D02*
X1383523D01*
G01X1383686Y434410D02*
X1366111Y429409D01*
G01D02*
X1365958Y429366D01*
G01X1383523Y435560D02*
X1365797Y430516D01*
G01X1366111Y429409D02*
X1365958Y429366D01*
G01D02*
X1355120D01*
G01X1365797Y430516D02*
X1354891D01*
G01X1355120Y429366D02*
X1349306Y426959D01*
G01X1354891Y430516D02*
X1348721Y427962D01*
G01X1349306Y426959D02*
X1345989Y424365D01*
G01X1348721Y427962D02*
X1345109Y425137D01*
G01X1406974Y426076D02*
X1400702D01*
G01X1407451Y427226D02*
X1400931D01*
G01X1400702Y426076D02*
X1399194Y426699D01*
G01X1400931Y427226D02*
X1399846Y427675D01*
G01X1399194Y426699D02*
X1397177Y428716D01*
G01Y428717D02*
X1396504Y429390D01*
G01X1399846Y427675D02*
X1396981Y430540D01*
G01X1396504Y429390D02*
X1383756D01*
G01X1396981Y430540D02*
X1383563D01*
G01X1383756Y429390D02*
X1359570Y421081D01*
G01X1383563Y430540D02*
X1359585Y422303D01*
G01X1359570Y421081D02*
X1353650Y423286D01*
G01X1359585Y422303D02*
X1353663Y424510D01*
G01X1353650Y423286D02*
X1347068Y420975D01*
G01X1353663Y424510D02*
X1346290Y421921D01*
G01X1347068Y420975D02*
X1342321Y412916D01*
G01X1405203Y418530D02*
X1403398D01*
G01D02*
X1401602Y420326D01*
G01X1403875Y419680D02*
X1402752Y420803D01*
G01X1401602Y420326D02*
Y422616D01*
G01X1402752Y420803D02*
Y423093D01*
G01X1401602Y422616D02*
X1400981Y423237D01*
G01X1402752Y423093D02*
X1401631Y424214D01*
G01X1400979Y423238D02*
X1399611Y423806D01*
G01X1401631Y424214D02*
X1399841Y424956D01*
G01X1399611Y423806D02*
X1392069D01*
G01X1399841Y424956D02*
X1391956D01*
G01X1392069Y423806D02*
X1351009Y415678D01*
G01X1391956Y424956D02*
X1350541Y416758D01*
G01X1351009Y415678D02*
X1344085Y410704D01*
G01X1350541Y416758D02*
X1343147Y411447D01*
G01X1345791Y408049D02*
X1352886Y413158D01*
G01X1344853Y408792D02*
X1352420Y414240D01*
G01X1352889Y413159D02*
X1392463Y420861D01*
G01X1352423Y414241D02*
X1392455Y422032D01*
G01X1392463Y420861D02*
X1398099Y419847D01*
G01X1392455Y422032D02*
X1398724Y420903D01*
G01X1398099Y419847D02*
X1399601Y417995D01*
G01X1398724Y420903D02*
X1400751Y418403D01*
G01X1399601Y417995D02*
Y412178D01*
G01X1400751Y418403D02*
Y412655D01*
G01X1399601Y412178D02*
X1401573Y410206D01*
G01X1400751Y412655D02*
X1402050Y411356D01*
G01X1401573Y410206D02*
X1404973D01*
G01X1402050Y411356D02*
X1404973D01*
G01X1394924Y454872D02*
X1392713D01*
G01X1394768Y456022D02*
X1392236D01*
G01X1394924Y454872D02*
X1392713D01*
G01D02*
X1392291Y454450D01*
G01X1392236Y456022D02*
X1391814Y455600D01*
G01X1392291Y454450D02*
X1346679D01*
G01X1391814Y455600D02*
X1346202D01*
G01X1346679Y454450D02*
X1342580Y450351D01*
G01X1401006Y456150D02*
X1402061D01*
G01X1402361Y455000D02*
X1401483D01*
G01X1399933Y455077D02*
X1401006Y456150D01*
G01X1401483Y455000D02*
X1401083Y454600D01*
G01X1399933Y452800D02*
Y455077D01*
G01X1401083Y454600D02*
Y452323D01*
G01X1399113Y451980D02*
X1399933Y452800D01*
G01X1401083Y452323D02*
X1399765Y451005D01*
G01X1395786Y450600D02*
X1399113Y451980D01*
G01X1399765Y451005D02*
X1396016Y449450D01*
G01X1347660Y450600D02*
X1395786D01*
G01X1396016Y449450D02*
X1348137D01*
G01X1344404Y447344D02*
X1347660Y450600D01*
G01X1348137Y449450D02*
X1345056Y446368D01*
G01X1400262Y447398D02*
X1405974Y449765D01*
G01X1405322Y450741D02*
X1399610Y448374D01*
G01X1397213Y444350D02*
X1400262Y447398D01*
G01X1399610Y448374D02*
X1396736Y445500D01*
G01X1363828Y444350D02*
X1397213D01*
G01X1396736Y445500D02*
X1363478D01*
G01X1356302Y439320D02*
X1363827Y444349D01*
G01X1363478Y445500D02*
X1355953Y440470D01*
G01X1404850Y438450D02*
X1398603D01*
G01X1404373Y437300D02*
X1398126D01*
G01X1398603Y438450D02*
X1396475Y440578D01*
G01X1398126Y437300D02*
X1395998Y439428D01*
G01X1396475Y440578D02*
X1363520D01*
G01X1395998Y439428D02*
X1363872D01*
G01X1363520Y440578D02*
X1361618Y439307D01*
G01Y439306D02*
X1356485Y435875D01*
G01X1363872Y439428D02*
X1356834Y434725D01*
G01X1400948Y432850D02*
X1399549D01*
G01X1400948Y431700D02*
X1399072D01*
G01X1399549Y432850D02*
X1396839Y435560D01*
G01X1399072Y431700D02*
X1396362Y434410D01*
G01X1396839Y435560D02*
X1383523D01*
G01X1396362Y434410D02*
X1383686D01*
G01X1383523Y435560D02*
X1365797Y430516D01*
G01X1383686Y434410D02*
X1366111Y429409D01*
G01X1383523Y435560D02*
X1365797Y430516D01*
G01D02*
X1354891D01*
G01X1366111Y429409D02*
X1365958Y429366D01*
G01X1365797Y430516D02*
X1354891D01*
G01X1365958Y429366D02*
X1355120D01*
G01X1354891Y430516D02*
X1348721Y427962D01*
G01X1355120Y429366D02*
X1349306Y426959D01*
G01X1348721Y427962D02*
X1345109Y425137D01*
G01X1349306Y426959D02*
X1345989Y424365D01*
G01X1407451Y427226D02*
X1400931D01*
G01X1406974Y426076D02*
X1400702D01*
G01X1400931Y427226D02*
X1399846Y427675D01*
G01X1400702Y426076D02*
X1399194Y426699D01*
G01X1399846Y427675D02*
X1396981Y430540D01*
G01X1399194Y426699D02*
X1397177Y428716D01*
G01X1399846Y427675D02*
X1396981Y430540D01*
G01X1397177Y428717D02*
X1396504Y429390D01*
G01X1396981Y430540D02*
X1383563D01*
G01X1396504Y429390D02*
X1383756D01*
G01X1383563Y430540D02*
X1359585Y422303D01*
G01X1383756Y429390D02*
X1359570Y421081D01*
G01X1359585Y422303D02*
X1353663Y424510D01*
G01X1359570Y421081D02*
X1353650Y423286D01*
G01X1353663Y424510D02*
X1346290Y421921D01*
G01X1353650Y423286D02*
X1347068Y420975D01*
G01D02*
X1342321Y412916D01*
G01X1405203Y418530D02*
X1403398D01*
G01X1403875Y419680D02*
X1402752Y420803D01*
G01X1403398Y418530D02*
X1401602Y420326D01*
G01X1402752Y420803D02*
Y423093D01*
G01X1401602Y420326D02*
Y422616D01*
G01X1402752Y423093D02*
X1401631Y424214D01*
G01X1401602Y422616D02*
X1400981Y423237D01*
G01X1401631Y424214D02*
X1399841Y424956D01*
G01X1400979Y423238D02*
X1399611Y423806D01*
G01X1399841Y424956D02*
X1391956D01*
G01X1399611Y423806D02*
X1392069D01*
G01X1391956Y424956D02*
X1350541Y416758D01*
G01X1392069Y423806D02*
X1351009Y415678D01*
G01X1350541Y416758D02*
X1343147Y411447D01*
G01X1351009Y415678D02*
X1344085Y410704D01*
G01X1344853Y408792D02*
X1352420Y414240D01*
G01X1345791Y408049D02*
X1352886Y413158D01*
G01X1352423Y414241D02*
X1392455Y422032D01*
G01X1352889Y413159D02*
X1392463Y420861D01*
G01X1392455Y422032D02*
X1398724Y420903D01*
G01X1392463Y420861D02*
X1398099Y419847D01*
G01X1398724Y420903D02*
X1400751Y418403D01*
G01X1398099Y419847D02*
X1399601Y417995D01*
G01X1400751Y418403D02*
Y412655D01*
G01X1399601Y417995D02*
Y412178D01*
G01X1400751Y412655D02*
X1402050Y411356D01*
G01X1399601Y412178D02*
X1401573Y410206D01*
G01X1402050Y411356D02*
X1404973D01*
G01X1401573Y410206D02*
X1404973D01*
G01X1394768Y456022D02*
X1392236D01*
G01D02*
X1391814Y455600D01*
G01X1394924Y454872D02*
X1392713D01*
G01X1392236Y456022D02*
X1391814Y455600D01*
G01X1392713Y454872D02*
X1392291Y454450D01*
G01X1391814Y455600D02*
X1346202D01*
G01X1392291Y454450D02*
X1346679D01*
G01D02*
X1342580Y450351D01*
G01X1348137Y449450D02*
X1345056Y446368D01*
G01X1344404Y447344D02*
X1347660Y450600D01*
G01X1396016Y449450D02*
X1348137D01*
G01X1347660Y450600D02*
X1395786D01*
G01X1399765Y451005D02*
X1396016Y449450D01*
G01X1395786Y450600D02*
X1399113Y451980D01*
G01X1401083Y452323D02*
X1399765Y451005D01*
G01X1399113Y451980D02*
X1399933Y452800D01*
G01X1401083Y454600D02*
Y452323D01*
G01X1399933Y452800D02*
Y455077D01*
G01X1401483Y455000D02*
X1401083Y454600D01*
G01X1399933Y455077D02*
X1401006Y456150D01*
G01X1402361Y455000D02*
X1401483D01*
G01X1401006Y456150D02*
X1402061D01*
G01X1373953Y458575D02*
Y459781D01*
G01X1375103Y458575D02*
Y459304D01*
G01X1373953Y459781D02*
X1375408Y461236D01*
G01X1375103Y459304D02*
X1375885Y460086D01*
G01X1375408Y461236D02*
X1441965D01*
G01X1375885Y460086D02*
X1381760D01*
G01X1375408Y461236D02*
X1441965D01*
G01X1384410Y460086D02*
X1385760D01*
G01X1375408Y461236D02*
X1441965D01*
G01X1388410Y460086D02*
X1398449D01*
G01X1375408Y461236D02*
X1441965D01*
G01X1401099Y460086D02*
X1413427D01*
G01X1375408Y461236D02*
X1441965D01*
G01X1375408D02*
X1441965D01*
G01X1375408D02*
X1441965D01*
G01X1375408D02*
X1441965D01*
G01X1375103Y458575D02*
Y459304D01*
G01X1373953Y458575D02*
Y459781D01*
G01X1375103Y459304D02*
X1375885Y460086D01*
G01X1373953Y459781D02*
X1375408Y461236D01*
G01X1375885Y460086D02*
X1381760D01*
G01X1384410D02*
X1385760D01*
G01X1388410D02*
X1398449D01*
G01X1401099D02*
X1413427D01*
G01X1375408Y461236D02*
X1441965D01*
G01X1345774Y484370D02*
X1354541Y482666D01*
G01X1345767Y485543D02*
X1355106Y483728D01*
G01X1354541Y482666D02*
X1358708Y478498D01*
G01X1355106Y483728D02*
X1359186Y479648D01*
G01X1358708Y478498D02*
X1366967D01*
G01X1359186Y479648D02*
X1366856D01*
G01X1366967Y478498D02*
X1374359Y479935D01*
G01X1366856Y479648D02*
X1374359Y481107D01*
G01Y479935D02*
X1381751Y478498D01*
G01X1374359Y481107D02*
X1381862Y479648D01*
G01X1381751Y478498D02*
X1383931D01*
G01X1381862Y479648D02*
X1383820D01*
G01X1383931Y478498D02*
X1388818Y479448D01*
G01X1383820Y479648D02*
X1388369Y480533D01*
G01X1388818Y479448D02*
X1402363Y488581D01*
G01X1388369Y480533D02*
X1394952Y484972D01*
G01X1388818Y479448D02*
X1402363Y488581D01*
G01X1394952Y484972D02*
X1401534Y489410D01*
G01X1402363Y488581D02*
X1405280Y492907D01*
G01X1401534Y489410D02*
X1404493Y493799D01*
G01X1357331Y489487D02*
X1379124D01*
G01X1357213Y490637D02*
X1379013D01*
G01X1379124Y489487D02*
X1382172Y490079D01*
G01X1379013Y490637D02*
X1382172Y491251D01*
G01Y490079D02*
X1384954Y489539D01*
G01X1382172Y491251D02*
X1384954Y490711D01*
G01Y489539D02*
X1387703Y490073D01*
G01X1384954Y490711D02*
X1387703Y491245D01*
G01Y490073D02*
X1391246Y489384D01*
G01X1387703Y491245D02*
X1391246Y490556D01*
G01Y489384D02*
X1394500Y490017D01*
G01X1391246Y490556D02*
X1394051Y491102D01*
G01X1394500Y490017D02*
X1397888Y492301D01*
G01X1397889Y492303D02*
X1401001Y494401D01*
G01X1394051Y491102D02*
X1400440Y495411D01*
G01X1401001Y494401D02*
X1414380Y500380D01*
G01X1400440Y495411D02*
X1414134Y501530D01*
G01X1343110Y494695D02*
X1351192Y496267D01*
G01X1342999Y495845D02*
X1350505Y497305D01*
G01X1351192Y496267D02*
X1354509Y501182D01*
G01X1350505Y497305D02*
X1353680Y502011D01*
G01X1354509Y501182D02*
X1359155Y504316D01*
G01X1353680Y502011D02*
X1358706Y505401D01*
G01X1359155Y504316D02*
X1366815Y505804D01*
G01X1358706Y505401D02*
X1366893Y506991D01*
G01X1366815Y505804D02*
X1371584Y504203D01*
G01X1366893Y506991D02*
X1371665Y505390D01*
G01X1371584Y504203D02*
X1386745Y507093D01*
G01X1371665Y505390D02*
X1386783Y508271D01*
G01X1386745Y507093D02*
X1401491Y503294D01*
G01X1386783Y508271D02*
X1394084Y506391D01*
G01X1386745Y507093D02*
X1401491Y503294D01*
G01X1394084Y506390D02*
X1401389Y504508D01*
G01X1401491Y503294D02*
X1412148Y508050D01*
G01X1401389Y504508D02*
X1411903Y509200D01*
G01X1406681Y516029D02*
X1400145Y514759D01*
G01X1406681Y514857D02*
X1400595Y513674D01*
G01X1400145Y514759D02*
X1393143Y510034D01*
G01X1400595Y513674D02*
X1393391Y508814D01*
G01X1393143Y510034D02*
X1387343Y511162D01*
G01X1393391Y508814D02*
X1387343Y509990D01*
G01Y511162D02*
X1374709Y508706D01*
G01X1387343Y509990D02*
X1374709Y507534D01*
G01Y508706D02*
X1372532Y509130D01*
G01X1374709Y507534D02*
X1371844Y508091D01*
G01X1372532Y509130D02*
X1370644Y511929D01*
G01X1371844Y508091D02*
X1369956Y510890D01*
G01X1370644Y511929D02*
X1362649Y513482D01*
G01X1369956Y510890D02*
X1362649Y512310D01*
G01Y513482D02*
X1354806Y511959D01*
G01X1362649Y512310D02*
X1355256Y510874D01*
G01X1354806Y511959D02*
X1352688Y510529D01*
G01X1355256Y510874D02*
X1353517Y509701D01*
G01X1352688Y510529D02*
X1349964Y506491D01*
G01X1353517Y509701D02*
X1350793Y505663D01*
G01X1349964Y506491D02*
X1347974Y505148D01*
G01X1350793Y505663D02*
X1348424Y504063D01*
G01X1399228Y526986D02*
X1409291Y516923D01*
G01X1399705Y528136D02*
X1409943Y517898D01*
G01X1353738Y493997D02*
X1357998Y500313D01*
G01X1353047Y495030D02*
X1357169Y501142D01*
G01X1357998Y500313D02*
X1360382Y501920D01*
G01X1357169Y501142D02*
X1359932Y503005D01*
G01X1360382Y501920D02*
X1366741Y503162D01*
G01X1359932Y503005D02*
X1366827Y504351D01*
G01X1366741Y503162D02*
X1371516Y501489D01*
G01X1366827Y504351D02*
X1371605Y502677D01*
G01X1371516Y501489D02*
X1386616Y504364D01*
G01X1371605Y502677D02*
X1386649Y505542D01*
G01X1386616Y504364D02*
X1401997Y500524D01*
G01X1386649Y505542D02*
X1394269Y503640D01*
G01X1386616Y504364D02*
X1401997Y500524D01*
G01X1394268Y503639D02*
X1401890Y501737D01*
G01X1401997Y500524D02*
X1413047Y505464D01*
G01X1401890Y501737D02*
X1412801Y506614D01*
G01X1355999Y491817D02*
X1360858Y499018D01*
G01X1355308Y492851D02*
X1360029Y499846D01*
G01X1360858Y499018D02*
X1361738Y499613D01*
G01X1360029Y499846D02*
X1361288Y500697D01*
G01X1361738Y499613D02*
X1366533Y500552D01*
G01X1361288Y500697D02*
X1366619Y501741D01*
G01X1366533Y500552D02*
X1371684Y498743D01*
G01X1366619Y501741D02*
X1371772Y499931D01*
G01X1371684Y498743D02*
X1386715Y501604D01*
G01X1371772Y499931D02*
X1386748Y502782D01*
G01X1386715Y501604D02*
X1402264Y497722D01*
G01X1386748Y502782D02*
X1402157Y498935D01*
G01X1402264Y497722D02*
X1413966Y502955D01*
G01X1402157Y498935D02*
X1413720Y504105D01*
G01X1345767Y485543D02*
X1355106Y483728D01*
G01X1345774Y484370D02*
X1354541Y482666D01*
G01X1355106Y483728D02*
X1359186Y479648D01*
G01X1354541Y482666D02*
X1358708Y478498D01*
G01X1359186Y479648D02*
X1366856D01*
G01X1358708Y478498D02*
X1366967D01*
G01X1366856Y479648D02*
X1374359Y481107D01*
G01X1366967Y478498D02*
X1374359Y479935D01*
G01Y481107D02*
X1381862Y479648D01*
G01X1374359Y479935D02*
X1381751Y478498D01*
G01X1381862Y479648D02*
X1383820D01*
G01X1381751Y478498D02*
X1383931D01*
G01X1383820Y479648D02*
X1388369Y480533D01*
G01X1383931Y478498D02*
X1388818Y479448D01*
G01X1388369Y480533D02*
X1394952Y484972D01*
G01D02*
X1401534Y489410D01*
G01X1388818Y479448D02*
X1402363Y488581D01*
G01X1401534Y489410D02*
X1404493Y493799D01*
G01X1402363Y488581D02*
X1405280Y492907D01*
G01X1357213Y490637D02*
X1379013D01*
G01X1357331Y489487D02*
X1379124D01*
G01X1379013Y490637D02*
X1382172Y491251D01*
G01X1379124Y489487D02*
X1382172Y490079D01*
G01Y491251D02*
X1384954Y490711D01*
G01X1382172Y490079D02*
X1384954Y489539D01*
G01Y490711D02*
X1387703Y491245D01*
G01X1384954Y489539D02*
X1387703Y490073D01*
G01Y491245D02*
X1391246Y490556D01*
G01X1387703Y490073D02*
X1391246Y489384D01*
G01Y490556D02*
X1394051Y491102D01*
G01X1391246Y489384D02*
X1394500Y490017D01*
G01X1394051Y491102D02*
X1400440Y495411D01*
G01X1394500Y490017D02*
X1397888Y492301D01*
G01X1394051Y491102D02*
X1400440Y495411D01*
G01X1397889Y492303D02*
X1401001Y494401D01*
G01X1400440Y495411D02*
X1414134Y501530D01*
G01X1401001Y494401D02*
X1414380Y500380D01*
G01X1342999Y495845D02*
X1350505Y497305D01*
G01X1343110Y494695D02*
X1351192Y496267D01*
G01X1350505Y497305D02*
X1353680Y502011D01*
G01X1351192Y496267D02*
X1354509Y501182D01*
G01X1353680Y502011D02*
X1358706Y505401D01*
G01X1354509Y501182D02*
X1359155Y504316D01*
G01X1358706Y505401D02*
X1366893Y506991D01*
G01X1359155Y504316D02*
X1366815Y505804D01*
G01X1366893Y506991D02*
X1371665Y505390D01*
G01X1366815Y505804D02*
X1371584Y504203D01*
G01X1371665Y505390D02*
X1386783Y508271D01*
G01X1371584Y504203D02*
X1386745Y507093D01*
G01X1386783Y508271D02*
X1394084Y506391D01*
G01Y506390D02*
X1401389Y504508D01*
G01X1386745Y507093D02*
X1401491Y503294D01*
G01X1401389Y504508D02*
X1411903Y509200D01*
G01X1401491Y503294D02*
X1412148Y508050D01*
G01X1406681Y514857D02*
X1400595Y513674D01*
G01X1406681Y516029D02*
X1400145Y514759D01*
G01X1400595Y513674D02*
X1393391Y508814D01*
G01X1400145Y514759D02*
X1393143Y510034D01*
G01X1393391Y508814D02*
X1387343Y509990D01*
G01X1393143Y510034D02*
X1387343Y511162D01*
G01Y509990D02*
X1374709Y507534D01*
G01X1387343Y511162D02*
X1374709Y508706D01*
G01Y507534D02*
X1371844Y508091D01*
G01X1374709Y508706D02*
X1372532Y509130D01*
G01X1371844Y508091D02*
X1369956Y510890D01*
G01X1372532Y509130D02*
X1370644Y511929D01*
G01X1369956Y510890D02*
X1362649Y512310D01*
G01X1370644Y511929D02*
X1362649Y513482D01*
G01Y512310D02*
X1355256Y510874D01*
G01X1362649Y513482D02*
X1354806Y511959D01*
G01X1355256Y510874D02*
X1353517Y509701D01*
G01X1354806Y511959D02*
X1352688Y510529D01*
G01X1353517Y509701D02*
X1350793Y505663D01*
G01X1352688Y510529D02*
X1349964Y506491D01*
G01X1350793Y505663D02*
X1348424Y504063D01*
G01X1349964Y506491D02*
X1347974Y505148D01*
G01X1399705Y528136D02*
X1409943Y517898D01*
G01X1399228Y526986D02*
X1409291Y516923D01*
G01X1353047Y495030D02*
X1357169Y501142D01*
G01X1353738Y493997D02*
X1357998Y500313D01*
G01X1357169Y501142D02*
X1359932Y503005D01*
G01X1357998Y500313D02*
X1360382Y501920D01*
G01X1359932Y503005D02*
X1366827Y504351D01*
G01X1360382Y501920D02*
X1366741Y503162D01*
G01X1366827Y504351D02*
X1371605Y502677D01*
G01X1366741Y503162D02*
X1371516Y501489D01*
G01X1371605Y502677D02*
X1386649Y505542D01*
G01X1371516Y501489D02*
X1386616Y504364D01*
G01X1386649Y505542D02*
X1394269Y503640D01*
G01X1394268Y503639D02*
X1401890Y501737D01*
G01X1386616Y504364D02*
X1401997Y500524D01*
G01X1401890Y501737D02*
X1412801Y506614D01*
G01X1401997Y500524D02*
X1413047Y505464D01*
G01X1355308Y492851D02*
X1360029Y499846D01*
G01X1355999Y491817D02*
X1360858Y499018D01*
G01X1360029Y499846D02*
X1361288Y500697D01*
G01X1360858Y499018D02*
X1361738Y499613D01*
G01X1361288Y500697D02*
X1366619Y501741D01*
G01X1361738Y499613D02*
X1366533Y500552D01*
G01X1366619Y501741D02*
X1371772Y499931D01*
G01X1366533Y500552D02*
X1371684Y498743D01*
G01X1371772Y499931D02*
X1386748Y502782D01*
G01X1371684Y498743D02*
X1386715Y501604D01*
G01X1386748Y502782D02*
X1402157Y498935D01*
G01X1386715Y501604D02*
X1402264Y497722D01*
G01X1402157Y498935D02*
X1413720Y504105D01*
G01X1402264Y497722D02*
X1413966Y502955D01*
G01X1346894Y526986D02*
X1399228D01*
G01X1346715Y528136D02*
X1399705D01*
G01X1346245Y530765D02*
X1401005D01*
G01X1346424Y529615D02*
X1400528D01*
G01X1401005Y530765D02*
X1411988Y519782D01*
G01X1400528Y529615D02*
X1411336Y518807D01*
G01X1346715Y528136D02*
X1399705D01*
G01X1346894Y526986D02*
X1399228D01*
G01X1346424Y529615D02*
X1400528D01*
G01X1346245Y530765D02*
X1401005D01*
G01X1400528Y529615D02*
X1411336Y518807D01*
G01X1401005Y530765D02*
X1411988Y519782D01*
G01X1421582Y347587D02*
X1418875Y334047D01*
G01X1422755Y347587D02*
X1420048Y334047D01*
G01X1418875D02*
X1419275Y332046D01*
G01X1420048Y334047D02*
X1420448Y332046D01*
G01X1419275D02*
X1418068Y326005D01*
G01X1420448Y332046D02*
X1419241Y326006D01*
G01X1418068Y326005D02*
X1421837Y307163D01*
G01D02*
X1421995Y306375D01*
G01X1419241Y326006D02*
X1423168Y306375D01*
G01X1421995D02*
X1420949Y301144D01*
G01X1423168Y306375D02*
X1423078Y305922D01*
G01X1421995Y306375D02*
X1420949Y301144D01*
G01X1423078Y305922D02*
X1422033Y300695D01*
G01X1420949Y301144D02*
X1419184Y298496D01*
G01X1422033Y300695D02*
X1419877Y297461D01*
G01X1419184Y298496D02*
X1411300Y296920D01*
G01X1419877Y297461D02*
X1411300Y295747D01*
G01Y296920D02*
X1404498Y298280D01*
G01X1411300Y295747D02*
X1404498Y297107D01*
G01X1409589Y331347D02*
X1411964Y334911D01*
G01X1410419Y330518D02*
X1413047Y334462D01*
G01X1411964Y334911D02*
X1413453Y342354D01*
G01X1413047Y334462D02*
X1414626Y342354D01*
G01X1405279Y292823D02*
X1412151Y291449D01*
G01X1405279Y291650D02*
X1412151Y290276D01*
G01Y291449D02*
X1422504Y293521D01*
G01X1412151Y290276D02*
X1423197Y292486D01*
G01X1422504Y293521D02*
X1423989Y295748D01*
G01X1423197Y292486D02*
X1425139Y295399D01*
G01X1423989Y295749D02*
X1425475Y297977D01*
G01X1425139Y295400D02*
X1426558Y297528D01*
G01X1425475Y297977D02*
X1426400Y302600D01*
G01X1426558Y297528D02*
X1427377Y301623D01*
G01X1426400Y302600D02*
X1427170Y306448D01*
G01X1427377Y301623D02*
X1428343Y306448D01*
G01X1427170D02*
X1423373Y325434D01*
G01X1428343Y306448D02*
X1424546Y325434D01*
G01X1423373D02*
X1425567Y336400D01*
G01X1424546Y325434D02*
X1426773Y336561D01*
G01X1425566Y336402D02*
X1427512Y346127D01*
G01X1426772Y336563D02*
X1428685Y346127D01*
G01X1421471Y334149D02*
X1424309Y348333D01*
G01X1425482D02*
X1422644Y334149D01*
G01X1421921Y331900D02*
X1421471Y334149D01*
G01X1422644D02*
X1423096Y331898D01*
G01X1420682Y325690D02*
X1421923Y331899D01*
G01X1423096Y331898D02*
X1421855Y325690D01*
G01X1423412Y312042D02*
X1420682Y325690D01*
G01X1421855D02*
X1424540Y312268D01*
G01X1424546Y306371D02*
X1423412Y312042D01*
G01X1424540Y312268D02*
X1425673Y306600D01*
G01X1424546Y306371D02*
X1423412Y312042D01*
G01X1425673Y306600D02*
X1425685Y306542D01*
G01X1424546Y306371D02*
X1423412Y312042D01*
G01X1425685Y306542D02*
X1425688Y306525D01*
G01X1424575Y306225D02*
X1424563Y306283D01*
G01X1424546Y306371D02*
X1423412Y312042D01*
G01X1425688Y306525D02*
X1425718Y306375D01*
G01X1424275Y304725D02*
X1424575Y306225D01*
G01X1425748D02*
X1425252Y303748D01*
G01X1423347Y300087D02*
X1424275Y304725D01*
G01X1425252Y303748D02*
X1424430Y299638D01*
G01X1420494Y295808D02*
X1423347Y300087D01*
G01X1424430Y299638D02*
X1421187Y294773D01*
G01X1411973Y294103D02*
X1420494Y295808D01*
G01X1421187Y294773D02*
X1411973Y292930D01*
G01X1404644Y295568D02*
X1411973Y294103D01*
G01Y292930D02*
X1404644Y294395D01*
G01X1422755Y347587D02*
X1420048Y334047D01*
G01X1421582Y347587D02*
X1418875Y334047D01*
G01X1420048D02*
X1420448Y332046D01*
G01X1418875Y334047D02*
X1419275Y332046D01*
G01X1420448D02*
X1419241Y326006D01*
G01X1419275Y332046D02*
X1418068Y326005D01*
G01X1419241Y326006D02*
X1423168Y306375D01*
G01X1418068Y326005D02*
X1421837Y307163D01*
G01X1419241Y326006D02*
X1423168Y306375D01*
G01X1421837Y307163D02*
X1421995Y306375D01*
G01X1423168D02*
X1423078Y305922D01*
G01D02*
X1422033Y300695D01*
G01X1421995Y306375D02*
X1420949Y301144D01*
G01X1422033Y300695D02*
X1419877Y297461D01*
G01X1420949Y301144D02*
X1419184Y298496D01*
G01X1419877Y297461D02*
X1411300Y295747D01*
G01X1419184Y298496D02*
X1411300Y296920D01*
G01Y295747D02*
X1404498Y297107D01*
G01X1411300Y296920D02*
X1404498Y298280D01*
G01X1410419Y330518D02*
X1413047Y334462D01*
G01X1409589Y331347D02*
X1411964Y334911D01*
G01X1413047Y334462D02*
X1414626Y342354D01*
G01X1411964Y334911D02*
X1413453Y342354D01*
G01X1405279Y291650D02*
X1412151Y290276D01*
G01X1405279Y292823D02*
X1412151Y291449D01*
G01Y290276D02*
X1423197Y292486D01*
G01X1412151Y291449D02*
X1422504Y293521D01*
G01X1423197Y292486D02*
X1425139Y295399D01*
G01X1422504Y293521D02*
X1423989Y295748D01*
G01X1425139Y295400D02*
X1426558Y297528D01*
G01X1423989Y295749D02*
X1425475Y297977D01*
G01X1426558Y297528D02*
X1427377Y301623D01*
G01X1425475Y297977D02*
X1426400Y302600D01*
G01X1427377Y301623D02*
X1428343Y306448D01*
G01X1426400Y302600D02*
X1427170Y306448D01*
G01X1428343D02*
X1424546Y325434D01*
G01X1427170Y306448D02*
X1423373Y325434D01*
G01X1424546D02*
X1426773Y336561D01*
G01X1423373Y325434D02*
X1425567Y336400D01*
G01X1426772Y336563D02*
X1428685Y346127D01*
G01X1425566Y336402D02*
X1427512Y346127D01*
G01X1411973Y292930D02*
X1404644Y294395D01*
G01Y295568D02*
X1411973Y294103D01*
G01X1421187Y294773D02*
X1411973Y292930D01*
G01Y294103D02*
X1420494Y295808D01*
G01X1424430Y299638D02*
X1421187Y294773D01*
G01X1420494Y295808D02*
X1423347Y300087D01*
G01X1425252Y303748D02*
X1424430Y299638D01*
G01X1423347Y300087D02*
X1424275Y304725D01*
G01X1425748Y306225D02*
X1425252Y303748D01*
G01X1424275Y304725D02*
X1424575Y306225D01*
G01X1425688Y306525D02*
X1425718Y306375D01*
G01X1424575Y306225D02*
X1424563Y306283D01*
G01X1424540Y312268D02*
X1425673Y306600D01*
G01D02*
X1425685Y306542D01*
G01D02*
X1425688Y306525D01*
G01D02*
X1425718Y306375D01*
G01X1424546Y306371D02*
X1423412Y312042D01*
G01X1421855Y325690D02*
X1424540Y312268D01*
G01X1423412Y312042D02*
X1420682Y325690D01*
G01X1423096Y331898D02*
X1421855Y325690D01*
G01X1420682D02*
X1421923Y331899D01*
G01X1422644Y334149D02*
X1423096Y331898D01*
G01X1421921Y331900D02*
X1421471Y334149D01*
G01X1425482Y348333D02*
X1422644Y334149D01*
G01X1421471D02*
X1424309Y348333D01*
G01X1408151Y348281D02*
X1405100Y340749D01*
G01X1409347Y348168D02*
X1406207Y340417D01*
G01X1405100Y340749D02*
X1403739Y333950D01*
G01X1406207Y340417D02*
X1404822Y333501D01*
G01X1409347Y348168D02*
X1406207Y340417D01*
G01X1408151Y348281D02*
X1405100Y340749D01*
G01X1406207Y340417D02*
X1404822Y333501D01*
G01X1405100Y340749D02*
X1403739Y333950D01*
G01X1419428Y391427D02*
X1417499D01*
G01X1419623Y390277D02*
X1417976D01*
G01X1417499Y391427D02*
X1414826Y388754D01*
G01X1417976Y390277D02*
X1415720Y388021D01*
G01X1414826Y388754D02*
X1413687Y387046D01*
G01X1415720Y388021D02*
X1414770Y386597D01*
G01X1413687Y387046D02*
X1410389Y370566D01*
G01X1414770Y386597D02*
X1411562Y370566D01*
G01X1410389D02*
X1411050Y367267D01*
G01X1411562Y370566D02*
X1412133Y367716D01*
G01X1411050Y367267D02*
X1413585Y363463D01*
G01X1412133Y367716D02*
X1414415Y364292D01*
G01X1413585Y363463D02*
X1416069Y361803D01*
G01X1414415Y364292D02*
X1416899Y362632D01*
G01X1416069Y361803D02*
X1419879Y356088D01*
G01X1416899Y362632D02*
X1420962Y356537D01*
G01X1419879Y356088D02*
X1421582Y347587D01*
G01X1420962Y356537D02*
X1422755Y347587D01*
G01X1413453Y342354D02*
X1410241Y358419D01*
G01X1414626Y342354D02*
X1411347Y358756D01*
G01X1410241Y358419D02*
X1405954Y368743D01*
G01X1411347Y358756D02*
X1407151Y368861D01*
G01X1405954Y368743D02*
X1408268Y380308D01*
G01X1407151Y368861D02*
X1409441Y380308D01*
G01X1408268D02*
X1407078Y386258D01*
G01X1409441Y380308D02*
X1408251Y386258D01*
G01X1407078D02*
X1408366Y392694D01*
G01X1408251Y386258D02*
X1409426Y392127D01*
G01X1408366Y392694D02*
X1409749Y394077D01*
G01X1409426Y392127D02*
X1410226Y392927D01*
G01X1409749Y394077D02*
X1411510D01*
G01X1410226Y392927D02*
X1412110D01*
G01X1427512Y346127D02*
X1425822Y354576D01*
G01D02*
X1424132Y363026D01*
G01X1428685Y346127D02*
X1425305Y363026D01*
G01X1424132D02*
X1426577Y375246D01*
G01X1425305Y363026D02*
X1427799Y375488D01*
G01X1426577Y375246D02*
X1423873Y379300D01*
G01X1427799Y375488D02*
X1424767Y380033D01*
G01X1423873Y379300D02*
X1422573Y380600D01*
G01X1424767Y380033D02*
X1423050Y381750D01*
G01X1422573Y380600D02*
X1420625D01*
G01X1423050Y381750D02*
X1420625D01*
G01X1416823Y371649D02*
X1419779D01*
G01X1419829Y370499D02*
X1417300D01*
G01X1415246Y370073D02*
X1415500Y370327D01*
G01D02*
X1416823Y371649D01*
G01X1417300Y370499D02*
X1416221Y369420D01*
G01X1414650Y368640D02*
X1414948Y369356D01*
G01X1414947D02*
X1415246Y370073D01*
G01X1416221Y369420D02*
X1415800Y368409D01*
G01X1414650Y366454D02*
Y368640D01*
G01X1415800Y368409D02*
Y366931D01*
G01X1416738Y364366D02*
X1414650Y366454D01*
G01X1415800Y366931D02*
X1417306Y365426D01*
G01X1417936Y364126D02*
X1416738Y364366D01*
G01X1417306Y365426D02*
X1417983Y365290D01*
G01X1417936Y364126D02*
X1416738Y364366D01*
G01X1417983Y365290D02*
X1418629Y365161D01*
G01X1422530Y357240D02*
X1417983Y364056D01*
G01D02*
X1417936Y364126D01*
G01X1418629Y365161D02*
X1423614Y357689D01*
G01X1424309Y348333D02*
X1422530Y357240D01*
G01X1423614Y357689D02*
X1425482Y348333D01*
G01X1419623Y390277D02*
X1417976D01*
G01X1419428Y391427D02*
X1417499D01*
G01X1417976Y390277D02*
X1415720Y388021D01*
G01X1417499Y391427D02*
X1414826Y388754D01*
G01X1415720Y388021D02*
X1414770Y386597D01*
G01X1414826Y388754D02*
X1413687Y387046D01*
G01X1414770Y386597D02*
X1411562Y370566D01*
G01X1413687Y387046D02*
X1410389Y370566D01*
G01X1411562D02*
X1412133Y367716D01*
G01X1410389Y370566D02*
X1411050Y367267D01*
G01X1412133Y367716D02*
X1414415Y364292D01*
G01X1411050Y367267D02*
X1413585Y363463D01*
G01X1414415Y364292D02*
X1416899Y362632D01*
G01X1413585Y363463D02*
X1416069Y361803D01*
G01X1416899Y362632D02*
X1420962Y356537D01*
G01X1416069Y361803D02*
X1419879Y356088D01*
G01X1420962Y356537D02*
X1422755Y347587D01*
G01X1419879Y356088D02*
X1421582Y347587D01*
G01X1414626Y342354D02*
X1411347Y358756D01*
G01X1413453Y342354D02*
X1410241Y358419D01*
G01X1411347Y358756D02*
X1407151Y368861D01*
G01X1410241Y358419D02*
X1405954Y368743D01*
G01X1407151Y368861D02*
X1409441Y380308D01*
G01X1405954Y368743D02*
X1408268Y380308D01*
G01X1409441D02*
X1408251Y386258D01*
G01X1408268Y380308D02*
X1407078Y386258D01*
G01X1408251D02*
X1409426Y392127D01*
G01X1407078Y386258D02*
X1408366Y392694D01*
G01X1409426Y392127D02*
X1410226Y392927D01*
G01X1408366Y392694D02*
X1409749Y394077D01*
G01X1410226Y392927D02*
X1412110D01*
G01X1409749Y394077D02*
X1411510D01*
G01X1428685Y346127D02*
X1425305Y363026D01*
G01X1427512Y346127D02*
X1425822Y354576D01*
G01X1428685Y346127D02*
X1425305Y363026D01*
G01X1425822Y354576D02*
X1424132Y363026D01*
G01X1425305D02*
X1427799Y375488D01*
G01X1424132Y363026D02*
X1426577Y375246D01*
G01X1427799Y375488D02*
X1424767Y380033D01*
G01X1426577Y375246D02*
X1423873Y379300D01*
G01X1424767Y380033D02*
X1423050Y381750D01*
G01X1423873Y379300D02*
X1422573Y380600D01*
G01X1423050Y381750D02*
X1420625D01*
G01X1422573Y380600D02*
X1420625D01*
G01X1423614Y357689D02*
X1425482Y348333D01*
G01X1424309D02*
X1422530Y357240D01*
G01X1418629Y365161D02*
X1423614Y357689D01*
G01X1422530Y357240D02*
X1417983Y364056D01*
G01X1418629Y365161D02*
X1423614Y357689D01*
G01X1417983Y364056D02*
X1417936Y364126D01*
G01X1417306Y365426D02*
X1417983Y365290D01*
G01D02*
X1418629Y365161D01*
G01X1417936Y364126D02*
X1416738Y364366D01*
G01X1415800Y366931D02*
X1417306Y365426D01*
G01X1416738Y364366D02*
X1414650Y366454D01*
G01X1415800Y368409D02*
Y366931D01*
G01X1414650Y366454D02*
Y368640D01*
G01X1416221Y369420D02*
X1415800Y368409D01*
G01X1414650Y368640D02*
X1414948Y369356D01*
G01X1416221Y369420D02*
X1415800Y368409D01*
G01X1414947Y369356D02*
X1415246Y370073D01*
G01X1417300Y370499D02*
X1416221Y369420D01*
G01X1415246Y370073D02*
X1415500Y370327D01*
G01X1417300Y370499D02*
X1416221Y369420D01*
G01X1415500Y370327D02*
X1416823Y371649D01*
G01X1419829Y370499D02*
X1417300D01*
G01X1416823Y371649D02*
X1419779D01*
G01X1422860Y408535D02*
X1411235Y400189D01*
G01X1423781Y407780D02*
X1411909Y399257D01*
G01X1411235Y400189D02*
X1405458Y395986D01*
G01X1411909Y399257D02*
X1406498Y395320D01*
G01D02*
X1404789Y386775D01*
G01X1404817Y386635D02*
X1405804Y381704D01*
G01D02*
X1403772Y368805D01*
G01D02*
X1405971Y363500D01*
G01D02*
X1406572Y362051D01*
G01X1405466Y361715D02*
X1408151Y348281D01*
G01X1406572Y362051D02*
X1409347Y348168D01*
G01X1421335Y409103D02*
X1404169Y396779D01*
G01X1404308Y360282D02*
X1406217Y350734D01*
G01X1423781Y407780D02*
X1411909Y399257D01*
G01X1422860Y408535D02*
X1411235Y400189D01*
G01X1411909Y399257D02*
X1406498Y395320D01*
G01X1411235Y400189D02*
X1405458Y395986D01*
G01X1406498Y395320D02*
X1404789Y386775D01*
G01X1404817Y386635D02*
X1405804Y381704D01*
G01D02*
X1403772Y368805D01*
G01D02*
X1405971Y363500D01*
G01D02*
X1406572Y362051D01*
G01D02*
X1409347Y348168D01*
G01X1405466Y361715D02*
X1408151Y348281D01*
G01X1421335Y409103D02*
X1404169Y396779D01*
G01X1421335Y409103D02*
X1404169Y396779D01*
G01X1404308Y360282D02*
X1406217Y350734D01*
G01X1447626Y434825D02*
X1438292D01*
G01X1447650Y433675D02*
X1442916D01*
G01X1447626Y434825D02*
X1438292D01*
G01X1440921Y433675D02*
X1438630D01*
G01X1438292Y434825D02*
X1433600Y431813D01*
G01X1438630Y433675D02*
X1434398Y430958D01*
G01X1433492Y431744D02*
X1422860Y408535D01*
G01X1434397Y430957D02*
X1423781Y407780D01*
G01X1432099Y440474D02*
X1425806D01*
G01X1432001Y439324D02*
X1426422D01*
G01X1425806Y440474D02*
X1423745Y437382D01*
G01X1426422Y439324D02*
X1424828Y436933D01*
G01X1423745Y437382D02*
X1422122Y429268D01*
G01X1424828Y436933D02*
X1423295Y429268D01*
G01X1422122D02*
X1424184Y418958D01*
G01D02*
X1424305Y418351D01*
G01X1423295Y429268D02*
X1425357Y418957D01*
G01X1424184Y418958D02*
X1424305Y418351D01*
G01X1425357Y418957D02*
X1425414Y418673D01*
G01X1424305Y418351D02*
X1420416Y409859D01*
G01X1425550Y418306D02*
X1421934Y410411D01*
G01X1424305Y418351D02*
X1420416Y409859D01*
G01X1421934Y410411D02*
X1421335Y409103D01*
G01X1447150Y445825D02*
X1429084D01*
G01X1447250Y444675D02*
X1429198D01*
G01X1429084Y445825D02*
X1424376Y444885D01*
G01X1429198Y444675D02*
X1425069Y443850D01*
G01X1424376Y444885D02*
X1420955Y439752D01*
G01X1425069Y443850D02*
X1422038Y439303D01*
G01X1420955Y439752D02*
X1419081Y430378D01*
G01X1422038Y439303D02*
X1421146Y434840D01*
G01X1420955Y439752D02*
X1419081Y430378D01*
G01X1421146Y434839D02*
X1420254Y430378D01*
G01X1419081D02*
X1419125Y430153D01*
G01X1419126D02*
X1421364Y418959D01*
G01D02*
X1421500Y418279D01*
G01X1420254Y430378D02*
X1422537Y418958D01*
G01X1421364Y418959D02*
X1421500Y418279D01*
G01X1422537Y418958D02*
X1422701Y418139D01*
G01X1421499Y418279D02*
X1418510Y411757D01*
G01X1422701Y418139D02*
X1419429Y411000D01*
G01X1418510Y411757D02*
X1417983Y411379D01*
G01X1447650Y433675D02*
X1442916D01*
G01X1440921D02*
X1438630D01*
G01X1447626Y434825D02*
X1438292D01*
G01X1438630Y433675D02*
X1434398Y430958D01*
G01X1438292Y434825D02*
X1433600Y431813D01*
G01X1434397Y430957D02*
X1423781Y407780D01*
G01X1433492Y431744D02*
X1422860Y408535D01*
G01X1432001Y439324D02*
X1426422D01*
G01X1432099Y440474D02*
X1425806D01*
G01X1426422Y439324D02*
X1424828Y436933D01*
G01X1425806Y440474D02*
X1423745Y437382D01*
G01X1424828Y436933D02*
X1423295Y429268D01*
G01X1423745Y437382D02*
X1422122Y429268D01*
G01X1423295D02*
X1425357Y418957D01*
G01X1422122Y429268D02*
X1424184Y418958D01*
G01X1423295Y429268D02*
X1425357Y418957D01*
G01D02*
X1425414Y418673D01*
G01X1424184Y418958D02*
X1424305Y418351D01*
G01X1425550Y418306D02*
X1421934Y410411D01*
G01D02*
X1421335Y409103D01*
G01X1424305Y418351D02*
X1420416Y409859D01*
G01X1447250Y444675D02*
X1429198D01*
G01X1447150Y445825D02*
X1429084D01*
G01X1429198Y444675D02*
X1425069Y443850D01*
G01X1429084Y445825D02*
X1424376Y444885D01*
G01X1425069Y443850D02*
X1422038Y439303D01*
G01X1424376Y444885D02*
X1420955Y439752D01*
G01X1422038Y439303D02*
X1421146Y434840D01*
G01Y434839D02*
X1420254Y430378D01*
G01X1420955Y439752D02*
X1419081Y430378D01*
G01X1420254D02*
X1422537Y418958D01*
G01X1419081Y430378D02*
X1419125Y430153D01*
G01X1420254Y430378D02*
X1422537Y418958D01*
G01X1419126Y430153D02*
X1421364Y418959D01*
G01X1420254Y430378D02*
X1422537Y418958D01*
G01D02*
X1422701Y418139D01*
G01X1421364Y418959D02*
X1421500Y418279D01*
G01X1422701Y418139D02*
X1419429Y411000D01*
G01X1421499Y418279D02*
X1418510Y411757D01*
G01D02*
X1417983Y411379D01*
G01X1432150Y451375D02*
X1428487D01*
G01X1432100Y450225D02*
X1428602D01*
G01X1428487Y451375D02*
X1423964Y450470D01*
G01X1428602Y450225D02*
X1424657Y449435D01*
G01X1423964Y450470D02*
X1418590Y442409D01*
G01X1424657Y449435D02*
X1419673Y441960D01*
G01X1418590Y442409D02*
X1416161Y430264D01*
G01X1419673Y441959D02*
X1417334Y430264D01*
G01X1416161D02*
X1417983Y421155D01*
G01X1417334Y430264D02*
X1417983Y427019D01*
G01X1416161Y430264D02*
X1417983Y421155D01*
G01D02*
X1418538Y418380D01*
G01X1417983Y427019D02*
X1419595Y418960D01*
G01X1417983Y421155D02*
X1418538Y418380D01*
G01X1419595Y418960D02*
X1419739Y418240D01*
G01X1418538Y418380D02*
X1416296Y413488D01*
G01X1419739Y418240D02*
X1417983Y414407D01*
G01X1418538Y418380D02*
X1416296Y413488D01*
G01X1417983Y414407D02*
X1417215Y412731D01*
G01X1432100Y450225D02*
X1428602D01*
G01X1432150Y451375D02*
X1428487D01*
G01X1428602Y450225D02*
X1424657Y449435D01*
G01X1428487Y451375D02*
X1423964Y450470D01*
G01X1424657Y449435D02*
X1419673Y441960D01*
G01X1423964Y450470D02*
X1418590Y442409D01*
G01X1419673Y441959D02*
X1417334Y430264D01*
G01X1418590Y442409D02*
X1416161Y430264D01*
G01X1417334D02*
X1417983Y427019D01*
G01D02*
X1419595Y418960D01*
G01X1416161Y430264D02*
X1417983Y421155D01*
G01Y427019D02*
X1419595Y418960D01*
G01D02*
X1419739Y418240D01*
G01X1417983Y421155D02*
X1418538Y418380D01*
G01X1419739Y418240D02*
X1417983Y414407D01*
G01D02*
X1417215Y412731D01*
G01X1418538Y418380D02*
X1416296Y413488D01*
G01X1407050Y452469D02*
X1405322Y450741D01*
G01X1405974Y449765D02*
X1408200Y451992D01*
G01X1407050Y454877D02*
Y452469D01*
G01X1408200Y451992D02*
Y454400D01*
G01X1408223Y456050D02*
X1407050Y454877D01*
G01X1408200Y454400D02*
X1408700Y454900D01*
G01X1409563Y456050D02*
X1408223D01*
G01X1408700Y454900D02*
X1409630D01*
G01X1408850Y431700D02*
X1406973D01*
G01X1408850Y432850D02*
X1407450D01*
G01X1406973Y431700D02*
X1405850Y432823D01*
G01X1407450Y432850D02*
X1407000Y433300D01*
G01X1405850Y432823D02*
Y435823D01*
G01X1407000Y433300D02*
Y436300D01*
G01X1405850Y435823D02*
X1404373Y437300D01*
G01X1407000Y436300D02*
X1404850Y438450D01*
G01X1414532Y418884D02*
X1411530D01*
G01X1414458Y420034D02*
X1412007D01*
G01X1411530Y418884D02*
X1409725Y420689D01*
G01X1412007Y420034D02*
X1410875Y421166D01*
G01X1409725Y420689D02*
Y423325D01*
G01X1410875Y421166D02*
Y423802D01*
G01X1409725Y423325D02*
X1406974Y426076D01*
G01X1410875Y423802D02*
X1407451Y427226D01*
G01X1405263Y419680D02*
X1403875D01*
G01X1408700Y454900D02*
X1409630D01*
G01X1409563Y456050D02*
X1408223D01*
G01X1408200Y454400D02*
X1408700Y454900D01*
G01X1408223Y456050D02*
X1407050Y454877D01*
G01X1408200Y451992D02*
Y454400D01*
G01X1407050Y454877D02*
Y452469D01*
G01X1405974Y449765D02*
X1408200Y451992D01*
G01X1407050Y452469D02*
X1405322Y450741D01*
G01X1408850Y432850D02*
X1407450D01*
G01X1408850Y431700D02*
X1406973D01*
G01X1407450Y432850D02*
X1407000Y433300D01*
G01X1406973Y431700D02*
X1405850Y432823D01*
G01X1407000Y433300D02*
Y436300D01*
G01X1405850Y432823D02*
Y435823D01*
G01X1407000Y436300D02*
X1404850Y438450D01*
G01X1405850Y435823D02*
X1404373Y437300D01*
G01X1414458Y420034D02*
X1412007D01*
G01X1414532Y418884D02*
X1411530D01*
G01X1412007Y420034D02*
X1410875Y421166D01*
G01X1411530Y418884D02*
X1409725Y420689D01*
G01X1410875Y421166D02*
Y423802D01*
G01X1409725Y420689D02*
Y423325D01*
G01X1410875Y423802D02*
X1407451Y427226D01*
G01X1409725Y423325D02*
X1406974Y426076D01*
G01X1405263Y419680D02*
X1403875D01*
G01X1416077Y460086D02*
X1417427D01*
G01X1420077D02*
X1421427D01*
G01X1424077D02*
X1425427D01*
G01X1428077D02*
X1441488D01*
G01X1441965Y461236D02*
X1451626Y451575D01*
G01X1441488Y460086D02*
X1451149Y450425D01*
G01X1451626Y451575D02*
X1454725D01*
G01X1451149Y450425D02*
X1454248D01*
G01X1454725Y451575D02*
X1461249Y445051D01*
G01X1454248Y450425D02*
X1460099Y444574D01*
G01X1461249Y445051D02*
Y433733D01*
G01X1460099Y444574D02*
Y433472D01*
G01X1416077Y460086D02*
X1417427D01*
G01X1420077D02*
X1421427D01*
G01X1424077D02*
X1425427D01*
G01X1428077D02*
X1441488D01*
G01D02*
X1451149Y450425D01*
G01X1441965Y461236D02*
X1451626Y451575D01*
G01X1451149Y450425D02*
X1454248D01*
G01X1451626Y451575D02*
X1454725D01*
G01X1454248Y450425D02*
X1460099Y444574D01*
G01X1454725Y451575D02*
X1461249Y445051D01*
G01X1460099Y444574D02*
Y433472D01*
G01X1461249Y445051D02*
Y433733D01*
G01X1405280Y492907D02*
X1414954Y497799D01*
G01X1404493Y493799D02*
X1414679Y498949D01*
G01X1414954Y497799D02*
X1424683D01*
G01X1414679Y498949D02*
X1424454D01*
G01X1424683Y497799D02*
X1446794Y506965D01*
G01X1424454Y498949D02*
X1446142Y507940D01*
G01X1446794Y506965D02*
X1457620Y517791D01*
G01X1446142Y507940D02*
X1457143Y518941D01*
G01X1457620Y517791D02*
X1463673D01*
G01X1457143Y518941D02*
X1463326D01*
G01X1463673Y517791D02*
X1469765Y521825D01*
G01X1463326Y518941D02*
X1469316Y522908D01*
G01X1414380Y500380D02*
X1424098D01*
G01X1414134Y501530D02*
X1423869D01*
G01X1424098Y500380D02*
X1445062Y509062D01*
G01X1423869Y501530D02*
X1444411Y510038D01*
G01X1445062Y509062D02*
X1456350Y520350D01*
G01X1444411Y510038D02*
X1455873Y521500D01*
G01X1456350Y520350D02*
X1461638D01*
G01X1455873Y521500D02*
X1461408D01*
G01X1461638Y520350D02*
X1465244Y521847D01*
G01X1461408Y521500D02*
X1464592Y522822D01*
G01X1465244Y521847D02*
X1474463Y531064D01*
G01X1464592Y522822D02*
X1473313Y531541D01*
G01X1412148Y508050D02*
X1421910D01*
G01X1411903Y509200D02*
X1421688D01*
G01X1421910Y508050D02*
X1437063Y514124D01*
G01X1421688Y509200D02*
X1436413Y515103D01*
G01X1437063Y514124D02*
X1446496Y523558D01*
G01X1436413Y515103D02*
X1445520Y524210D01*
G01X1446496Y523558D02*
X1451764Y536279D01*
G01X1445520Y524210D02*
X1450818Y537004D01*
G01X1448644Y538495D02*
X1443298Y525590D01*
G01X1449589Y537769D02*
X1444274Y524938D01*
G01X1443298Y525590D02*
X1435211Y517502D01*
G01X1444274Y524938D02*
X1435863Y516526D01*
G01X1435211Y517502D02*
X1424075Y512890D01*
G01X1435863Y516526D02*
X1424304Y511740D01*
G01X1424075Y512890D02*
X1415376D01*
G01X1424304Y511740D02*
X1415147D01*
G01X1415376Y512890D02*
X1408780Y515620D01*
G01X1415147Y511740D02*
X1408447Y514513D01*
G01X1408780Y515620D02*
X1406681Y516029D01*
G01X1408447Y514513D02*
X1406681Y514857D01*
G01X1409291Y516923D02*
X1415623Y514300D01*
G01X1409943Y517898D02*
X1415852Y515450D01*
G01X1415623Y514300D02*
X1423576D01*
G01X1415852Y515450D02*
X1423347D01*
G01X1423576Y514300D02*
X1434074Y518647D01*
G01X1423347Y515450D02*
X1433422Y519623D01*
G01X1434074Y518647D02*
X1440914Y525487D01*
G01X1433422Y519623D02*
X1439938Y526139D01*
G01X1440914Y525487D02*
X1443450Y531611D01*
G01X1439938Y526139D02*
X1442300Y531840D01*
G01X1411988Y519782D02*
X1416314Y517990D01*
G01X1411336Y518807D02*
X1416085Y516840D01*
G01X1416314Y517990D02*
X1420802D01*
G01X1416085Y516840D02*
X1421127D01*
G01X1420802Y517990D02*
X1423410Y519591D01*
G01X1421127Y516840D02*
X1424305Y518791D01*
G01X1423410Y519591D02*
X1424756Y522454D01*
G01X1424305Y518791D02*
X1425712Y521782D01*
G01X1424774Y522466D02*
X1428470Y527720D01*
G01X1425710Y521796D02*
X1429158Y526697D01*
G01X1413047Y505464D02*
X1422924D01*
G01X1412801Y506614D02*
X1422695D01*
G01X1422924Y505464D02*
X1441768Y513267D01*
G01X1422695Y506614D02*
X1441116Y514243D01*
G01X1441768Y513267D02*
X1456231Y527730D01*
G01X1441116Y514243D02*
X1455754Y528880D01*
G01X1413966Y502955D02*
X1423736D01*
G01X1413720Y504105D02*
X1423507D01*
G01X1423736Y502955D02*
X1443277Y511048D01*
G01X1423507Y504105D02*
X1442625Y512024D01*
G01X1443277Y511048D02*
X1457458Y525230D01*
G01X1442625Y512024D02*
X1456981Y526380D01*
G01X1457458Y525230D02*
X1465030D01*
G01X1456981Y526380D02*
X1464553D01*
G01X1465030Y525230D02*
X1470348Y530548D01*
G01X1464553Y526380D02*
X1469198Y531025D01*
G01X1404493Y493799D02*
X1414679Y498949D01*
G01X1405280Y492907D02*
X1414954Y497799D01*
G01X1414679Y498949D02*
X1424454D01*
G01X1414954Y497799D02*
X1424683D01*
G01X1424454Y498949D02*
X1446142Y507940D01*
G01X1424683Y497799D02*
X1446794Y506965D01*
G01X1446142Y507940D02*
X1457143Y518941D01*
G01X1446794Y506965D02*
X1457620Y517791D01*
G01X1457143Y518941D02*
X1463326D01*
G01X1457620Y517791D02*
X1463673D01*
G01X1463326Y518941D02*
X1469316Y522908D01*
G01X1463673Y517791D02*
X1469765Y521825D01*
G01X1414134Y501530D02*
X1423869D01*
G01X1414380Y500380D02*
X1424098D01*
G01X1423869Y501530D02*
X1444411Y510038D01*
G01X1424098Y500380D02*
X1445062Y509062D01*
G01X1444411Y510038D02*
X1455873Y521500D01*
G01X1445062Y509062D02*
X1456350Y520350D01*
G01X1455873Y521500D02*
X1461408D01*
G01X1456350Y520350D02*
X1461638D01*
G01X1461408Y521500D02*
X1464592Y522822D01*
G01X1461638Y520350D02*
X1465244Y521847D01*
G01X1464592Y522822D02*
X1473313Y531541D01*
G01X1465244Y521847D02*
X1474463Y531064D01*
G01X1411903Y509200D02*
X1421688D01*
G01X1412148Y508050D02*
X1421910D01*
G01X1421688Y509200D02*
X1436413Y515103D01*
G01X1421910Y508050D02*
X1437063Y514124D01*
G01X1436413Y515103D02*
X1445520Y524210D01*
G01X1437063Y514124D02*
X1446496Y523558D01*
G01X1445520Y524210D02*
X1450818Y537004D01*
G01X1446496Y523558D02*
X1451764Y536279D01*
G01X1449589Y537769D02*
X1444274Y524938D01*
G01X1448644Y538495D02*
X1443298Y525590D01*
G01X1444274Y524938D02*
X1435863Y516526D01*
G01X1443298Y525590D02*
X1435211Y517502D01*
G01X1435863Y516526D02*
X1424304Y511740D01*
G01X1435211Y517502D02*
X1424075Y512890D01*
G01X1424304Y511740D02*
X1415147D01*
G01X1424075Y512890D02*
X1415376D01*
G01X1415147Y511740D02*
X1408447Y514513D01*
G01X1415376Y512890D02*
X1408780Y515620D01*
G01X1408447Y514513D02*
X1406681Y514857D01*
G01X1408780Y515620D02*
X1406681Y516029D01*
G01X1409943Y517898D02*
X1415852Y515450D01*
G01X1409291Y516923D02*
X1415623Y514300D01*
G01X1415852Y515450D02*
X1423347D01*
G01X1415623Y514300D02*
X1423576D01*
G01X1423347Y515450D02*
X1433422Y519623D01*
G01X1423576Y514300D02*
X1434074Y518647D01*
G01X1433422Y519623D02*
X1439938Y526139D01*
G01X1434074Y518647D02*
X1440914Y525487D01*
G01X1439938Y526139D02*
X1442300Y531840D01*
G01X1440914Y525487D02*
X1443450Y531611D01*
G01X1411336Y518807D02*
X1416085Y516840D01*
G01X1411988Y519782D02*
X1416314Y517990D01*
G01X1416085Y516840D02*
X1421127D01*
G01X1416314Y517990D02*
X1420802D01*
G01X1421127Y516840D02*
X1424305Y518791D01*
G01X1420802Y517990D02*
X1423410Y519591D01*
G01X1424305Y518791D02*
X1425712Y521782D01*
G01X1423410Y519591D02*
X1424756Y522454D01*
G01X1425710Y521796D02*
X1429158Y526697D01*
G01X1424774Y522466D02*
X1428470Y527720D01*
G01X1412801Y506614D02*
X1422695D01*
G01X1413047Y505464D02*
X1422924D01*
G01X1422695Y506614D02*
X1441116Y514243D01*
G01X1422924Y505464D02*
X1441768Y513267D01*
G01X1441116Y514243D02*
X1455754Y528880D01*
G01X1441768Y513267D02*
X1456231Y527730D01*
G01X1413720Y504105D02*
X1423507D01*
G01X1413966Y502955D02*
X1423736D01*
G01X1423507Y504105D02*
X1442625Y512024D01*
G01X1423736Y502955D02*
X1443277Y511048D01*
G01X1442625Y512024D02*
X1456981Y526380D01*
G01X1443277Y511048D02*
X1457458Y525230D01*
G01X1456981Y526380D02*
X1464553D01*
G01X1457458Y525230D02*
X1465030D01*
G01X1464553Y526380D02*
X1469198Y531025D01*
G01X1465030Y525230D02*
X1470348Y530548D01*
G01X1451764Y536279D02*
X1465689Y546942D01*
G01X1450818Y537004D02*
X1465200Y548017D01*
G01D02*
X1492273Y553523D01*
G01X1492591Y556177D02*
X1464188Y550399D01*
G01X1492591Y555003D02*
X1464677Y549324D01*
G01X1464188Y550399D02*
X1448644Y538495D01*
G01X1464677Y549324D02*
X1449589Y537769D01*
G01X1443450Y531611D02*
Y544287D01*
G01X1442300Y531840D02*
Y544516D01*
G01X1443450Y544287D02*
X1444944Y547891D01*
G01X1442300Y544516D02*
X1444010Y548643D01*
G01X1444944Y547891D02*
X1446159Y548736D01*
G01X1444010Y548643D02*
X1445697Y549816D01*
G01X1446159Y548736D02*
X1491066Y557871D01*
G01X1445697Y549816D02*
X1491066Y559045D01*
G01X1428470Y527720D02*
X1432311Y528602D01*
G01X1429158Y526697D02*
X1432990Y527577D01*
G01X1432311Y528602D02*
X1435480Y532976D01*
G01X1432990Y527577D02*
X1436511Y532437D01*
G01X1435480Y532976D02*
X1436466Y535798D01*
G01X1436511Y532437D02*
X1437675Y535771D01*
G01X1436466Y535798D02*
X1434006Y544004D01*
G01X1437675Y535771D02*
X1435226Y543942D01*
G01X1434006Y544004D02*
X1437689Y552894D01*
G01X1435226Y543942D02*
X1438536Y551931D01*
G01X1437689Y552894D02*
X1444851Y554834D01*
G01X1438536Y551931D02*
X1444907Y553657D01*
G01X1444851Y554834D02*
X1448168Y554266D01*
G01X1444907Y553657D02*
X1448186Y553096D01*
G01X1448168Y554266D02*
X1475694Y559867D01*
G01X1448186Y553096D02*
X1476172Y558790D01*
G01X1456231Y527730D02*
X1463757D01*
G01X1455754Y528880D02*
X1463280D01*
G01X1463757Y527730D02*
X1467400Y531373D01*
G01X1463280Y528880D02*
X1466250Y531850D01*
G01X1450818Y537004D02*
X1465200Y548017D01*
G01X1451764Y536279D02*
X1465689Y546942D01*
G01X1465200Y548017D02*
X1492273Y553523D01*
G01X1492591Y555003D02*
X1464677Y549324D01*
G01X1492591Y556177D02*
X1464188Y550399D01*
G01X1464677Y549324D02*
X1449589Y537769D01*
G01X1464188Y550399D02*
X1448644Y538495D01*
G01X1442300Y531840D02*
Y544516D01*
G01X1443450Y531611D02*
Y544287D01*
G01X1442300Y544516D02*
X1444010Y548643D01*
G01X1443450Y544287D02*
X1444944Y547891D01*
G01X1444010Y548643D02*
X1445697Y549816D01*
G01X1444944Y547891D02*
X1446159Y548736D01*
G01X1445697Y549816D02*
X1491066Y559045D01*
G01X1446159Y548736D02*
X1491066Y557871D01*
G01X1429158Y526697D02*
X1432990Y527577D01*
G01X1428470Y527720D02*
X1432311Y528602D01*
G01X1432990Y527577D02*
X1436511Y532437D01*
G01X1432311Y528602D02*
X1435480Y532976D01*
G01X1436511Y532437D02*
X1437675Y535771D01*
G01X1435480Y532976D02*
X1436466Y535798D01*
G01X1437675Y535771D02*
X1435226Y543942D01*
G01X1436466Y535798D02*
X1434006Y544004D01*
G01X1435226Y543942D02*
X1438536Y551931D01*
G01X1434006Y544004D02*
X1437689Y552894D01*
G01X1438536Y551931D02*
X1444907Y553657D01*
G01X1437689Y552894D02*
X1444851Y554834D01*
G01X1444907Y553657D02*
X1448186Y553096D01*
G01X1444851Y554834D02*
X1448168Y554266D01*
G01X1448186Y553096D02*
X1476172Y558790D01*
G01X1448168Y554266D02*
X1475694Y559867D01*
G01X1455754Y528880D02*
X1463280D01*
G01X1456231Y527730D02*
X1463757D01*
G01X1463280Y528880D02*
X1466250Y531850D01*
G01X1463757Y527730D02*
X1467400Y531373D01*
G01X1506050Y100548D02*
Y77969D01*
G01X1504900Y100071D02*
Y77492D01*
G01X1506050Y77969D02*
X1511129Y72890D01*
G01X1504900Y77492D02*
X1510652Y71740D01*
G01X1511129Y72890D02*
X1542070D01*
G01X1510652Y71740D02*
X1542547D01*
G01X1541106Y68197D02*
X1519722D01*
G01X1517072D02*
X1515722D01*
G01X1513072D02*
X1510163D01*
G01X1541583Y67047D02*
X1509686D01*
G01X1510163Y68197D02*
X1503550Y74810D01*
G01X1509686Y67047D02*
X1502400Y74333D01*
G01X1503550Y74810D02*
Y99434D01*
G01X1502400Y74333D02*
Y98957D01*
G01X1543291Y63610D02*
X1508622D01*
G01X1543291D02*
X1508622D01*
G01X1543291D02*
X1508622D01*
G01X1543291D02*
X1508622D01*
G01X1543291D02*
X1508622D01*
G01X1525201Y64760D02*
X1509099D01*
G01X1508622Y63610D02*
X1498846Y73386D01*
G01X1509099Y64760D02*
X1499996Y73863D01*
G01X1498846Y73386D02*
Y79711D01*
G01X1499996Y73863D02*
Y80188D01*
G01X1498846Y79711D02*
X1495930Y82627D01*
G01X1499996Y80188D02*
X1497080Y83104D01*
G01X1495930Y82627D02*
Y87650D01*
G01X1497080Y83104D02*
Y87173D01*
G01X1495930Y87650D02*
X1497436Y89156D01*
G01X1497080Y87173D02*
X1497913Y88006D01*
G01X1495930Y87650D02*
X1497436Y89156D01*
G01D02*
X1498550D01*
G01X1497913Y88006D02*
X1498550D01*
G01X1504900Y100071D02*
Y77492D01*
G01X1506050Y100548D02*
Y77969D01*
G01X1504900Y77492D02*
X1510652Y71740D01*
G01X1506050Y77969D02*
X1511129Y72890D01*
G01X1510652Y71740D02*
X1542547D01*
G01X1511129Y72890D02*
X1542070D01*
G01X1541583Y67047D02*
X1509686D01*
G01X1541106Y68197D02*
X1519722D01*
G01X1541583Y67047D02*
X1509686D01*
G01X1517072Y68197D02*
X1515722D01*
G01X1541583Y67047D02*
X1509686D01*
G01X1513072Y68197D02*
X1510163D01*
G01X1509686Y67047D02*
X1502400Y74333D01*
G01X1510163Y68197D02*
X1503550Y74810D01*
G01X1502400Y74333D02*
Y98957D01*
G01X1503550Y74810D02*
Y99434D01*
G01X1525201Y64760D02*
X1509099D01*
G01X1543291Y63610D02*
X1508622D01*
G01X1509099Y64760D02*
X1499996Y73863D01*
G01X1508622Y63610D02*
X1498846Y73386D01*
G01X1499996Y73863D02*
Y80188D01*
G01X1498846Y73386D02*
Y79711D01*
G01X1499996Y80188D02*
X1497080Y83104D01*
G01X1498846Y79711D02*
X1495930Y82627D01*
G01X1497080Y83104D02*
Y87173D01*
G01X1495930Y82627D02*
Y87650D01*
G01X1497080Y87173D02*
X1497913Y88006D01*
G01D02*
X1498550D01*
G01X1495930Y87650D02*
X1497436Y89156D01*
G01X1497913Y88006D02*
X1498550D01*
G01X1497436Y89156D02*
X1498550D01*
G01X1541924Y75509D02*
X1515133D01*
G01X1541447Y76659D02*
X1515610D01*
G01X1515133Y75509D02*
X1508000Y82642D01*
G01X1515610Y76659D02*
X1509150Y83119D01*
G01X1508000Y82642D02*
Y101522D01*
G01X1509150Y83119D02*
Y101999D01*
G01X1541447Y76659D02*
X1515610D01*
G01X1541924Y75509D02*
X1515133D01*
G01X1515610Y76659D02*
X1509150Y83119D01*
G01X1515133Y75509D02*
X1508000Y82642D01*
G01X1509150Y83119D02*
Y101999D01*
G01X1508000Y82642D02*
Y101522D01*
G01X1501608Y113235D02*
X1502722D01*
G01D02*
X1505177Y110780D01*
G01X1501607Y112085D02*
X1502245D01*
G01X1502722Y113235D02*
X1505177Y110780D01*
G01X1502245Y112085D02*
X1504027Y110303D01*
G01X1505177Y110780D02*
Y101421D01*
G01X1504027Y110303D02*
Y100944D01*
G01X1505177Y101421D02*
X1506050Y100548D01*
G01X1504027Y100944D02*
X1504900Y100071D01*
G01X1503550Y99434D02*
X1501251Y101733D01*
G01X1502400Y98957D02*
X1500774Y100583D01*
G01X1501251Y101733D02*
X1499943D01*
G01X1500774Y100583D02*
X1500006D01*
G01X1501607Y112085D02*
X1502245D01*
G01X1501608Y113235D02*
X1502722D01*
G01X1501607Y112085D02*
X1502245D01*
G01D02*
X1504027Y110303D01*
G01X1502722Y113235D02*
X1505177Y110780D01*
G01X1504027Y110303D02*
Y100944D01*
G01X1505177Y110780D02*
Y101421D01*
G01X1504027Y100944D02*
X1504900Y100071D01*
G01X1505177Y101421D02*
X1506050Y100548D01*
G01X1502400Y98957D02*
X1500774Y100583D01*
G01X1503550Y99434D02*
X1501251Y101733D01*
G01X1500774Y100583D02*
X1500006D01*
G01X1501251Y101733D02*
X1499943D01*
G01X1526294Y96340D02*
X1522269D01*
G01X1526294Y95190D02*
X1521792D01*
G01X1522269Y96340D02*
X1521490Y97119D01*
G01X1521792Y95190D02*
X1520340Y96642D01*
G01X1521490Y97119D02*
Y124689D01*
G01X1520340Y96642D02*
Y125166D01*
G01X1521490Y124689D02*
X1523382Y126581D01*
G01X1520340Y125166D02*
X1522232Y127058D01*
G01X1523382Y126581D02*
Y131413D01*
G01X1522232Y127058D02*
Y130936D01*
G01X1523382Y131413D02*
X1521814Y132981D01*
G01X1522232Y130936D02*
X1520664Y132504D01*
G01X1521814Y132981D02*
Y140277D01*
G01X1520664Y132504D02*
Y140754D01*
G01X1521814Y140277D02*
X1536641Y155104D01*
G01X1520664Y140754D02*
X1535491Y155581D01*
G01X1508000Y101522D02*
X1507127Y102395D01*
G01X1509150Y101999D02*
X1508277Y102872D01*
G01X1507127Y102395D02*
Y111588D01*
G01X1508277Y102872D02*
Y112065D01*
G01X1507127Y111588D02*
X1501466Y117249D01*
G01X1508277Y112065D02*
X1501943Y118399D01*
G01X1501466Y117249D02*
X1497300D01*
G01X1501943Y118399D02*
X1497581D01*
G01X1509150Y101999D02*
X1508277Y102872D01*
G01X1508000Y101522D02*
X1507127Y102395D01*
G01X1508277Y102872D02*
Y112065D01*
G01X1507127Y102395D02*
Y111588D01*
G01X1508277Y112065D02*
X1501943Y118399D01*
G01X1507127Y111588D02*
X1501466Y117249D01*
G01X1501943Y118399D02*
X1497581D01*
G01X1501466Y117249D02*
X1497300D01*
G01X1509726Y156452D02*
X1511073Y149829D01*
G01X1508503Y156690D02*
X1509899Y149829D01*
G01X1509726Y156452D02*
X1511073Y149829D01*
G01D02*
X1511349Y148473D01*
G01X1509899Y149829D02*
X1510127Y148711D01*
G01X1511350Y148473D02*
X1503575Y136725D01*
G01X1510127Y148711D02*
X1502878Y137758D01*
G01X1503575Y136725D02*
X1499087Y135812D01*
G01X1502878Y137758D02*
X1498391Y136844D01*
G01X1499087Y135812D02*
X1493430Y127268D01*
G01X1498391Y136844D02*
X1492600Y128098D01*
G01X1493430Y127268D02*
X1491014Y125668D01*
G01X1492600Y128098D02*
X1490184Y126498D01*
G01X1491014Y125668D02*
X1488130Y121310D01*
G01X1490184Y126498D02*
X1486980Y121657D01*
G01X1488130Y121310D02*
Y119596D01*
G01X1486980Y121657D02*
Y120073D01*
G01X1488130Y119596D02*
X1486307Y117773D01*
G01X1486980Y120073D02*
X1485830Y118923D01*
G01X1486307Y117773D02*
X1485237D01*
G01X1485830Y118923D02*
X1485189D01*
G01X1508503Y156690D02*
X1509899Y149829D01*
G01D02*
X1510127Y148711D01*
G01X1509726Y156452D02*
X1511073Y149829D01*
G01X1509899D02*
X1510127Y148711D01*
G01X1511073Y149829D02*
X1511349Y148473D01*
G01X1510127Y148711D02*
X1502878Y137758D01*
G01X1511350Y148473D02*
X1503575Y136725D01*
G01X1502878Y137758D02*
X1498391Y136844D01*
G01X1503575Y136725D02*
X1499087Y135812D01*
G01X1498391Y136844D02*
X1492600Y128098D01*
G01X1499087Y135812D02*
X1493430Y127268D01*
G01X1492600Y128098D02*
X1490184Y126498D01*
G01X1493430Y127268D02*
X1491014Y125668D01*
G01X1490184Y126498D02*
X1486980Y121657D01*
G01X1491014Y125668D02*
X1488130Y121310D01*
G01X1486980Y121657D02*
Y120073D01*
G01X1488130Y121310D02*
Y119596D01*
G01X1486980Y120073D02*
X1485830Y118923D01*
G01X1488130Y119596D02*
X1486307Y117773D01*
G01X1485830Y118923D02*
X1485189D01*
G01X1486307Y117773D02*
X1485237D01*
G01X1508318Y163322D02*
X1497984Y147706D01*
G01X1509015Y162289D02*
X1499067Y147257D01*
G01X1497984Y147706D02*
X1496977Y142761D01*
G01X1499067Y147257D02*
X1498060Y142312D01*
G01X1496977Y142761D02*
X1488506Y129963D01*
G01X1498060Y142312D02*
X1489202Y128931D01*
G01X1488506Y129963D02*
X1487471Y129752D01*
G01D02*
X1486833D01*
G01X1489202Y128931D02*
X1487588Y128602D01*
G01X1487471Y129752D02*
X1486833D01*
G01X1487588Y128602D02*
X1486551D01*
G01X1487471Y129752D02*
X1486833D01*
G01D02*
X1486269Y130046D01*
G01X1486551Y128602D02*
X1485738Y129025D01*
G01X1509015Y162289D02*
X1499067Y147257D01*
G01X1508318Y163322D02*
X1497984Y147706D01*
G01X1499067Y147257D02*
X1498060Y142312D01*
G01X1497984Y147706D02*
X1496977Y142761D01*
G01X1498060Y142312D02*
X1489202Y128931D01*
G01X1496977Y142761D02*
X1488506Y129963D01*
G01X1489202Y128931D02*
X1487588Y128602D01*
G01X1488506Y129963D02*
X1487471Y129752D01*
G01X1489202Y128931D02*
X1487588Y128602D01*
G01D02*
X1486551D01*
G01D02*
X1485738Y129025D01*
G01X1487471Y129752D02*
X1486833D01*
G01X1486551Y128602D02*
X1485738Y129025D01*
G01X1486833Y129752D02*
X1486269Y130046D01*
G01X1526963Y118844D02*
X1530188D01*
G01X1526963Y117694D02*
X1530665D01*
G01X1526963D02*
X1530665D01*
G01X1526963Y118844D02*
X1530188D01*
G01X1526294Y95190D02*
X1521792D01*
G01X1526294Y96340D02*
X1522269D01*
G01X1521792Y95190D02*
X1520340Y96642D01*
G01X1522269Y96340D02*
X1521490Y97119D01*
G01X1520340Y96642D02*
Y125166D01*
G01X1521490Y97119D02*
Y124689D01*
G01X1520340Y125166D02*
X1522232Y127058D01*
G01X1521490Y124689D02*
X1523382Y126581D01*
G01X1522232Y127058D02*
Y130936D01*
G01X1523382Y126581D02*
Y131413D01*
G01X1522232Y130936D02*
X1520664Y132504D01*
G01X1523382Y131413D02*
X1521814Y132981D01*
G01X1520664Y132504D02*
Y140754D01*
G01X1521814Y132981D02*
Y140277D01*
G01X1520664Y140754D02*
X1535491Y155581D01*
G01X1521814Y140277D02*
X1536641Y155104D01*
G01X1519046Y154092D02*
Y152742D01*
G01Y150092D02*
Y148742D01*
G01Y146092D02*
Y144105D01*
G01X1520196Y159792D02*
Y143628D01*
G01X1519046Y144105D02*
X1516810Y141869D01*
G01X1520196Y143628D02*
X1517960Y141392D01*
G01X1516810Y141869D02*
Y133696D01*
G01X1517960Y141392D02*
Y133219D01*
G01X1516810Y133696D02*
X1514600Y131486D01*
G01X1517960Y133219D02*
X1515077Y130336D01*
G01X1514600Y131486D02*
X1501256D01*
G01X1515077Y130336D02*
X1502647D01*
G01X1520196Y159792D02*
Y143628D01*
G01Y159792D02*
Y143628D01*
G01X1519046Y154092D02*
Y152742D01*
G01X1520196Y159792D02*
Y143628D01*
G01X1519046Y150092D02*
Y148742D01*
G01X1520196Y159792D02*
Y143628D01*
G01X1519046Y146092D02*
Y144105D01*
G01X1520196Y143628D02*
X1517960Y141392D01*
G01X1519046Y144105D02*
X1516810Y141869D01*
G01X1517960Y141392D02*
Y133219D01*
G01X1516810Y141869D02*
Y133696D01*
G01X1517960Y133219D02*
X1515077Y130336D01*
G01X1516810Y133696D02*
X1514600Y131486D01*
G01X1515077Y130336D02*
X1502647D01*
G01X1514600Y131486D02*
X1501256D01*
G01X1533476Y172940D02*
X1523290Y170868D01*
G01X1532779Y173973D02*
X1522594Y171900D01*
G01X1523290Y170868D02*
X1516008Y159869D01*
G01X1522594Y171900D02*
X1515312Y160901D01*
G01X1516008Y159869D02*
X1511361Y158923D01*
G01X1515312Y160901D02*
X1510664Y159956D01*
G01X1511361Y158923D02*
X1509726Y156452D01*
G01X1510664Y159956D02*
X1508503Y156690D01*
G01X1532779Y173973D02*
X1522594Y171900D01*
G01X1533476Y172940D02*
X1523290Y170868D01*
G01X1522594Y171900D02*
X1515312Y160901D01*
G01X1523290Y170868D02*
X1516008Y159869D01*
G01X1515312Y160901D02*
X1510664Y159956D01*
G01X1516008Y159869D02*
X1511361Y158923D01*
G01X1510664Y159956D02*
X1508503Y156690D01*
G01X1511361Y158923D02*
X1509726Y156452D01*
G01X1532277Y179921D02*
X1521723Y177775D01*
G01X1532973Y178889D02*
X1522420Y176742D01*
G01X1521723Y177775D02*
X1512756Y164225D01*
G01X1522420Y176742D02*
X1513453Y163192D01*
G01X1512756Y164225D02*
X1508318Y163322D01*
G01X1513453Y163192D02*
X1509015Y162289D01*
G01X1532973Y178889D02*
X1522420Y176742D01*
G01X1532277Y179921D02*
X1521723Y177775D01*
G01X1522420Y176742D02*
X1513453Y163192D01*
G01X1521723Y177775D02*
X1512756Y164225D01*
G01X1513453Y163192D02*
X1509015Y162289D01*
G01X1512756Y164225D02*
X1508318Y163322D01*
G01X1529537Y165534D02*
X1524311D01*
G01X1530014Y164384D02*
X1524788D01*
G01X1524311Y165534D02*
X1519046Y160269D01*
G01X1524788Y164384D02*
X1520196Y159792D01*
G01X1519046Y160269D02*
Y156742D01*
G01X1530014Y164384D02*
X1524788D01*
G01X1529537Y165534D02*
X1524311D01*
G01X1524788Y164384D02*
X1520196Y159792D01*
G01X1524311Y165534D02*
X1519046Y160269D01*
G01D02*
Y156742D01*
G01X1468209Y422473D02*
Y421658D01*
G01X1469359Y421614D02*
Y421996D01*
G01X1469868Y424132D02*
X1468209Y422473D01*
G01X1469359Y421996D02*
X1470345Y422982D01*
G01X1474880Y424132D02*
X1469868D01*
G01X1470345Y422982D02*
X1475357D01*
G01X1475893Y425145D02*
X1474880Y424132D01*
G01X1475357Y422982D02*
X1477043Y424668D01*
G01X1475893Y428519D02*
Y425145D01*
G01X1477043Y424668D02*
Y428042D01*
G01X1476675Y429301D02*
X1475893Y428519D01*
G01X1477043Y428042D02*
X1477825Y428824D01*
G01X1476675Y487734D02*
Y429301D01*
G01X1477825Y428824D02*
Y487257D01*
G01Y428824D02*
Y487257D01*
G01X1476675Y487734D02*
Y429301D01*
G01X1477043Y428042D02*
X1477825Y428824D01*
G01X1476675Y429301D02*
X1475893Y428519D01*
G01X1477043Y424668D02*
Y428042D01*
G01X1475893Y428519D02*
Y425145D01*
G01X1475357Y422982D02*
X1477043Y424668D01*
G01X1475893Y425145D02*
X1474880Y424132D01*
G01X1470345Y422982D02*
X1475357D01*
G01X1474880Y424132D02*
X1469868D01*
G01X1469359Y421996D02*
X1470345Y422982D01*
G01X1469868Y424132D02*
X1468209Y422473D01*
G01X1469359Y421614D02*
Y421996D01*
G01X1468209Y422473D02*
Y421658D01*
G01X1479076Y486661D02*
Y427618D01*
G01X1480226Y486184D02*
Y427141D01*
G01X1479076Y427618D02*
X1478229Y426771D01*
G01X1480226Y427141D02*
X1479379Y426294D01*
G01X1478229Y426771D02*
Y417373D01*
G01X1479379Y426294D02*
Y417850D01*
G01X1478229Y417373D02*
X1479418Y416184D01*
G01X1479379Y417850D02*
X1479895Y417334D01*
G01X1479418Y416184D02*
X1480887D01*
G01X1479895Y417334D02*
X1480887D01*
G01X1480226Y486184D02*
Y427141D01*
G01X1479076Y486661D02*
Y427618D01*
G01X1480226Y427141D02*
X1479379Y426294D01*
G01X1479076Y427618D02*
X1478229Y426771D01*
G01X1479379Y426294D02*
Y417850D01*
G01X1478229Y426771D02*
Y417373D01*
G01X1479379Y417850D02*
X1479895Y417334D01*
G01X1478229Y417373D02*
X1479418Y416184D01*
G01X1479895Y417334D02*
X1480887D01*
G01X1479418Y416184D02*
X1480887D01*
G01X1469765Y521825D02*
X1477299Y523357D01*
G01X1469316Y522908D02*
X1476850Y524440D01*
G01X1477299Y523357D02*
X1479923Y525095D01*
G01D02*
X1479924D01*
G01D02*
X1482550Y526834D01*
G01X1476850Y524440D02*
X1482103Y527918D01*
G01X1469316Y522908D02*
X1476850Y524440D01*
G01X1469765Y521825D02*
X1477299Y523357D01*
G01X1476850Y524440D02*
X1482103Y527918D01*
G01X1477299Y523357D02*
X1479923Y525095D01*
G01X1476850Y524440D02*
X1482103Y527918D01*
G01X1479923Y525095D02*
X1479924D01*
G01X1476850Y524440D02*
X1482103Y527918D01*
G01X1479924Y525095D02*
X1482550Y526834D01*
G01X1483791Y494850D02*
X1476675Y487734D01*
G01X1477825Y487257D02*
X1484268Y493700D01*
G01X1496980Y494850D02*
X1483791D01*
G01X1484268Y493700D02*
X1496503D01*
G01X1498830Y493000D02*
X1496980Y494850D01*
G01X1496503Y493700D02*
X1498353Y491850D01*
G01X1513140Y493000D02*
X1498830D01*
G01X1498353Y491850D02*
X1513617D01*
G01X1519163Y499023D02*
X1513140Y493000D01*
G01X1513617Y491850D02*
X1520313Y498546D01*
G01X1519163Y504411D02*
Y499023D01*
G01X1520313Y498546D02*
Y503934D01*
G01X1520129Y505377D02*
X1519163Y504411D01*
G01X1520313Y503934D02*
X1521279Y504900D01*
G01X1520129Y507687D02*
Y505377D01*
G01X1521279Y504900D02*
Y507210D01*
G01X1538705Y526263D02*
X1520129Y507687D01*
G01X1521279Y507210D02*
X1539182Y525113D01*
G01X1521279Y507210D02*
X1539182Y525113D01*
G01X1538705Y526263D02*
X1520129Y507687D01*
G01X1521279Y504900D02*
Y507210D01*
G01X1520129Y507687D02*
Y505377D01*
G01X1520313Y503934D02*
X1521279Y504900D01*
G01X1520129Y505377D02*
X1519163Y504411D01*
G01X1520313Y498546D02*
Y503934D01*
G01X1519163Y504411D02*
Y499023D01*
G01X1513617Y491850D02*
X1520313Y498546D01*
G01X1519163Y499023D02*
X1513140Y493000D01*
G01X1498353Y491850D02*
X1513617D01*
G01X1513140Y493000D02*
X1498830D01*
G01X1496503Y493700D02*
X1498353Y491850D01*
G01X1498830Y493000D02*
X1496980Y494850D01*
G01X1484268Y493700D02*
X1496503D01*
G01X1496980Y494850D02*
X1483791D01*
G01X1477825Y487257D02*
X1484268Y493700D01*
G01X1483791Y494850D02*
X1476675Y487734D01*
G01X1539826Y523763D02*
X1522649Y506586D01*
G01X1540303Y522613D02*
X1523799Y506109D01*
G01X1522649Y506586D02*
Y504200D01*
G01X1523799Y506109D02*
Y503723D01*
G01X1522649Y504200D02*
X1521732Y503283D01*
G01X1523799Y503723D02*
X1522882Y502806D01*
G01X1521732Y503283D02*
Y497419D01*
G01X1522882Y502806D02*
Y496942D01*
G01X1521732Y497419D02*
X1514823Y490510D01*
G01X1522882Y496942D02*
X1515300Y489360D01*
G01X1514823Y490510D02*
X1497170D01*
G01X1515300Y489360D02*
X1496693D01*
G01X1497170Y490510D02*
X1495102Y492578D01*
G01X1496693Y489360D02*
X1494625Y491428D01*
G01X1495102Y492578D02*
X1484993D01*
G01X1494625Y491428D02*
X1485470D01*
G01X1484993Y492578D02*
X1479076Y486661D01*
G01X1485470Y491428D02*
X1480226Y486184D01*
G01X1540303Y522613D02*
X1523799Y506109D01*
G01X1539826Y523763D02*
X1522649Y506586D01*
G01X1523799Y506109D02*
Y503723D01*
G01X1522649Y506586D02*
Y504200D01*
G01X1523799Y503723D02*
X1522882Y502806D01*
G01X1522649Y504200D02*
X1521732Y503283D01*
G01X1522882Y502806D02*
Y496942D01*
G01X1521732Y503283D02*
Y497419D01*
G01X1522882Y496942D02*
X1515300Y489360D01*
G01X1521732Y497419D02*
X1514823Y490510D01*
G01X1515300Y489360D02*
X1496693D01*
G01X1514823Y490510D02*
X1497170D01*
G01X1496693Y489360D02*
X1494625Y491428D01*
G01X1497170Y490510D02*
X1495102Y492578D01*
G01X1494625Y491428D02*
X1485470D01*
G01X1495102Y492578D02*
X1484993D01*
G01X1485470Y491428D02*
X1480226Y486184D01*
G01X1484993Y492578D02*
X1479076Y486661D01*
G01X1482550Y526834D02*
X1486795Y527684D01*
G01X1482103Y527918D02*
X1486348Y528768D01*
G01X1486795Y527684D02*
X1503321Y538621D01*
G01X1486348Y528768D02*
X1502872Y539704D01*
G01X1503321Y538621D02*
X1527138Y543465D01*
G01X1502872Y539704D02*
X1527022Y544615D01*
G01D02*
X1538061D01*
G01X1474463Y531064D02*
Y533860D01*
G01X1473313Y531541D02*
Y534337D01*
G01X1474463Y533860D02*
X1476960Y536357D01*
G01X1473313Y534337D02*
X1476483Y537507D01*
G01X1476960Y536357D02*
X1495329D01*
G01X1476483Y537507D02*
X1494982D01*
G01X1495329Y536357D02*
X1502759Y541275D01*
G01X1494982Y537507D02*
X1502310Y542358D01*
G01X1502759Y541275D02*
X1525804Y545965D01*
G01X1502310Y542358D02*
X1525688Y547115D01*
G01X1525804Y545965D02*
X1537880D01*
G01X1525688Y547115D02*
X1537726D01*
G01X1465689Y546942D02*
X1492273Y552349D01*
G01D02*
X1503181Y550128D01*
G01X1492273Y553523D02*
X1503181Y551302D01*
G01Y550128D02*
X1519734Y553494D01*
G01X1503181Y551302D02*
X1519618Y554644D01*
G01X1519734Y553494D02*
X1536870D01*
G01X1519618Y554644D02*
X1536715D01*
G01X1536376Y557164D02*
X1519355D01*
G01X1536531Y556014D02*
X1519471D01*
G01X1519355Y557164D02*
X1503540Y553948D01*
G01X1519471Y556014D02*
X1503540Y552774D01*
G01Y553948D02*
X1492591Y556177D01*
G01X1503540Y552774D02*
X1492591Y555003D01*
G01X1491066Y557871D02*
X1497694Y556523D01*
G01X1491066Y559045D02*
X1497582Y557720D01*
G01X1497694Y556523D02*
X1518594Y565056D01*
G01X1497582Y557720D02*
X1518368Y566206D01*
G01X1518594Y565056D02*
X1530818D01*
G01X1518368Y566206D02*
X1530562D01*
G01X1475694Y559867D02*
X1483375Y565515D01*
G01X1476172Y558790D02*
X1483841Y564429D01*
G01X1483375Y565515D02*
X1493172Y567256D01*
G01X1483841Y564429D02*
X1493165Y566086D01*
G01X1493172Y567256D02*
X1499533Y566042D01*
G01X1493165Y566086D02*
X1499538Y564870D01*
G01X1499533Y566042D02*
X1512970Y568714D01*
G01X1499538Y564870D02*
X1513084Y567564D01*
G01X1512970Y568714D02*
X1529605D01*
G01X1513084Y567564D02*
X1529861D01*
G01X1467400Y531373D02*
Y540298D01*
G01X1466250Y531850D02*
Y540645D01*
G01X1467400Y540298D02*
X1469084Y542843D01*
G01X1466250Y540645D02*
X1468254Y543674D01*
G01X1469084Y542843D02*
X1473210Y545568D01*
G01X1468254Y543674D02*
X1472762Y546651D01*
G01X1473210Y545568D02*
X1493033Y549599D01*
G01X1472762Y546651D02*
X1493033Y550773D01*
G01Y549599D02*
X1503086Y547553D01*
G01X1493033Y550773D02*
X1503086Y548727D01*
G01Y547553D02*
X1519858Y550965D01*
G01X1503086Y548727D02*
X1519742Y552115D01*
G01X1519858Y550965D02*
X1537209D01*
G01X1519742Y552115D02*
X1537055D01*
G01X1470348Y530548D02*
Y535065D01*
G01X1469198Y531025D02*
Y535417D01*
G01X1470348Y535065D02*
X1473125Y539181D01*
G01X1469198Y535417D02*
X1472296Y540010D01*
G01X1473125Y539181D02*
X1476464Y541434D01*
G01X1472296Y540010D02*
X1476014Y542519D01*
G01X1476464Y541434D02*
X1481579Y542428D01*
G01X1476014Y542519D02*
X1476245Y542564D01*
G01X1476464Y541434D02*
X1481579Y542428D01*
G01X1476245Y542563D02*
X1481579Y543600D01*
G01Y542428D02*
X1491376Y540525D01*
G01X1481579Y543600D02*
X1491376Y541697D01*
G01Y540525D02*
X1499017Y542010D01*
G01X1491376Y541697D02*
X1498568Y543095D01*
G01X1499017Y542010D02*
X1501473Y543666D01*
G01X1498568Y543095D02*
X1501021Y544749D01*
G01X1501473Y543666D02*
X1525458Y548465D01*
G01X1501021Y544749D02*
X1525344Y549615D01*
G01X1525458Y548465D02*
X1537545D01*
G01X1525344Y549615D02*
X1537391D01*
G01X1482103Y527918D02*
X1486348Y528768D01*
G01X1482550Y526834D02*
X1486795Y527684D01*
G01X1486348Y528768D02*
X1502872Y539704D01*
G01X1486795Y527684D02*
X1503321Y538621D01*
G01X1502872Y539704D02*
X1527022Y544615D01*
G01X1503321Y538621D02*
X1527138Y543465D01*
G01X1527022Y544615D02*
X1538061D01*
G01X1473313Y531541D02*
Y534337D01*
G01X1474463Y531064D02*
Y533860D01*
G01X1473313Y534337D02*
X1476483Y537507D01*
G01X1474463Y533860D02*
X1476960Y536357D01*
G01X1476483Y537507D02*
X1494982D01*
G01X1476960Y536357D02*
X1495329D01*
G01X1494982Y537507D02*
X1502310Y542358D01*
G01X1495329Y536357D02*
X1502759Y541275D01*
G01X1502310Y542358D02*
X1525688Y547115D01*
G01X1502759Y541275D02*
X1525804Y545965D01*
G01X1525688Y547115D02*
X1537726D01*
G01X1525804Y545965D02*
X1537880D01*
G01X1465689Y546942D02*
X1492273Y552349D01*
G01Y553523D02*
X1503181Y551302D01*
G01X1492273Y552349D02*
X1503181Y550128D01*
G01Y551302D02*
X1519618Y554644D01*
G01X1503181Y550128D02*
X1519734Y553494D01*
G01X1519618Y554644D02*
X1536715D01*
G01X1519734Y553494D02*
X1536870D01*
G01X1536531Y556014D02*
X1519471D01*
G01X1536376Y557164D02*
X1519355D01*
G01X1519471Y556014D02*
X1503540Y552774D01*
G01X1519355Y557164D02*
X1503540Y553948D01*
G01Y552774D02*
X1492591Y555003D01*
G01X1503540Y553948D02*
X1492591Y556177D01*
G01X1491066Y559045D02*
X1497582Y557720D01*
G01X1491066Y557871D02*
X1497694Y556523D01*
G01X1497582Y557720D02*
X1518368Y566206D01*
G01X1497694Y556523D02*
X1518594Y565056D01*
G01X1518368Y566206D02*
X1530562D01*
G01X1518594Y565056D02*
X1530818D01*
G01X1476172Y558790D02*
X1483841Y564429D01*
G01X1475694Y559867D02*
X1483375Y565515D01*
G01X1483841Y564429D02*
X1493165Y566086D01*
G01X1483375Y565515D02*
X1493172Y567256D01*
G01X1493165Y566086D02*
X1499538Y564870D01*
G01X1493172Y567256D02*
X1499533Y566042D01*
G01X1499538Y564870D02*
X1513084Y567564D01*
G01X1499533Y566042D02*
X1512970Y568714D01*
G01X1513084Y567564D02*
X1529861D01*
G01X1512970Y568714D02*
X1529605D01*
G01X1466250Y531850D02*
Y540645D01*
G01X1467400Y531373D02*
Y540298D01*
G01X1466250Y540645D02*
X1468254Y543674D01*
G01X1467400Y540298D02*
X1469084Y542843D01*
G01X1468254Y543674D02*
X1472762Y546651D01*
G01X1469084Y542843D02*
X1473210Y545568D01*
G01X1472762Y546651D02*
X1493033Y550773D01*
G01X1473210Y545568D02*
X1493033Y549599D01*
G01Y550773D02*
X1503086Y548727D01*
G01X1493033Y549599D02*
X1503086Y547553D01*
G01Y548727D02*
X1519742Y552115D01*
G01X1503086Y547553D02*
X1519858Y550965D01*
G01X1519742Y552115D02*
X1537055D01*
G01X1519858Y550965D02*
X1537209D01*
G01X1469198Y531025D02*
Y535417D01*
G01X1470348Y530548D02*
Y535065D01*
G01X1469198Y535417D02*
X1472296Y540010D01*
G01X1470348Y535065D02*
X1473125Y539181D01*
G01X1472296Y540010D02*
X1476014Y542519D01*
G01X1473125Y539181D02*
X1476464Y541434D01*
G01X1476014Y542519D02*
X1476245Y542564D01*
G01Y542563D02*
X1481579Y543600D01*
G01X1476464Y541434D02*
X1481579Y542428D01*
G01Y543600D02*
X1491376Y541697D01*
G01X1481579Y542428D02*
X1491376Y540525D01*
G01Y541697D02*
X1498568Y543095D01*
G01X1491376Y540525D02*
X1499017Y542010D01*
G01X1498568Y543095D02*
X1501021Y544749D01*
G01X1499017Y542010D02*
X1501473Y543666D01*
G01X1501021Y544749D02*
X1525344Y549615D01*
G01X1501473Y543666D02*
X1525458Y548465D01*
G01X1525344Y549615D02*
X1537391D01*
G01X1525458Y548465D02*
X1537545D01*
G01X1542070Y72890D02*
X1563379Y94199D01*
G01X1542547Y71740D02*
X1564529Y93722D01*
G01X1563379Y94199D02*
Y114907D01*
G01X1564529Y93722D02*
Y114430D01*
G01X1565879Y113256D02*
Y92970D01*
G01X1567029Y112779D02*
Y92493D01*
G01X1565879Y92970D02*
X1541106Y68197D01*
G01X1567029Y92493D02*
X1541583Y67047D01*
G01X1570250Y112050D02*
Y90569D01*
G01Y112050D02*
Y90569D01*
G01Y112050D02*
Y90569D01*
G01Y112050D02*
Y90569D01*
G01X1569100Y100527D02*
Y91046D01*
G01X1570250Y90569D02*
X1543291Y63610D01*
G01X1569100Y91046D02*
X1568145Y90091D01*
G01X1570250Y90569D02*
X1543291Y63610D01*
G01X1568145Y90091D02*
X1567226D01*
G01X1570250Y90569D02*
X1543291Y63610D01*
G01X1566272Y88218D02*
X1565317Y87263D01*
G01X1570250Y90569D02*
X1543291Y63610D01*
G01X1565317Y87263D02*
X1564398D01*
G01X1570250Y90569D02*
X1543291Y63610D01*
G01X1563444Y85390D02*
X1562489Y84435D01*
G01X1570250Y90569D02*
X1543291Y63610D01*
G01X1562489Y84435D02*
X1561570D01*
G01X1570250Y90569D02*
X1543291Y63610D01*
G01X1560616Y82562D02*
X1559661Y81607D01*
G01X1570250Y90569D02*
X1543291Y63610D01*
G01X1559661Y81607D02*
X1558742D01*
G01X1570250Y90569D02*
X1543291Y63610D01*
G01X1557788Y79734D02*
X1542814Y64760D01*
G01D02*
X1539851D01*
G01X1537201D02*
X1535851D01*
G01X1533201D02*
X1531851D01*
G01X1529201D02*
X1527851D01*
G01X1542547Y71740D02*
X1564529Y93722D01*
G01X1542070Y72890D02*
X1563379Y94199D01*
G01X1564529Y93722D02*
Y114430D01*
G01X1563379Y94199D02*
Y114907D01*
G01X1567029Y112779D02*
Y92493D01*
G01X1565879Y113256D02*
Y92970D01*
G01X1567029Y92493D02*
X1541583Y67047D01*
G01X1565879Y92970D02*
X1541106Y68197D01*
G01X1569100Y100527D02*
Y91046D01*
G01X1570250Y112050D02*
Y90569D01*
G01X1569100Y91046D02*
X1568145Y90091D01*
G01D02*
X1567226D01*
G01X1566272Y88218D02*
X1565317Y87263D01*
G01D02*
X1564398D01*
G01X1563444Y85390D02*
X1562489Y84435D01*
G01D02*
X1561570D01*
G01X1560616Y82562D02*
X1559661Y81607D01*
G01D02*
X1558742D01*
G01X1557788Y79734D02*
X1542814Y64760D01*
G01X1570250Y90569D02*
X1543291Y63610D01*
G01X1542814Y64760D02*
X1539851D01*
G01X1537201D02*
X1535851D01*
G01X1533201D02*
X1531851D01*
G01X1529201D02*
X1527851D01*
G01X1561237Y94822D02*
X1541924Y75509D01*
G01X1560087Y95299D02*
X1556831Y92043D01*
G01X1561237Y94822D02*
X1541924Y75509D01*
G01X1556831Y92043D02*
X1555911D01*
G01X1561237Y94822D02*
X1541924Y75509D01*
G01X1554957Y90169D02*
X1554002Y89214D01*
G01X1561237Y94822D02*
X1541924Y75509D01*
G01X1554002Y89214D02*
X1553083D01*
G01X1561237Y94822D02*
X1541924Y75509D01*
G01X1552129Y87341D02*
X1541447Y76659D01*
G01X1560087Y95299D02*
X1556831Y92043D01*
G01D02*
X1555911D01*
G01X1554957Y90169D02*
X1554002Y89214D01*
G01D02*
X1553083D01*
G01X1552129Y87341D02*
X1541447Y76659D01*
G01X1561237Y94822D02*
X1541924Y75509D01*
G01X1583250Y92900D02*
Y91550D01*
G01X1582100Y105474D02*
Y92027D01*
G01X1583250Y91550D02*
X1581781Y90081D01*
G01X1582100Y92027D02*
X1580631Y90558D01*
G01X1581781Y90081D02*
Y86441D01*
G01X1580631Y90558D02*
Y85964D01*
G01X1581781Y86441D02*
X1583556Y84666D01*
G01D02*
X1584242D01*
G01X1580631Y85964D02*
X1583079Y83516D01*
G01X1583556Y84666D02*
X1584242D01*
G01X1583079Y83516D02*
X1583765D01*
G01X1584242Y84666D02*
X1586357Y82551D01*
G01X1583765Y83516D02*
X1585207Y82074D01*
G01X1586357Y82551D02*
Y80030D01*
G01X1585207Y82074D02*
Y80507D01*
G01X1586357Y80030D02*
X1585485Y79158D01*
G01X1585207Y80507D02*
X1584335Y79635D01*
G01X1585485Y79158D02*
Y74293D01*
G01X1584335Y79635D02*
Y74770D01*
G01X1585485Y74293D02*
X1582857Y71665D01*
G01X1584335Y74770D02*
X1581707Y72142D01*
G01X1582857Y71665D02*
Y68438D01*
G01X1581707Y72142D02*
Y67961D01*
G01X1582857Y68438D02*
X1584605Y66690D01*
G01D02*
X1585759D01*
G01X1581707Y67961D02*
X1584128Y65540D01*
G01X1584605Y66690D02*
X1585759D01*
G01X1588459D02*
X1589859D01*
G01X1584128Y65540D02*
X1597697D01*
G01X1582100Y105474D02*
Y92027D01*
G01Y105474D02*
Y92027D01*
G01Y105474D02*
Y92027D01*
G01X1583250Y92900D02*
Y91550D01*
G01X1582100Y92027D02*
X1580631Y90558D01*
G01X1583250Y91550D02*
X1581781Y90081D01*
G01X1580631Y90558D02*
Y85964D01*
G01X1581781Y90081D02*
Y86441D01*
G01X1580631Y85964D02*
X1583079Y83516D01*
G01X1581781Y86441D02*
X1583556Y84666D01*
G01X1580631Y85964D02*
X1583079Y83516D01*
G01D02*
X1583765D01*
G01X1583556Y84666D02*
X1584242D01*
G01X1583765Y83516D02*
X1585207Y82074D01*
G01X1584242Y84666D02*
X1586357Y82551D01*
G01X1585207Y82074D02*
Y80507D01*
G01X1586357Y82551D02*
Y80030D01*
G01X1585207Y80507D02*
X1584335Y79635D01*
G01X1586357Y80030D02*
X1585485Y79158D01*
G01X1584335Y79635D02*
Y74770D01*
G01X1585485Y79158D02*
Y74293D01*
G01X1584335Y74770D02*
X1581707Y72142D01*
G01X1585485Y74293D02*
X1582857Y71665D01*
G01X1581707Y72142D02*
Y67961D01*
G01X1582857Y71665D02*
Y68438D01*
G01X1581707Y67961D02*
X1584128Y65540D01*
G01X1582857Y68438D02*
X1584605Y66690D01*
G01X1581707Y67961D02*
X1584128Y65540D01*
G01D02*
X1597697D01*
G01X1584605Y66690D02*
X1585759D01*
G01X1584128Y65540D02*
X1597697D01*
G01X1588459Y66690D02*
X1589859D01*
G01X1584128Y65540D02*
X1597697D01*
G01X1563379Y114907D02*
X1566900Y118428D01*
G01X1564529Y114430D02*
X1568050Y117951D01*
G01X1566900Y118428D02*
Y123042D01*
G01X1568050Y117951D02*
Y122565D01*
G01X1566900Y123042D02*
X1568450Y124592D01*
G01X1568050Y122565D02*
X1569600Y124115D01*
G01X1568450Y124592D02*
Y130619D01*
G01X1569600Y124115D02*
Y130142D01*
G01X1568450Y130619D02*
X1570850Y133019D01*
G01X1569600Y130142D02*
X1572000Y132542D01*
G01X1570850Y133019D02*
Y144773D01*
G01X1572000Y132542D02*
Y145250D01*
G01X1570850Y144773D02*
X1568050Y147573D01*
G01X1572000Y145250D02*
X1569200Y148050D01*
G01X1568050Y147573D02*
Y154528D01*
G01X1569200Y148050D02*
Y154051D01*
G01X1568050Y154528D02*
X1572000Y158478D01*
G01X1569200Y154051D02*
X1573150Y158001D01*
G01X1574800Y157718D02*
X1570550Y153468D01*
G01X1575950Y157241D02*
X1571700Y152991D01*
G01X1570550Y153468D02*
Y148699D01*
G01X1571700Y152991D02*
Y149176D01*
G01X1570550Y148699D02*
X1573500Y145749D01*
G01X1571700Y149176D02*
X1574650Y146226D01*
G01X1573500Y145749D02*
Y131743D01*
G01X1574650Y146226D02*
Y131266D01*
G01X1573500Y131743D02*
X1571200Y129443D01*
G01X1574650Y131266D02*
X1572350Y128966D01*
G01X1571200Y129443D02*
Y123757D01*
G01X1572350Y128966D02*
Y123280D01*
G01X1571200Y123757D02*
X1569425Y121982D01*
G01X1572350Y123280D02*
X1570575Y121505D01*
G01X1569425Y121982D02*
Y116802D01*
G01X1570575Y121505D02*
Y116325D01*
G01X1569425Y116802D02*
X1565879Y113256D01*
G01X1570575Y116325D02*
X1567029Y112779D01*
G01X1581393Y161237D02*
Y137458D01*
G01X1580243Y161714D02*
Y137935D01*
G01X1581393Y137458D02*
X1577450Y133515D01*
G01X1580243Y137935D02*
X1576300Y133992D01*
G01X1577450Y133515D02*
Y119250D01*
G01X1576300Y133992D02*
Y119727D01*
G01X1577450Y119250D02*
X1570250Y112050D01*
G01X1576300Y119727D02*
X1569100Y112527D01*
G01D02*
Y111177D01*
G01Y108527D02*
Y107177D01*
G01Y104527D02*
Y103177D01*
G01X1564529Y114430D02*
X1568050Y117951D01*
G01X1563379Y114907D02*
X1566900Y118428D01*
G01X1568050Y117951D02*
Y122565D01*
G01X1566900Y118428D02*
Y123042D01*
G01X1568050Y122565D02*
X1569600Y124115D01*
G01X1566900Y123042D02*
X1568450Y124592D01*
G01X1569600Y124115D02*
Y130142D01*
G01X1568450Y124592D02*
Y130619D01*
G01X1569600Y130142D02*
X1572000Y132542D01*
G01X1568450Y130619D02*
X1570850Y133019D01*
G01X1572000Y132542D02*
Y145250D01*
G01X1570850Y133019D02*
Y144773D01*
G01X1572000Y145250D02*
X1569200Y148050D01*
G01X1570850Y144773D02*
X1568050Y147573D01*
G01X1569200Y148050D02*
Y154051D01*
G01X1568050Y147573D02*
Y154528D01*
G01X1569200Y154051D02*
X1573150Y158001D01*
G01X1568050Y154528D02*
X1572000Y158478D01*
G01X1575950Y157241D02*
X1571700Y152991D01*
G01X1574800Y157718D02*
X1570550Y153468D01*
G01X1571700Y152991D02*
Y149176D01*
G01X1570550Y153468D02*
Y148699D01*
G01X1571700Y149176D02*
X1574650Y146226D01*
G01X1570550Y148699D02*
X1573500Y145749D01*
G01X1574650Y146226D02*
Y131266D01*
G01X1573500Y145749D02*
Y131743D01*
G01X1574650Y131266D02*
X1572350Y128966D01*
G01X1573500Y131743D02*
X1571200Y129443D01*
G01X1572350Y128966D02*
Y123280D01*
G01X1571200Y129443D02*
Y123757D01*
G01X1572350Y123280D02*
X1570575Y121505D01*
G01X1571200Y123757D02*
X1569425Y121982D01*
G01X1570575Y121505D02*
Y116325D01*
G01X1569425Y121982D02*
Y116802D01*
G01X1570575Y116325D02*
X1567029Y112779D01*
G01X1569425Y116802D02*
X1565879Y113256D01*
G01X1580243Y161714D02*
Y137935D01*
G01X1581393Y161237D02*
Y137458D01*
G01X1580243Y137935D02*
X1576300Y133992D01*
G01X1581393Y137458D02*
X1577450Y133515D01*
G01X1576300Y133992D02*
Y119727D01*
G01X1577450Y133515D02*
Y119250D01*
G01X1576300Y119727D02*
X1569100Y112527D01*
G01X1577450Y119250D02*
X1570250Y112050D01*
G01X1569100Y112527D02*
Y111177D01*
G01Y108527D02*
Y107177D01*
G01Y104527D02*
Y103177D01*
G01X1536641Y155104D02*
Y157715D01*
G01X1535491Y155581D02*
Y158192D01*
G01X1569950Y159222D02*
X1565500Y154772D01*
G01X1568800Y159699D02*
X1564350Y155249D01*
G01X1565500Y154772D02*
Y129000D01*
G01X1564350Y155249D02*
Y128523D01*
G01X1565500Y129000D02*
X1566500Y128000D01*
G01X1564350Y128523D02*
X1565350Y127523D01*
G01X1566500Y128000D02*
Y125400D01*
G01X1565350Y127523D02*
Y125877D01*
G01X1566500Y125400D02*
X1564950Y123850D01*
G01X1565350Y125877D02*
X1563800Y124327D01*
G01X1564950Y123850D02*
Y119350D01*
G01X1563800Y124327D02*
Y119827D01*
G01X1564950Y119350D02*
X1561237Y115637D01*
G01X1563800Y119827D02*
X1560087Y116114D01*
G01X1561237Y115637D02*
Y94822D01*
G01X1560087Y116114D02*
Y95299D01*
G01X1568800Y159699D02*
X1564350Y155249D01*
G01X1569950Y159222D02*
X1565500Y154772D01*
G01X1564350Y155249D02*
Y128523D01*
G01X1565500Y154772D02*
Y129000D01*
G01X1564350Y128523D02*
X1565350Y127523D01*
G01X1565500Y129000D02*
X1566500Y128000D01*
G01X1565350Y127523D02*
Y125877D01*
G01X1566500Y128000D02*
Y125400D01*
G01X1565350Y125877D02*
X1563800Y124327D01*
G01X1566500Y125400D02*
X1564950Y123850D01*
G01X1563800Y124327D02*
Y119827D01*
G01X1564950Y123850D02*
Y119350D01*
G01X1563800Y119827D02*
X1560087Y116114D01*
G01X1564950Y119350D02*
X1561237Y115637D01*
G01X1560087Y116114D02*
Y95299D01*
G01X1561237Y115637D02*
Y94822D01*
G01X1530188Y118844D02*
X1533551Y122207D01*
G01X1530665Y117694D02*
X1534701Y121730D01*
G01X1533551Y122207D02*
Y141671D01*
G01X1534701Y121730D02*
Y141194D01*
G01X1533551Y141671D02*
X1537874Y145994D01*
G01X1534701Y141194D02*
X1538351Y144844D01*
G01X1537874Y145994D02*
X1542103D01*
G01X1538351Y144844D02*
X1542580D01*
G01X1542103Y145994D02*
X1544098Y147989D01*
G01X1542580Y144844D02*
X1545248Y147512D01*
G01X1544098Y147989D02*
Y157969D01*
G01X1545248Y147512D02*
Y158446D01*
G01X1527780Y107048D02*
X1530606D01*
G01X1527554Y105898D02*
X1531083D01*
G01X1530606Y107048D02*
X1537212Y113654D01*
G01X1531083Y105898D02*
X1538362Y113177D01*
G01X1537212Y113654D02*
Y140051D01*
G01X1538362Y113177D02*
Y139574D01*
G01X1537212Y140051D02*
X1540178Y143017D01*
G01X1538362Y139574D02*
X1540655Y141867D01*
G01X1540178Y143017D02*
X1542663D01*
G01X1540655Y141867D02*
X1543140D01*
G01X1542663Y143017D02*
X1547054Y147408D01*
G01X1543140Y141867D02*
X1548204Y146931D01*
G01X1547054Y147408D02*
Y171381D01*
G01X1548204Y146931D02*
Y170904D01*
G01X1530665Y117694D02*
X1534701Y121730D01*
G01X1530188Y118844D02*
X1533551Y122207D01*
G01X1534701Y121730D02*
Y141194D01*
G01X1533551Y122207D02*
Y141671D01*
G01X1534701Y141194D02*
X1538351Y144844D01*
G01X1533551Y141671D02*
X1537874Y145994D01*
G01X1538351Y144844D02*
X1542580D01*
G01X1537874Y145994D02*
X1542103D01*
G01X1542580Y144844D02*
X1545248Y147512D01*
G01X1542103Y145994D02*
X1544098Y147989D01*
G01X1545248Y147512D02*
Y158446D01*
G01X1544098Y147989D02*
Y157969D01*
G01X1527554Y105898D02*
X1531083D01*
G01X1527780Y107048D02*
X1530606D01*
G01X1531083Y105898D02*
X1538362Y113177D01*
G01X1530606Y107048D02*
X1537212Y113654D01*
G01X1538362Y113177D02*
Y139574D01*
G01X1537212Y113654D02*
Y140051D01*
G01X1538362Y139574D02*
X1540655Y141867D01*
G01X1537212Y140051D02*
X1540178Y143017D01*
G01X1540655Y141867D02*
X1543140D01*
G01X1540178Y143017D02*
X1542663D01*
G01X1543140Y141867D02*
X1548204Y146931D01*
G01X1542663Y143017D02*
X1547054Y147408D01*
G01X1548204Y146931D02*
Y170904D01*
G01X1547054Y147408D02*
Y171381D01*
G01X1535491Y155581D02*
Y158192D01*
G01X1536641Y155104D02*
Y157715D01*
G01X1584535Y159959D02*
Y148058D01*
G01Y145358D02*
Y143958D01*
G01Y141258D02*
Y139858D01*
G01Y137158D02*
Y131118D01*
G01Y128468D02*
Y127118D01*
G01Y124468D02*
Y123118D01*
G01Y120468D02*
Y119118D01*
G01Y116468D02*
Y114934D01*
G01X1583385Y160436D02*
Y115411D01*
G01X1584535Y114934D02*
X1580500Y110899D01*
G01X1583385Y115411D02*
X1579350Y111376D01*
G01X1580500Y110899D02*
Y108701D01*
G01X1579350Y111376D02*
Y108224D01*
G01X1580500Y108701D02*
X1583250Y105951D01*
G01X1579350Y108224D02*
X1582100Y105474D01*
G01X1583250Y105951D02*
Y99550D01*
G01Y96900D02*
Y95550D01*
G01X1583385Y160436D02*
Y115411D01*
G01X1584535Y159959D02*
Y148058D01*
G01X1583385Y160436D02*
Y115411D01*
G01X1584535Y145358D02*
Y143958D01*
G01X1583385Y160436D02*
Y115411D01*
G01X1584535Y141258D02*
Y139858D01*
G01X1583385Y160436D02*
Y115411D01*
G01X1584535Y137158D02*
Y131118D01*
G01X1583385Y160436D02*
Y115411D01*
G01X1584535Y128468D02*
Y127118D01*
G01X1583385Y160436D02*
Y115411D01*
G01X1584535Y124468D02*
Y123118D01*
G01X1583385Y160436D02*
Y115411D01*
G01X1584535Y120468D02*
Y119118D01*
G01X1583385Y160436D02*
Y115411D01*
G01X1584535Y116468D02*
Y114934D01*
G01X1583385Y115411D02*
X1579350Y111376D01*
G01X1584535Y114934D02*
X1580500Y110899D01*
G01X1579350Y111376D02*
Y108224D01*
G01X1580500Y110899D02*
Y108701D01*
G01X1579350Y108224D02*
X1582100Y105474D01*
G01X1580500Y108701D02*
X1583250Y105951D01*
G01D02*
Y99550D01*
G01Y96900D02*
Y95550D01*
G01X1556402Y126125D02*
X1549860D01*
G01X1556449Y127275D02*
X1550337D01*
G01X1549860Y126125D02*
X1546391Y129594D01*
G01X1550337Y127275D02*
X1547541Y130071D01*
G01X1546391Y129594D02*
Y142131D01*
G01X1547541Y130071D02*
Y141654D01*
G01X1546391Y142131D02*
X1550783Y146523D01*
G01X1547541Y141654D02*
X1551933Y146046D01*
G01X1550783Y146523D02*
Y153976D01*
G01X1551933Y146046D02*
Y154453D01*
G01X1550783Y153976D02*
X1550154Y154605D01*
G01X1551933Y154453D02*
X1551304Y155082D01*
G01X1550154Y154605D02*
Y166281D01*
G01X1551304Y155082D02*
Y165804D01*
G01X1556449Y127275D02*
X1550337D01*
G01X1556402Y126125D02*
X1549860D01*
G01X1550337Y127275D02*
X1547541Y130071D01*
G01X1549860Y126125D02*
X1546391Y129594D01*
G01X1547541Y130071D02*
Y141654D01*
G01X1546391Y129594D02*
Y142131D01*
G01X1547541Y141654D02*
X1551933Y146046D01*
G01X1546391Y142131D02*
X1550783Y146523D01*
G01X1551933Y146046D02*
Y154453D01*
G01X1550783Y146523D02*
Y153976D01*
G01X1551933Y154453D02*
X1551304Y155082D01*
G01X1550783Y153976D02*
X1550154Y154605D01*
G01X1551304Y155082D02*
Y165804D01*
G01X1550154Y154605D02*
Y166281D01*
G01X1565963Y159663D02*
X1561683Y155383D01*
G01X1564813Y160140D02*
X1560533Y155860D01*
G01X1561683Y155383D02*
Y136317D01*
G01X1560533Y155860D02*
Y148870D01*
G01X1561683Y155383D02*
Y136317D01*
G01X1560533Y146220D02*
Y144870D01*
G01X1561683Y155383D02*
Y136317D01*
G01X1560533Y142220D02*
Y136794D01*
G01X1561683Y136317D02*
X1561283Y135917D01*
G01X1560533Y136794D02*
X1560133Y136394D01*
G01X1561283Y135917D02*
Y122926D01*
G01X1560133Y136394D02*
Y122449D01*
G01X1561475Y122734D02*
Y120266D01*
G01X1560325Y122257D02*
Y120743D01*
G01X1561475Y120266D02*
X1559734Y118525D01*
G01X1560325Y120743D02*
X1559257Y119675D01*
G01X1559734Y118525D02*
X1559153D01*
G01X1559257Y119675D02*
X1558676D01*
G01X1559734Y118525D02*
X1559153D01*
G01D02*
X1555550Y114922D01*
G01X1558676Y119675D02*
X1554400Y115399D01*
G01X1555550Y114922D02*
Y105450D01*
G01X1554400Y115399D02*
Y112973D01*
G01X1555550Y114922D02*
Y105450D01*
G01X1554400Y110323D02*
Y108973D01*
G01X1555550Y114922D02*
Y105450D01*
G01X1554400Y106323D02*
Y104973D01*
G01X1555550Y105450D02*
X1556950Y104050D01*
G01X1554400Y104973D02*
X1555800Y103573D01*
G01X1556950Y104050D02*
Y102063D01*
G01X1555800Y103573D02*
Y102050D01*
G01X1564813Y160140D02*
X1560533Y155860D01*
G01X1565963Y159663D02*
X1561683Y155383D01*
G01X1560533Y155860D02*
Y148870D01*
G01Y146220D02*
Y144870D01*
G01Y142220D02*
Y136794D01*
G01X1561683Y155383D02*
Y136317D01*
G01X1560533Y136794D02*
X1560133Y136394D01*
G01X1561683Y136317D02*
X1561283Y135917D01*
G01X1560133Y136394D02*
Y122449D01*
G01X1561283Y135917D02*
Y122926D01*
G01X1560325Y122257D02*
Y120743D01*
G01X1561475Y122734D02*
Y120266D01*
G01X1560325Y120743D02*
X1559257Y119675D01*
G01X1561475Y120266D02*
X1559734Y118525D01*
G01X1559257Y119675D02*
X1558676D01*
G01D02*
X1554400Y115399D01*
G01X1559734Y118525D02*
X1559153D01*
G01X1558676Y119675D02*
X1554400Y115399D01*
G01X1559153Y118525D02*
X1555550Y114922D01*
G01X1554400Y115399D02*
Y112973D01*
G01Y110323D02*
Y108973D01*
G01Y106323D02*
Y104973D01*
G01X1555550Y114922D02*
Y105450D01*
G01X1554400Y104973D02*
X1555800Y103573D01*
G01X1555550Y105450D02*
X1556950Y104050D01*
G01X1555800Y103573D02*
Y102050D01*
G01X1556950Y104050D02*
Y102063D01*
G01X1556799Y156696D02*
Y150302D01*
G01X1557949Y157173D02*
Y149825D01*
G01X1556799Y150302D02*
X1554106Y147609D01*
G01X1557949Y149825D02*
X1555256Y147132D01*
G01X1554106Y147609D02*
Y145541D01*
G01X1555256Y147132D02*
Y145064D01*
G01X1553883Y145238D02*
X1549671Y141026D01*
G01X1555033Y144761D02*
X1550821Y140549D01*
G01X1549671Y141026D02*
Y138122D01*
G01X1550821Y140549D02*
Y138599D01*
G01X1549671Y138122D02*
X1551928Y135865D01*
G01X1550821Y138599D02*
X1552405Y137015D01*
G01X1551928Y135865D02*
X1554788D01*
G01X1552405Y137015D02*
X1555265D01*
G01X1554788Y135865D02*
X1555502Y135151D01*
G01X1555265Y137015D02*
X1555979Y136301D01*
G01X1554788Y135865D02*
X1555502Y135151D01*
G01D02*
X1557650D01*
G01X1555979Y136301D02*
X1557536D01*
G01X1557949Y157173D02*
Y149825D01*
G01X1556799Y156696D02*
Y150302D01*
G01X1557949Y149825D02*
X1555256Y147132D01*
G01X1556799Y150302D02*
X1554106Y147609D01*
G01X1555256Y147132D02*
Y145064D01*
G01X1554106Y147609D02*
Y145541D01*
G01X1555033Y144761D02*
X1550821Y140549D01*
G01X1553883Y145238D02*
X1549671Y141026D01*
G01X1550821Y140549D02*
Y138599D01*
G01X1549671Y141026D02*
Y138122D01*
G01X1550821Y138599D02*
X1552405Y137015D01*
G01X1549671Y138122D02*
X1551928Y135865D01*
G01X1552405Y137015D02*
X1555265D01*
G01X1551928Y135865D02*
X1554788D01*
G01X1555265Y137015D02*
X1555979Y136301D01*
G01D02*
X1557536D01*
G01X1554788Y135865D02*
X1555502Y135151D01*
G01X1555979Y136301D02*
X1557536D01*
G01X1555502Y135151D02*
X1557650D01*
G01X1572000Y158478D02*
Y160545D01*
G01X1573150Y158001D02*
Y160068D01*
G01X1572000Y160545D02*
X1579582Y168127D01*
G01X1573150Y160068D02*
X1580732Y167650D01*
G01X1579582Y168127D02*
Y172046D01*
G01X1580732Y167650D02*
Y171569D01*
G01X1579582Y172046D02*
X1587526Y179990D01*
G01X1580732Y171569D02*
X1588676Y179513D01*
G01X1587526Y179990D02*
Y184396D01*
G01X1588676Y179513D02*
Y183919D01*
G01X1587526Y184396D02*
X1589550Y186420D01*
G01X1588676Y183919D02*
X1590700Y185943D01*
G01X1590047Y178974D02*
X1582082Y171009D01*
G01X1591197Y178497D02*
X1583232Y170532D01*
G01X1582082Y171009D02*
Y167090D01*
G01X1583232Y170532D02*
Y166613D01*
G01X1582082Y167090D02*
X1574800Y159808D01*
G01X1583232Y166613D02*
X1575950Y159331D01*
G01X1574800Y159808D02*
Y157718D01*
G01X1575950Y159331D02*
Y157241D01*
G01X1593784Y177468D02*
X1585732Y169416D01*
G01X1592634Y177945D02*
X1584582Y169893D01*
G01X1585732Y169416D02*
Y165576D01*
G01X1584582Y169893D02*
Y166053D01*
G01X1585732Y165576D02*
X1581393Y161237D01*
G01X1584582Y166053D02*
X1580243Y161714D01*
G01X1573150Y158001D02*
Y160068D01*
G01X1572000Y158478D02*
Y160545D01*
G01X1573150Y160068D02*
X1580732Y167650D01*
G01X1572000Y160545D02*
X1579582Y168127D01*
G01X1580732Y167650D02*
Y171569D01*
G01X1579582Y168127D02*
Y172046D01*
G01X1580732Y171569D02*
X1588676Y179513D01*
G01X1579582Y172046D02*
X1587526Y179990D01*
G01X1588676Y179513D02*
Y183919D01*
G01X1587526Y179990D02*
Y184396D01*
G01X1588676Y183919D02*
X1590700Y185943D01*
G01X1587526Y184396D02*
X1589550Y186420D01*
G01X1591197Y178497D02*
X1583232Y170532D01*
G01X1590047Y178974D02*
X1582082Y171009D01*
G01X1583232Y170532D02*
Y166613D01*
G01X1582082Y171009D02*
Y167090D01*
G01X1583232Y166613D02*
X1575950Y159331D01*
G01X1582082Y167090D02*
X1574800Y159808D01*
G01X1575950Y159331D02*
Y157241D01*
G01X1574800Y159808D02*
Y157718D01*
G01X1592634Y177945D02*
X1584582Y169893D01*
G01X1593784Y177468D02*
X1585732Y169416D01*
G01X1584582Y169893D02*
Y166053D01*
G01X1585732Y169416D02*
Y165576D01*
G01X1584582Y166053D02*
X1580243Y161714D01*
G01X1585732Y165576D02*
X1581393Y161237D01*
G01X1536641Y157715D02*
X1540198Y161272D01*
G01X1535491Y158192D02*
X1539048Y161749D01*
G01X1540198Y161272D02*
Y171857D01*
G01X1539048Y161749D02*
Y172203D01*
G01X1540198Y171857D02*
X1540577Y172428D01*
G01X1539048Y172203D02*
X1539681Y173160D01*
G01X1540577Y172428D02*
X1553507Y185359D01*
G01X1539681Y173160D02*
X1553030Y186509D01*
G01X1553507Y185359D02*
X1558897D01*
G01X1553030Y186509D02*
X1558420D01*
G01X1558897Y185359D02*
X1565190Y191652D01*
G01X1558420Y186509D02*
X1564040Y192129D01*
G01X1565190Y191652D02*
Y206725D01*
G01X1564040Y192129D02*
Y207202D01*
G01X1565190Y206725D02*
X1586550Y228085D01*
G01X1564040Y207202D02*
X1586073Y229235D01*
G01X1591079Y198304D02*
X1585450Y192675D01*
G01X1590602Y199454D02*
X1584300Y193152D01*
G01X1585450Y192675D02*
Y180672D01*
G01X1584300Y193152D02*
Y181149D01*
G01X1585450Y180672D02*
X1577632Y172854D01*
G01X1584300Y181149D02*
X1576482Y173331D01*
G01X1577632Y172854D02*
Y168935D01*
G01X1576482Y173331D02*
Y169412D01*
G01X1577632Y168935D02*
X1569950Y161253D01*
G01X1576482Y169412D02*
X1568800Y161730D01*
G01X1569950Y161253D02*
Y159222D01*
G01X1568800Y161730D02*
Y159699D01*
G01X1590602Y199454D02*
X1584300Y193152D01*
G01X1591079Y198304D02*
X1585450Y192675D01*
G01X1584300Y193152D02*
Y181149D01*
G01X1585450Y192675D02*
Y180672D01*
G01X1584300Y181149D02*
X1576482Y173331D01*
G01X1585450Y180672D02*
X1577632Y172854D01*
G01X1576482Y173331D02*
Y169412D01*
G01X1577632Y172854D02*
Y168935D01*
G01X1576482Y169412D02*
X1568800Y161730D01*
G01X1577632Y168935D02*
X1569950Y161253D01*
G01X1568800Y161730D02*
Y159699D01*
G01X1569950Y161253D02*
Y159222D01*
G01X1568102Y225080D02*
X1554571Y204636D01*
G01X1567272Y225910D02*
X1553349Y204874D01*
G01X1554571Y204636D02*
X1555694Y199116D01*
G01X1553349Y204874D02*
X1554471Y199354D01*
G01X1555694Y199116D02*
X1552015Y193558D01*
G01X1554471Y199354D02*
X1551318Y194591D01*
G01X1552015Y193558D02*
X1546362Y192408D01*
G01X1551318Y194591D02*
X1545665Y193441D01*
G01X1546362Y192408D02*
X1533476Y172940D01*
G01X1545665Y193441D02*
X1532779Y173973D01*
G01X1567272Y225910D02*
X1553349Y204874D01*
G01X1568102Y225080D02*
X1554571Y204636D01*
G01X1553349Y204874D02*
X1554471Y199354D01*
G01X1554571Y204636D02*
X1555694Y199116D01*
G01X1554471Y199354D02*
X1551318Y194591D01*
G01X1555694Y199116D02*
X1552015Y193558D01*
G01X1551318Y194591D02*
X1545665Y193441D01*
G01X1552015Y193558D02*
X1546362Y192408D01*
G01X1545665Y193441D02*
X1532779Y173973D01*
G01X1546362Y192408D02*
X1533476Y172940D01*
G01X1564526Y228550D02*
X1549588Y205984D01*
G01X1564526Y228550D02*
X1549588Y205984D01*
G01X1565192Y227472D02*
X1550285Y204951D01*
G01X1549588Y205984D02*
X1542160Y204473D01*
G01X1550285Y204951D02*
X1542857Y203440D01*
G01X1542160Y204473D02*
X1538863Y199490D01*
G01X1542857Y203440D02*
X1540085Y199252D01*
G01X1538863Y199490D02*
X1540360Y192132D01*
G01X1540085Y199252D02*
X1541582Y191894D01*
G01X1540360Y192132D02*
X1532277Y179921D01*
G01X1541582Y191894D02*
X1532973Y178889D01*
G01X1565192Y227472D02*
X1550285Y204951D01*
G01X1564526Y228550D02*
X1549588Y205984D01*
G01X1550285Y204951D02*
X1542857Y203440D01*
G01X1549588Y205984D02*
X1542160Y204473D01*
G01X1542857Y203440D02*
X1540085Y199252D01*
G01X1542160Y204473D02*
X1538863Y199490D01*
G01X1540085Y199252D02*
X1541582Y191894D01*
G01X1538863Y199490D02*
X1540360Y192132D01*
G01X1541582Y191894D02*
X1532973Y178889D01*
G01X1540360Y192132D02*
X1532277Y179921D01*
G01X1544098Y157969D02*
X1541982Y160085D01*
G01X1545248Y158446D02*
X1543132Y160562D01*
G01X1541982Y160085D02*
Y171118D01*
G01X1543132Y160562D02*
Y170641D01*
G01X1541982Y171118D02*
X1554000Y183136D01*
G01X1543132Y170641D02*
X1554477Y181986D01*
G01X1541982Y171118D02*
X1554000Y183136D01*
G01D02*
X1554715D01*
G01X1554716Y183137D02*
X1559050D01*
G01X1554477Y181986D02*
X1554715D01*
G01X1554000Y183136D02*
X1554715D01*
G01X1554716Y183137D02*
X1559050D01*
G01X1554716Y181987D02*
X1559527D01*
G01X1559050Y183137D02*
X1567000Y191087D01*
G01X1559527Y181987D02*
X1568150Y190610D01*
G01X1567000Y191087D02*
Y206184D01*
G01X1568150Y190610D02*
Y205707D01*
G01X1567000Y206184D02*
X1583291Y222475D01*
G01X1568150Y205707D02*
X1583768Y221325D01*
G01X1547054Y171381D02*
X1555662Y179989D01*
G01X1548204Y170904D02*
X1556139Y178839D01*
G01X1555662Y179989D02*
X1560183D01*
G01X1556139Y178839D02*
X1560660D01*
G01X1560183Y179989D02*
X1569500Y189306D01*
G01X1560660Y178839D02*
X1570650Y188829D01*
G01X1569500Y189306D02*
Y202987D01*
G01X1570650Y188829D02*
Y202510D01*
G01X1569500Y202987D02*
X1580395Y213882D01*
G01X1570650Y202510D02*
X1580872Y212732D01*
G01X1580395Y213882D02*
X1587495D01*
G01X1580872Y212732D02*
X1587018D01*
G01X1587495Y213882D02*
X1589377Y212000D01*
G01X1587018Y212732D02*
X1588900Y210850D01*
G01X1545248Y158446D02*
X1543132Y160562D01*
G01X1544098Y157969D02*
X1541982Y160085D01*
G01X1543132Y160562D02*
Y170641D01*
G01X1541982Y160085D02*
Y171118D01*
G01X1543132Y170641D02*
X1554477Y181986D01*
G01D02*
X1554715D01*
G01X1541982Y171118D02*
X1554000Y183136D01*
G01X1554477Y181986D02*
X1554715D01*
G01X1554716Y181987D02*
X1559527D01*
G01X1554000Y183136D02*
X1554715D01*
G01X1554477Y181986D02*
X1554715D01*
G01X1554716Y181987D02*
X1559527D01*
G01X1554716Y183137D02*
X1559050D01*
G01X1559527Y181987D02*
X1568150Y190610D01*
G01X1559050Y183137D02*
X1567000Y191087D01*
G01X1568150Y190610D02*
Y205707D01*
G01X1567000Y191087D02*
Y206184D01*
G01X1568150Y205707D02*
X1583768Y221325D01*
G01X1567000Y206184D02*
X1583291Y222475D01*
G01X1548204Y170904D02*
X1556139Y178839D01*
G01X1547054Y171381D02*
X1555662Y179989D01*
G01X1556139Y178839D02*
X1560660D01*
G01X1555662Y179989D02*
X1560183D01*
G01X1560660Y178839D02*
X1570650Y188829D01*
G01X1560183Y179989D02*
X1569500Y189306D01*
G01X1570650Y188829D02*
Y202510D01*
G01X1569500Y189306D02*
Y202987D01*
G01X1570650Y202510D02*
X1580872Y212732D01*
G01X1569500Y202987D02*
X1580395Y213882D01*
G01X1580872Y212732D02*
X1587018D01*
G01X1580395Y213882D02*
X1587495D01*
G01X1587018Y212732D02*
X1588900Y210850D01*
G01X1587495Y213882D02*
X1589377Y212000D01*
G01X1535491Y158192D02*
X1539048Y161749D01*
G01X1536641Y157715D02*
X1540198Y161272D01*
G01X1539048Y161749D02*
Y172203D01*
G01X1540198Y161272D02*
Y171857D01*
G01X1539048Y172203D02*
X1539681Y173160D01*
G01X1540198Y171857D02*
X1540577Y172428D01*
G01X1539681Y173160D02*
X1553030Y186509D01*
G01X1540577Y172428D02*
X1553507Y185359D01*
G01X1553030Y186509D02*
X1558420D01*
G01X1553507Y185359D02*
X1558897D01*
G01X1558420Y186509D02*
X1564040Y192129D01*
G01X1558897Y185359D02*
X1565190Y191652D01*
G01X1564040Y192129D02*
Y207202D01*
G01X1565190Y191652D02*
Y206725D01*
G01X1564040Y207202D02*
X1586073Y229235D01*
G01X1565190Y206725D02*
X1586550Y228085D01*
G01X1570490Y218360D02*
X1560110Y207980D01*
G01X1585109Y231352D02*
X1561260Y207503D01*
G01X1560110Y207980D02*
Y198853D01*
G01X1561260Y207503D02*
Y198376D01*
G01X1560110Y198853D02*
X1547950Y186693D01*
G01X1561260Y198376D02*
X1549100Y186216D01*
G01X1547950Y186693D02*
Y186118D01*
G01X1549100Y186216D02*
Y185641D01*
G01X1547950Y186118D02*
X1547457Y185626D01*
G01D02*
X1537861Y176030D01*
G01X1549100Y185641D02*
X1538757Y175298D01*
G01X1537861Y176030D02*
X1534657Y171189D01*
G01X1538757Y175298D02*
X1535370Y170181D01*
G01X1534653Y171188D02*
X1533601Y169598D01*
G01X1535366Y170180D02*
X1535087Y169758D01*
G01X1534653Y171188D02*
X1533601Y169598D01*
G01X1535086Y169758D02*
X1534497Y168866D01*
G01X1533601Y169598D02*
X1529537Y165534D01*
G01X1534497Y168866D02*
X1530014Y164384D01*
G01X1585109Y231352D02*
X1561260Y207503D01*
G01X1585109Y231352D02*
X1561260Y207503D01*
G01X1585109Y231352D02*
X1561260Y207503D01*
G01X1585109Y231352D02*
X1561260Y207503D01*
G01X1570490Y218360D02*
X1560110Y207980D01*
G01X1561260Y207503D02*
Y198376D01*
G01X1560110Y207980D02*
Y198853D01*
G01X1561260Y198376D02*
X1549100Y186216D01*
G01X1560110Y198853D02*
X1547950Y186693D01*
G01X1549100Y186216D02*
Y185641D01*
G01X1547950Y186693D02*
Y186118D01*
G01X1549100Y185641D02*
X1538757Y175298D01*
G01X1547950Y186118D02*
X1547457Y185626D01*
G01X1549100Y185641D02*
X1538757Y175298D01*
G01X1547457Y185626D02*
X1537861Y176030D01*
G01X1538757Y175298D02*
X1535370Y170181D01*
G01X1537861Y176030D02*
X1534657Y171189D01*
G01X1535366Y170180D02*
X1535087Y169758D01*
G01X1535086D02*
X1534497Y168866D01*
G01X1534653Y171188D02*
X1533601Y169598D01*
G01X1534497Y168866D02*
X1530014Y164384D01*
G01X1533601Y169598D02*
X1529537Y165534D01*
G01X1596401Y175700D02*
X1588850Y168149D01*
G01X1595924Y176850D02*
X1587700Y168626D01*
G01D02*
Y164751D01*
G01X1588850Y164274D02*
X1584535Y159959D01*
G01X1587700Y164751D02*
X1583385Y160436D01*
G01X1595924Y176850D02*
X1587700Y168626D01*
G01X1596401Y175700D02*
X1588850Y168149D01*
G01X1587700Y168626D02*
Y164751D01*
G01D02*
X1583385Y160436D01*
G01X1588850Y164274D02*
X1584535Y159959D01*
G01X1550154Y166281D02*
X1554160Y170287D01*
G01X1551304Y165804D02*
X1554637Y169137D01*
G01X1554160Y170287D02*
X1560158D01*
G01X1554637Y169137D02*
X1560635D01*
G01X1560158Y170287D02*
X1563689Y173818D01*
G01X1560635Y169137D02*
X1564839Y173341D01*
G01X1563689Y173818D02*
Y176974D01*
G01X1564839Y173341D02*
Y176497D01*
G01X1563689Y176974D02*
X1565118Y178403D01*
G01X1564839Y176497D02*
X1565595Y177253D01*
G01X1563689Y176974D02*
X1565118Y178403D01*
G01D02*
X1566870D01*
G01X1565595Y177253D02*
X1567347D01*
G01X1565118Y178403D02*
X1566870D01*
G01D02*
X1568501Y180034D01*
G01X1567347Y177253D02*
X1569651Y179557D01*
G01X1568501Y180034D02*
Y182727D01*
G01X1569651Y179557D02*
Y182250D01*
G01X1568501Y182727D02*
X1572600Y186826D01*
G01X1569651Y182250D02*
X1573750Y186349D01*
G01X1572600Y186826D02*
Y200827D01*
G01X1573750Y186349D02*
Y200350D01*
G01X1572600Y200827D02*
X1582243Y210470D01*
G01X1573750Y200350D02*
X1575145Y201745D01*
G01X1572600Y200827D02*
X1582243Y210470D01*
G01X1575145Y201745D02*
X1576064D01*
G01X1572600Y200827D02*
X1582243Y210470D01*
G01X1577018Y203618D02*
X1577973Y204573D01*
G01X1572600Y200827D02*
X1582243Y210470D01*
G01X1577973Y204573D02*
X1578892D01*
G01X1572600Y200827D02*
X1582243Y210470D01*
G01X1579846Y206446D02*
X1582720Y209320D01*
G01X1582243Y210470D02*
X1585957D01*
G01X1582720Y209320D02*
X1585480D01*
G01X1585957Y210470D02*
X1587622Y208805D01*
G01X1585480Y209320D02*
X1587145Y207655D01*
G01X1587622Y208805D02*
X1594705D01*
G01X1587145Y207655D02*
X1595182D01*
G01X1551304Y165804D02*
X1554637Y169137D01*
G01X1550154Y166281D02*
X1554160Y170287D01*
G01X1554637Y169137D02*
X1560635D01*
G01X1554160Y170287D02*
X1560158D01*
G01X1560635Y169137D02*
X1564839Y173341D01*
G01X1560158Y170287D02*
X1563689Y173818D01*
G01X1564839Y173341D02*
Y176497D01*
G01X1563689Y173818D02*
Y176974D01*
G01X1564839Y176497D02*
X1565595Y177253D01*
G01D02*
X1567347D01*
G01X1563689Y176974D02*
X1565118Y178403D01*
G01X1565595Y177253D02*
X1567347D01*
G01D02*
X1569651Y179557D01*
G01X1565118Y178403D02*
X1566870D01*
G01X1567347Y177253D02*
X1569651Y179557D01*
G01X1566870Y178403D02*
X1568501Y180034D01*
G01X1569651Y179557D02*
Y182250D01*
G01X1568501Y180034D02*
Y182727D01*
G01X1569651Y182250D02*
X1573750Y186349D01*
G01X1568501Y182727D02*
X1572600Y186826D01*
G01X1573750Y186349D02*
Y200350D01*
G01X1572600Y186826D02*
Y200827D01*
G01X1573750Y200350D02*
X1575145Y201745D01*
G01D02*
X1576064D01*
G01X1577018Y203618D02*
X1577973Y204573D01*
G01D02*
X1578892D01*
G01X1579846Y206446D02*
X1582720Y209320D01*
G01X1572600Y200827D02*
X1582243Y210470D01*
G01X1582720Y209320D02*
X1585480D01*
G01X1582243Y210470D02*
X1585957D01*
G01X1585480Y209320D02*
X1587145Y207655D01*
G01X1585957Y210470D02*
X1587622Y208805D01*
G01X1587145Y207655D02*
X1595182D01*
G01X1587622Y208805D02*
X1594705D01*
G01X1597830Y201404D02*
X1588409D01*
G01X1597353Y202554D02*
X1587932D01*
G01X1588409Y201404D02*
X1579950Y192945D01*
G01X1587932Y202554D02*
X1578800Y193422D01*
G01X1579950Y192945D02*
Y179658D01*
G01X1578800Y193422D02*
Y180135D01*
G01X1579950Y179658D02*
X1565963Y165671D01*
G01X1578800Y180135D02*
X1564813Y166148D01*
G01X1565963Y165671D02*
Y159663D01*
G01X1564813Y166148D02*
Y160140D01*
G01X1597353Y202554D02*
X1587932D01*
G01X1597830Y201404D02*
X1588409D01*
G01X1587932Y202554D02*
X1578800Y193422D01*
G01X1588409Y201404D02*
X1579950Y192945D01*
G01X1578800Y193422D02*
Y180135D01*
G01X1579950Y192945D02*
Y179658D01*
G01X1578800Y180135D02*
X1564813Y166148D01*
G01X1579950Y179658D02*
X1565963Y165671D01*
G01X1564813Y166148D02*
Y160140D01*
G01X1565963Y165671D02*
Y159663D01*
G01X1595900Y205699D02*
X1586692D01*
G01X1596377Y204549D02*
X1587169D01*
G01X1586692Y205699D02*
X1575700Y194707D01*
G01X1587169Y204549D02*
X1576850Y194230D01*
G01X1575700Y194707D02*
Y181420D01*
G01X1576850Y194230D02*
Y180943D01*
G01X1575700Y181420D02*
X1555736Y161456D01*
G01X1576850Y180943D02*
X1556886Y160979D01*
G01X1555736Y161456D02*
Y157759D01*
G01X1556886Y160979D02*
Y158236D01*
G01X1555736Y157759D02*
X1556799Y156696D01*
G01X1556886Y158236D02*
X1557949Y157173D01*
G01X1596377Y204549D02*
X1587169D01*
G01X1596377D02*
X1587169D01*
G01X1595900Y205699D02*
X1586692D01*
G01X1587169Y204549D02*
X1576850Y194230D01*
G01X1586692Y205699D02*
X1575700Y194707D01*
G01X1576850Y194230D02*
Y180943D01*
G01X1575700Y194707D02*
Y181420D01*
G01X1576850Y180943D02*
X1556886Y160979D01*
G01X1575700Y181420D02*
X1555736Y161456D01*
G01X1556886Y160979D02*
Y158236D01*
G01X1555736Y161456D02*
Y157759D01*
G01X1556886Y158236D02*
X1557949Y157173D01*
G01X1555736Y157759D02*
X1556799Y156696D01*
G01X1586550Y228085D02*
X1603069D01*
G01X1586073Y229235D02*
X1602592D01*
G01X1591229Y240387D02*
X1568102Y225080D01*
G01X1590780Y241470D02*
X1567272Y225910D01*
G01X1590780Y241470D02*
X1567272Y225910D01*
G01X1591229Y240387D02*
X1568102Y225080D01*
G01X1594220Y254258D02*
X1587089Y243485D01*
G01X1595303Y253809D02*
X1587919Y242655D01*
G01X1587089Y243485D02*
X1564526Y228550D01*
G01X1587919Y242655D02*
X1565356Y227720D01*
G01D02*
X1565192Y227472D01*
G01X1595303Y253809D02*
X1587919Y242655D01*
G01X1594220Y254258D02*
X1587089Y243485D01*
G01X1587919Y242655D02*
X1565356Y227720D01*
G01X1587089Y243485D02*
X1564526Y228550D01*
G01X1565356Y227720D02*
X1565192Y227472D01*
G01X1583291Y222475D02*
X1599375D01*
G01X1583768Y221325D02*
X1599852D01*
G01X1583768D02*
X1599852D01*
G01X1583291Y222475D02*
X1599375D01*
G01X1586073Y229235D02*
X1602592D01*
G01X1586550Y228085D02*
X1603069D01*
G01X1601474Y232502D02*
X1584632D01*
G01X1601951Y231352D02*
X1585109D01*
G01X1584632Y232502D02*
X1578020Y225890D01*
G01X1576147Y224017D02*
X1575192Y223062D01*
G01X1573318Y221188D02*
X1572363Y220233D01*
G01X1601951Y231352D02*
X1585109D01*
G01X1601474Y232502D02*
X1584632D01*
G01D02*
X1578020Y225890D01*
G01X1576147Y224017D02*
X1575192Y223062D01*
G01X1573318Y221188D02*
X1572363Y220233D01*
G01X1590443Y311754D02*
X1588569Y302791D01*
G01D02*
X1589094Y299509D01*
G01D02*
X1588168Y296094D01*
G01D02*
X1588559Y294886D01*
G01X1588560Y294884D02*
X1588828Y294054D01*
G01X1590443Y311754D02*
X1588569Y302791D01*
G01D02*
X1589094Y299509D01*
G01D02*
X1588168Y296094D01*
G01D02*
X1588559Y294886D01*
G01X1588560Y294884D02*
X1588828Y294054D01*
G01X1592216Y459960D02*
X1588759Y463417D01*
G01X1591066Y459483D02*
X1587946Y462603D01*
G01X1575793Y444525D02*
Y442429D01*
G01X1576943Y444525D02*
Y442720D01*
G01X1575793Y442429D02*
X1576693Y440758D01*
G01X1576943Y442720D02*
X1577569Y441559D01*
G01X1576693Y440758D02*
X1578944Y439270D01*
G01X1577569Y441559D02*
X1579392Y440353D01*
G01X1578944Y439270D02*
X1580963Y438859D01*
G01D02*
X1580967Y438858D01*
G01D02*
X1591304Y436753D01*
G01X1579392Y440353D02*
X1591753Y437837D01*
G01X1576943Y444525D02*
Y442720D01*
G01X1575793Y444525D02*
Y442429D01*
G01X1576943Y442720D02*
X1577569Y441559D01*
G01X1575793Y442429D02*
X1576693Y440758D01*
G01X1577569Y441559D02*
X1579392Y440353D01*
G01X1576693Y440758D02*
X1578944Y439270D01*
G01X1579392Y440353D02*
X1591753Y437837D01*
G01X1578944Y439270D02*
X1580963Y438859D01*
G01X1579392Y440353D02*
X1591753Y437837D01*
G01X1580963Y438859D02*
X1580967Y438858D01*
G01X1579392Y440353D02*
X1591753Y437837D01*
G01X1580967Y438858D02*
X1591304Y436753D01*
G01X1591066Y459483D02*
X1587946Y462603D01*
G01X1592216Y459960D02*
X1588759Y463417D01*
G01X1576116Y456025D02*
X1578519Y453622D01*
G01X1576929Y456839D02*
X1577724Y456043D01*
G01X1576116Y456025D02*
X1578519Y453622D01*
G01X1577724Y456043D02*
X1579669Y454099D01*
G01X1578519Y453622D02*
Y452559D01*
G01X1579669Y454099D02*
Y453036D01*
G01X1578519Y452559D02*
X1582540Y448538D01*
G01X1579669Y453036D02*
X1583017Y449688D01*
G01X1582540Y448538D02*
X1593533D01*
G01X1583017Y449688D02*
X1594010D01*
G01X1576929Y456839D02*
X1577724Y456043D01*
G01D02*
X1579669Y454099D01*
G01X1576116Y456025D02*
X1578519Y453622D01*
G01X1579669Y454099D02*
Y453036D01*
G01X1578519Y453622D02*
Y452559D01*
G01X1579669Y453036D02*
X1583017Y449688D01*
G01X1578519Y452559D02*
X1582540Y448538D01*
G01X1583017Y449688D02*
X1594010D01*
G01X1582540Y448538D02*
X1593533D01*
G01X1618361Y484250D02*
X1584791D01*
G01X1618838Y485400D02*
X1585268D01*
G01X1584791Y484250D02*
X1572791Y496250D01*
G01X1585268Y485400D02*
X1573268Y497400D01*
G01X1572791Y496250D02*
X1566259D01*
G01X1563609D02*
X1561400D01*
G01X1573268Y497400D02*
X1561400D01*
G01X1546005Y511873D02*
Y512886D01*
G01X1544855Y511873D02*
Y513363D01*
G01X1546005Y512886D02*
X1547032Y513913D01*
G01X1544855Y513363D02*
X1546555Y515063D01*
G01X1547032Y513913D02*
X1551752D01*
G01X1554402D02*
X1557160D01*
G01X1546555Y515063D02*
X1557637D01*
G01X1557160Y513913D02*
X1560255Y510818D01*
G01X1557637Y515063D02*
X1560732Y511968D01*
G01X1560255Y510818D02*
X1572330D01*
G01X1560732Y511968D02*
X1572807D01*
G01X1572330Y510818D02*
X1577116Y506032D01*
G01X1572807Y511968D02*
X1578266Y506509D01*
G01X1577116Y506032D02*
Y505065D01*
G01Y502415D02*
Y500210D01*
G01Y497560D02*
Y496547D01*
G01X1578266Y506509D02*
Y497024D01*
G01X1577116Y496547D02*
X1586013Y487650D01*
G01X1578266Y497024D02*
X1586490Y488800D01*
G01X1586013Y487650D02*
X1590049D01*
G01X1586490Y488800D02*
X1589572D01*
G01X1548177Y517563D02*
X1558736D01*
G01X1548177Y516413D02*
X1558259D01*
G01X1558736Y517563D02*
X1561831Y514468D01*
G01X1558259Y516413D02*
X1561354Y513318D01*
G01X1561831Y514468D02*
X1573854D01*
G01X1561354Y513318D02*
X1573377D01*
G01X1573854Y514468D02*
X1586431Y501891D01*
G01X1573377Y513318D02*
X1585281Y501414D01*
G01X1586431Y501891D02*
Y495207D01*
G01X1585281Y501414D02*
Y494730D01*
G01X1586431Y495207D02*
X1588188Y493450D01*
G01X1585281Y494730D02*
X1587711Y492300D01*
G01X1588188Y493450D02*
X1592050D01*
G01X1587711Y492300D02*
X1591573D01*
G01X1618838Y485400D02*
X1585268D01*
G01X1618361Y484250D02*
X1584791D01*
G01X1585268Y485400D02*
X1573268Y497400D01*
G01X1584791Y484250D02*
X1572791Y496250D01*
G01X1573268Y497400D02*
X1561400D01*
G01X1572791Y496250D02*
X1566259D01*
G01X1573268Y497400D02*
X1561400D01*
G01X1563609Y496250D02*
X1561400D01*
G01X1544855Y511873D02*
Y513363D01*
G01X1546005Y511873D02*
Y512886D01*
G01X1544855Y513363D02*
X1546555Y515063D01*
G01X1546005Y512886D02*
X1547032Y513913D01*
G01X1546555Y515063D02*
X1557637D01*
G01X1547032Y513913D02*
X1551752D01*
G01X1546555Y515063D02*
X1557637D01*
G01X1554402Y513913D02*
X1557160D01*
G01X1557637Y515063D02*
X1560732Y511968D01*
G01X1557160Y513913D02*
X1560255Y510818D01*
G01X1560732Y511968D02*
X1572807D01*
G01X1560255Y510818D02*
X1572330D01*
G01X1572807Y511968D02*
X1578266Y506509D01*
G01X1572330Y510818D02*
X1577116Y506032D01*
G01X1578266Y506509D02*
Y497024D01*
G01X1577116Y506032D02*
Y505065D01*
G01X1578266Y506509D02*
Y497024D01*
G01X1577116Y502415D02*
Y500210D01*
G01X1578266Y506509D02*
Y497024D01*
G01X1577116Y497560D02*
Y496547D01*
G01X1578266Y497024D02*
X1586490Y488800D01*
G01X1577116Y496547D02*
X1586013Y487650D01*
G01X1586490Y488800D02*
X1589572D01*
G01X1586013Y487650D02*
X1590049D01*
G01X1548177Y516413D02*
X1558259D01*
G01X1548177Y517563D02*
X1558736D01*
G01X1558259Y516413D02*
X1561354Y513318D01*
G01X1558736Y517563D02*
X1561831Y514468D01*
G01X1561354Y513318D02*
X1573377D01*
G01X1561831Y514468D02*
X1573854D01*
G01X1573377Y513318D02*
X1585281Y501414D01*
G01X1573854Y514468D02*
X1586431Y501891D01*
G01X1585281Y501414D02*
Y494730D01*
G01X1586431Y501891D02*
Y495207D01*
G01X1585281Y494730D02*
X1587711Y492300D01*
G01X1586431Y495207D02*
X1588188Y493450D01*
G01X1587711Y492300D02*
X1591573D01*
G01X1588188Y493450D02*
X1592050D01*
G01X1560517Y492507D02*
X1573751D01*
G01X1560517Y491357D02*
X1573274D01*
G01X1573751Y492507D02*
X1583958Y482300D01*
G01X1573274Y491357D02*
X1583481Y481150D01*
G01X1583958Y482300D02*
X1611444D01*
G01X1583481Y481150D02*
X1605229D01*
G01X1583958Y482300D02*
X1611444D01*
G01X1560517Y491357D02*
X1573274D01*
G01X1560517Y492507D02*
X1573751D01*
G01X1573274Y491357D02*
X1583481Y481150D01*
G01X1573751Y492507D02*
X1583958Y482300D01*
G01X1583481Y481150D02*
X1605229D01*
G01X1583958Y482300D02*
X1611444D01*
G01X1594626Y468687D02*
X1586693D01*
G01X1595103Y469837D02*
X1586693D01*
G01X1595103D02*
X1586693D01*
G01X1594626Y468687D02*
X1586693D01*
G01X1562601Y526263D02*
X1538705D01*
G01X1539182Y525113D02*
X1562124D01*
G01X1565524Y523340D02*
X1562601Y526263D01*
G01X1562124Y525113D02*
X1565047Y522190D01*
G01X1577379Y523340D02*
X1565524D01*
G01X1565047Y522190D02*
X1576902D01*
G01X1592769Y507950D02*
X1577379Y523340D01*
G01X1576902Y522190D02*
X1592292Y506800D01*
G01X1576902Y522190D02*
X1592292Y506800D01*
G01X1592769Y507950D02*
X1577379Y523340D01*
G01X1565047Y522190D02*
X1576902D01*
G01X1577379Y523340D02*
X1565524D01*
G01X1562124Y525113D02*
X1565047Y522190D01*
G01X1565524Y523340D02*
X1562601Y526263D01*
G01X1539182Y525113D02*
X1562124D01*
G01X1562601Y526263D02*
X1538705D01*
G01X1591662Y505450D02*
X1576444Y520668D01*
G01X1591185Y504300D02*
X1575967Y519518D01*
G01X1576444Y520668D02*
X1564658D01*
G01X1575967Y519518D02*
X1564181D01*
G01X1564658Y520668D02*
X1561563Y523763D01*
G01X1564181Y519518D02*
X1561086Y522613D01*
G01X1561563Y523763D02*
X1539826D01*
G01X1561086Y522613D02*
X1540303D01*
G01X1591185Y504300D02*
X1575967Y519518D01*
G01X1591662Y505450D02*
X1576444Y520668D01*
G01X1575967Y519518D02*
X1564181D01*
G01X1576444Y520668D02*
X1564658D01*
G01X1564181Y519518D02*
X1561086Y522613D01*
G01X1564658Y520668D02*
X1561563Y523763D01*
G01X1561086Y522613D02*
X1540303D01*
G01X1561563Y523763D02*
X1539826D01*
G01X1531123Y501478D02*
X1529438D01*
G01X1530897Y500328D02*
X1529915D01*
G01X1529438Y501478D02*
X1528315Y500355D01*
G01X1529915Y500328D02*
X1529465Y499878D01*
G01X1528315Y500355D02*
Y497231D01*
G01X1529465Y499878D02*
Y497708D01*
G01X1528315Y497231D02*
X1530046Y495500D01*
G01X1529465Y497708D02*
X1530523Y496650D01*
G01X1530046Y495500D02*
X1535472D01*
G01X1530523Y496650D02*
X1534995D01*
G01X1535472Y495500D02*
X1537558Y497586D01*
G01X1534995Y496650D02*
X1536408Y498063D01*
G01X1537558Y497586D02*
Y514760D01*
G01X1536408Y498063D02*
Y515237D01*
G01X1537558Y514760D02*
X1542311Y519513D01*
G01X1536408Y515237D02*
X1541834Y520663D01*
G01X1542311Y519513D02*
X1559723D01*
G01X1541834Y520663D02*
X1560200D01*
G01X1559723Y519513D02*
X1562818Y516418D01*
G01X1560200Y520663D02*
X1563295Y517568D01*
G01X1562818Y516418D02*
X1574672D01*
G01X1563295Y517568D02*
X1575149D01*
G01X1574672Y516418D02*
X1589890Y501200D01*
G01X1575149Y517568D02*
X1590367Y502350D01*
G01X1530897Y500328D02*
X1529915D01*
G01X1531123Y501478D02*
X1529438D01*
G01X1529915Y500328D02*
X1529465Y499878D01*
G01X1529438Y501478D02*
X1528315Y500355D01*
G01X1529465Y499878D02*
Y497708D01*
G01X1528315Y500355D02*
Y497231D01*
G01X1529465Y497708D02*
X1530523Y496650D01*
G01X1528315Y497231D02*
X1530046Y495500D01*
G01X1530523Y496650D02*
X1534995D01*
G01X1530046Y495500D02*
X1535472D01*
G01X1534995Y496650D02*
X1536408Y498063D01*
G01X1535472Y495500D02*
X1537558Y497586D01*
G01X1536408Y498063D02*
Y515237D01*
G01X1537558Y497586D02*
Y514760D01*
G01X1536408Y515237D02*
X1541834Y520663D01*
G01X1537558Y514760D02*
X1542311Y519513D01*
G01X1541834Y520663D02*
X1560200D01*
G01X1542311Y519513D02*
X1559723D01*
G01X1560200Y520663D02*
X1563295Y517568D01*
G01X1559723Y519513D02*
X1562818Y516418D01*
G01X1563295Y517568D02*
X1575149D01*
G01X1562818Y516418D02*
X1574672D01*
G01X1575149Y517568D02*
X1590367Y502350D01*
G01X1574672Y516418D02*
X1589890Y501200D01*
G01X1527138Y543465D02*
X1538215D01*
G01D02*
X1552477Y547350D01*
G01X1538061Y544615D02*
X1552427Y548529D01*
G01X1552477Y547350D02*
X1572988Y543603D01*
G01X1552427Y548529D02*
X1573093Y544753D01*
G01X1572988Y543603D02*
X1595540D01*
G01X1573093Y544753D02*
X1595652D01*
G01X1537880Y545965D02*
X1552368Y549913D01*
G01X1537726Y547115D02*
X1552318Y551092D01*
G01X1552368Y549913D02*
X1573185Y546109D01*
G01X1552318Y551092D02*
X1573290Y547259D01*
G01X1573185Y546109D02*
X1595782D01*
G01X1573290Y547259D02*
X1595897D01*
G01X1536870Y553494D02*
X1552040Y557631D01*
G01X1536715Y554644D02*
X1551990Y558810D01*
G01X1552040Y557631D02*
X1573936Y553628D01*
G01X1551990Y558810D02*
X1574041Y554778D01*
G01X1573936Y553628D02*
X1596510D01*
G01X1574041Y554778D02*
X1596620D01*
G01X1596699Y557317D02*
X1574169D01*
G01X1596587Y556167D02*
X1574064D01*
G01X1574169Y557317D02*
X1551880Y561393D01*
G01X1574064Y556167D02*
X1551930Y560214D01*
G01X1551880Y561393D02*
X1536376Y557164D01*
G01X1551930Y560214D02*
X1536531Y556014D01*
G01X1530818Y565056D02*
X1536491Y567705D01*
G01X1530562Y566206D02*
X1535694Y568603D01*
G01X1536491Y567705D02*
X1538164Y570402D01*
G01X1535694Y568603D02*
X1537376Y571314D01*
G01X1538164Y570402D02*
X1541221Y571729D01*
G01X1537376Y571314D02*
X1540915Y572850D01*
G01X1541221Y571729D02*
X1553193Y573210D01*
G01X1540915Y572850D02*
X1552736Y574313D01*
G01X1553193Y573210D02*
X1560376Y578812D01*
G01X1552736Y574313D02*
X1559668Y579719D01*
G01X1560376Y578812D02*
X1563247Y579396D01*
G01X1560146Y579939D02*
X1563255Y580572D01*
G01X1563247Y579396D02*
X1588796Y573832D01*
G01X1563255Y580572D02*
X1588807Y575007D01*
G01X1588796Y573832D02*
X1599914Y576042D01*
G01X1588807Y575007D02*
X1600030Y577239D01*
G01X1529605Y568714D02*
X1534077Y570801D01*
G01X1529861Y567564D02*
X1534874Y569903D01*
G01X1534077Y570801D02*
X1536132Y574115D01*
G01X1534874Y569903D02*
X1536920Y573203D01*
G01X1536132Y574115D02*
X1539940Y575766D01*
G01X1536920Y573203D02*
X1540179Y574616D01*
G01X1536132Y574115D02*
X1539940Y575766D01*
G01X1540109D02*
X1552500Y577301D01*
G01X1540179Y574616D02*
X1540180D01*
G01X1539940Y575766D02*
X1540109D01*
G01D02*
X1552500Y577301D01*
G01X1540180Y574616D02*
X1552957Y576198D01*
G01X1552500Y577301D02*
X1558359Y581869D01*
G01X1552957Y576198D02*
X1558961Y580880D01*
G01X1558359Y581869D02*
X1559364Y582332D01*
G01X1558961Y580880D02*
X1559724Y581231D01*
G01X1559364Y582332D02*
X1563369Y583147D01*
G01X1559724Y581231D02*
X1563368Y581973D01*
G01X1563369Y583147D02*
X1572640Y581248D01*
G01X1563368Y581973D02*
X1572637Y580074D01*
G01X1572640Y581248D02*
X1586150Y583950D01*
G01X1572637Y580074D02*
X1586150Y582777D01*
G01Y583950D02*
X1591735Y582833D01*
G01X1586150Y582777D02*
X1591852Y581636D01*
G01X1537209Y550965D02*
X1552150Y555039D01*
G01X1537055Y552115D02*
X1552100Y556218D01*
G01X1552150Y555039D02*
X1573574Y551122D01*
G01X1552100Y556218D02*
X1573679Y552272D01*
G01X1573574Y551122D02*
X1596266D01*
G01X1573679Y552272D02*
X1596381D01*
G01X1537545Y548465D02*
X1552259Y552476D01*
G01X1537391Y549615D02*
X1552209Y553655D01*
G01X1552259Y552476D02*
X1573382Y548615D01*
G01X1552209Y553655D02*
X1573487Y549765D01*
G01X1573382Y548615D02*
X1596027D01*
G01X1573487Y549765D02*
X1596141D01*
G01X1527138Y543465D02*
X1538215D01*
G01X1538061Y544615D02*
X1552427Y548529D01*
G01X1538215Y543465D02*
X1552477Y547350D01*
G01X1552427Y548529D02*
X1573093Y544753D01*
G01X1552477Y547350D02*
X1572988Y543603D01*
G01X1573093Y544753D02*
X1595652D01*
G01X1572988Y543603D02*
X1595540D01*
G01X1537726Y547115D02*
X1552318Y551092D01*
G01X1537880Y545965D02*
X1552368Y549913D01*
G01X1552318Y551092D02*
X1573290Y547259D01*
G01X1552368Y549913D02*
X1573185Y546109D01*
G01X1573290Y547259D02*
X1595897D01*
G01X1573185Y546109D02*
X1595782D01*
G01X1536715Y554644D02*
X1551990Y558810D01*
G01X1536870Y553494D02*
X1552040Y557631D01*
G01X1551990Y558810D02*
X1574041Y554778D01*
G01X1552040Y557631D02*
X1573936Y553628D01*
G01X1574041Y554778D02*
X1596620D01*
G01X1573936Y553628D02*
X1596510D01*
G01X1596587Y556167D02*
X1574064D01*
G01X1596699Y557317D02*
X1574169D01*
G01X1574064Y556167D02*
X1551930Y560214D01*
G01X1574169Y557317D02*
X1551880Y561393D01*
G01X1551930Y560214D02*
X1536531Y556014D01*
G01X1551880Y561393D02*
X1536376Y557164D01*
G01X1530562Y566206D02*
X1535694Y568603D01*
G01X1530818Y565056D02*
X1536491Y567705D01*
G01X1535694Y568603D02*
X1537376Y571314D01*
G01X1536491Y567705D02*
X1538164Y570402D01*
G01X1537376Y571314D02*
X1540915Y572850D01*
G01X1538164Y570402D02*
X1541221Y571729D01*
G01X1540915Y572850D02*
X1552736Y574313D01*
G01X1541221Y571729D02*
X1553193Y573210D01*
G01X1552736Y574313D02*
X1559668Y579719D01*
G01X1553193Y573210D02*
X1560376Y578812D01*
G01X1560146Y579939D02*
X1563255Y580572D01*
G01X1560376Y578812D02*
X1563247Y579396D01*
G01X1563255Y580572D02*
X1588807Y575007D01*
G01X1563247Y579396D02*
X1588796Y573832D01*
G01X1588807Y575007D02*
X1600030Y577239D01*
G01X1588796Y573832D02*
X1599914Y576042D01*
G01X1529861Y567564D02*
X1534874Y569903D01*
G01X1529605Y568714D02*
X1534077Y570801D01*
G01X1534874Y569903D02*
X1536920Y573203D01*
G01X1534077Y570801D02*
X1536132Y574115D01*
G01X1536920Y573203D02*
X1540179Y574616D01*
G01D02*
X1540180D01*
G01X1536132Y574115D02*
X1539940Y575766D01*
G01X1540180Y574616D02*
X1552957Y576198D01*
G01X1539940Y575766D02*
X1540109D01*
G01X1540179Y574616D02*
X1540180D01*
G01D02*
X1552957Y576198D01*
G01X1540109Y575766D02*
X1552500Y577301D01*
G01X1552957Y576198D02*
X1558961Y580880D01*
G01X1552500Y577301D02*
X1558359Y581869D01*
G01X1558961Y580880D02*
X1559724Y581231D01*
G01X1558359Y581869D02*
X1559364Y582332D01*
G01X1559724Y581231D02*
X1563368Y581973D01*
G01X1559364Y582332D02*
X1563369Y583147D01*
G01X1563368Y581973D02*
X1572637Y580074D01*
G01X1563369Y583147D02*
X1572640Y581248D01*
G01X1572637Y580074D02*
X1586150Y582777D01*
G01X1572640Y581248D02*
X1586150Y583950D01*
G01Y582777D02*
X1591852Y581636D01*
G01X1586150Y583950D02*
X1591735Y582833D01*
G01X1537055Y552115D02*
X1552100Y556218D01*
G01X1537209Y550965D02*
X1552150Y555039D01*
G01X1552100Y556218D02*
X1573679Y552272D01*
G01X1552150Y555039D02*
X1573574Y551122D01*
G01X1573679Y552272D02*
X1596381D01*
G01X1573574Y551122D02*
X1596266D01*
G01X1537391Y549615D02*
X1552209Y553655D01*
G01X1537545Y548465D02*
X1552259Y552476D01*
G01X1552209Y553655D02*
X1573487Y549765D01*
G01X1552259Y552476D02*
X1573382Y548615D01*
G01X1573487Y549765D02*
X1596141D01*
G01X1573382Y548615D02*
X1596027D01*
G01X1592559Y66690D02*
X1598174D01*
G01D02*
X1600824Y64040D01*
G01X1597697Y65540D02*
X1600347Y62890D01*
G01X1600824Y64040D02*
X1605888D01*
G01X1600347Y62890D02*
X1608452D01*
G01X1592559Y66690D02*
X1598174D01*
G01X1597697Y65540D02*
X1600347Y62890D01*
G01X1598174Y66690D02*
X1600824Y64040D01*
G01X1600347Y62890D02*
X1608452D01*
G01X1600824Y64040D02*
X1605888D01*
G01X1589550Y186420D02*
Y192918D01*
G01X1590700Y185943D02*
Y192441D01*
G01X1589550Y192918D02*
X1592584Y195952D01*
G01X1590700Y192441D02*
X1593061Y194802D01*
G01X1592584Y195952D02*
X1599521D01*
G01X1593061Y194802D02*
X1599998D01*
G01X1599521Y195952D02*
X1604469Y200900D01*
G01X1599998Y194802D02*
X1604946Y199750D01*
G01X1604469Y200900D02*
X1615552D01*
G01X1604946Y199750D02*
X1616029D01*
G01X1615552Y200900D02*
X1627068Y212416D01*
G01X1616029Y199750D02*
X1627545Y211266D01*
G01X1627068Y212416D02*
X1629636D01*
G01X1627545Y211266D02*
X1629159D01*
G01X1629637Y212415D02*
X1631251D01*
G01X1629160Y211265D02*
X1631728D01*
G01X1631251Y212415D02*
X1648850Y230014D01*
G01X1631728Y211265D02*
X1650000Y229537D01*
G01X1651350Y228977D02*
X1632186Y209813D01*
G01X1652500Y228500D02*
X1632663Y208663D01*
G01X1632186Y209813D02*
X1628002D01*
G01X1632663Y208663D02*
X1628479D01*
G01X1628002Y209813D02*
X1612565Y194376D01*
G01X1628479Y208663D02*
X1613042Y193226D01*
G01X1612565Y194376D02*
X1603507D01*
G01X1613042Y193226D02*
X1603984D01*
G01X1603507Y194376D02*
X1598106Y188975D01*
G01X1603984Y193226D02*
X1598583Y187825D01*
G01X1598106Y188975D02*
X1595837D01*
G01X1598583Y187825D02*
X1596314D01*
G01X1595837Y188975D02*
X1590047Y183185D01*
G01X1596314Y187825D02*
X1591197Y182708D01*
G01X1590047Y183185D02*
Y178974D01*
G01X1591197Y182708D02*
Y178497D01*
G01X1655000Y227073D02*
X1642900Y214973D01*
G01X1653850Y227550D02*
X1641750Y215450D01*
G01X1642900Y214973D02*
Y209673D01*
G01X1641750Y215450D02*
Y210150D01*
G01X1642900Y209673D02*
X1637877Y204650D01*
G01X1641750Y210150D02*
X1637400Y205800D01*
G01X1637877Y204650D02*
X1629743D01*
G01X1637400Y205800D02*
X1629266D01*
G01X1629743Y204650D02*
X1622872Y197779D01*
G01X1629266Y205800D02*
X1621722Y198256D01*
G01X1622872Y197779D02*
Y192672D01*
G01X1621722Y198256D02*
Y193149D01*
G01X1622872Y192672D02*
X1620600Y190400D01*
G01X1621722Y193149D02*
X1620123Y191550D01*
G01X1620600Y190400D02*
X1604695D01*
G01X1620123Y191550D02*
X1604218D01*
G01X1604695Y190400D02*
X1599620Y185325D01*
G01X1604218Y191550D02*
X1599143Y186475D01*
G01X1599620Y185325D02*
X1597351D01*
G01X1599143Y186475D02*
X1596874D01*
G01X1597351Y185325D02*
X1593784Y181758D01*
G01X1596874Y186475D02*
X1592634Y182235D01*
G01X1593784Y181758D02*
Y177468D01*
G01X1592634Y182235D02*
Y177945D01*
G01X1590700Y185943D02*
Y192441D01*
G01X1589550Y186420D02*
Y192918D01*
G01X1590700Y192441D02*
X1593061Y194802D01*
G01X1589550Y192918D02*
X1592584Y195952D01*
G01X1593061Y194802D02*
X1599998D01*
G01X1592584Y195952D02*
X1599521D01*
G01X1599998Y194802D02*
X1604946Y199750D01*
G01X1599521Y195952D02*
X1604469Y200900D01*
G01X1604946Y199750D02*
X1616029D01*
G01X1604469Y200900D02*
X1615552D01*
G01X1616029Y199750D02*
X1627545Y211266D01*
G01X1615552Y200900D02*
X1627068Y212416D01*
G01X1627545Y211266D02*
X1629159D01*
G01X1627068Y212416D02*
X1629636D01*
G01X1629160Y211265D02*
X1631728D01*
G01X1629637Y212415D02*
X1631251D01*
G01X1631728Y211265D02*
X1650000Y229537D01*
G01X1631251Y212415D02*
X1648850Y230014D01*
G01X1652500Y228500D02*
X1632663Y208663D01*
G01X1651350Y228977D02*
X1632186Y209813D01*
G01X1632663Y208663D02*
X1628479D01*
G01X1632186Y209813D02*
X1628002D01*
G01X1628479Y208663D02*
X1613042Y193226D01*
G01X1628002Y209813D02*
X1612565Y194376D01*
G01X1613042Y193226D02*
X1603984D01*
G01X1612565Y194376D02*
X1603507D01*
G01X1603984Y193226D02*
X1598583Y187825D01*
G01X1603507Y194376D02*
X1598106Y188975D01*
G01X1598583Y187825D02*
X1596314D01*
G01X1598106Y188975D02*
X1595837D01*
G01X1596314Y187825D02*
X1591197Y182708D01*
G01X1595837Y188975D02*
X1590047Y183185D01*
G01X1591197Y182708D02*
Y178497D01*
G01X1590047Y183185D02*
Y178974D01*
G01X1653850Y227550D02*
X1641750Y215450D01*
G01X1655000Y227073D02*
X1642900Y214973D01*
G01X1641750Y215450D02*
Y210150D01*
G01X1642900Y214973D02*
Y209673D01*
G01X1641750Y210150D02*
X1637400Y205800D01*
G01X1642900Y209673D02*
X1637877Y204650D01*
G01X1637400Y205800D02*
X1629266D01*
G01X1637877Y204650D02*
X1629743D01*
G01X1629266Y205800D02*
X1621722Y198256D01*
G01X1629743Y204650D02*
X1622872Y197779D01*
G01X1621722Y198256D02*
Y193149D01*
G01X1622872Y197779D02*
Y192672D01*
G01X1621722Y193149D02*
X1620123Y191550D01*
G01X1622872Y192672D02*
X1620600Y190400D01*
G01X1620123Y191550D02*
X1604218D01*
G01X1620600Y190400D02*
X1604695D01*
G01X1604218Y191550D02*
X1599143Y186475D01*
G01X1604695Y190400D02*
X1599620Y185325D01*
G01X1599143Y186475D02*
X1596874D01*
G01X1599620Y185325D02*
X1597351D01*
G01X1596874Y186475D02*
X1592634Y182235D01*
G01X1597351Y185325D02*
X1593784Y181758D01*
G01X1592634Y182235D02*
Y177945D01*
G01X1593784Y181758D02*
Y177468D01*
G01X1646900Y230822D02*
X1630444Y214366D01*
G01X1645750Y231299D02*
X1629967Y215516D01*
G01X1630444Y214366D02*
X1626260D01*
G01X1629967Y215516D02*
X1625783D01*
G01X1626260Y214366D02*
X1614744Y202850D01*
G01X1625783Y215516D02*
X1614267Y204000D01*
G01X1614744Y202850D02*
X1603661D01*
G01X1614267Y204000D02*
X1603184D01*
G01X1603661Y202850D02*
X1599115Y198304D01*
G01X1603184Y204000D02*
X1598638Y199454D01*
G01X1599115Y198304D02*
X1591079D01*
G01X1598638Y199454D02*
X1590602D01*
G01X1645750Y231299D02*
X1629967Y215516D01*
G01X1646900Y230822D02*
X1630444Y214366D01*
G01X1629967Y215516D02*
X1625783D01*
G01X1630444Y214366D02*
X1626260D01*
G01X1625783Y215516D02*
X1614267Y204000D01*
G01X1626260Y214366D02*
X1614744Y202850D01*
G01X1614267Y204000D02*
X1603184D01*
G01X1614744Y202850D02*
X1603661D01*
G01X1603184Y204000D02*
X1598638Y199454D01*
G01X1603661Y202850D02*
X1599115Y198304D01*
G01X1598638Y199454D02*
X1590602D01*
G01X1599115Y198304D02*
X1591079D01*
G01X1589377Y212000D02*
X1592699D01*
G01X1588900Y210850D02*
X1593176D01*
G01X1592699Y212000D02*
X1619710Y239011D01*
G01X1593176Y210850D02*
X1620860Y238534D01*
G01X1588900Y210850D02*
X1593176D01*
G01X1589377Y212000D02*
X1592699D01*
G01X1593176Y210850D02*
X1620860Y238534D01*
G01X1592699Y212000D02*
X1619710Y239011D01*
G01X1620214Y185658D02*
Y186764D01*
G01X1621364Y185944D02*
Y187241D01*
G01X1620214Y186764D02*
X1619789Y187189D01*
G01X1621364Y187241D02*
X1620266Y188339D01*
G01X1619789Y187189D02*
X1607879D01*
G01X1620266Y188339D02*
X1607402D01*
G01X1607879Y187189D02*
X1606180Y185490D01*
G01X1607402Y188339D02*
X1605030Y185967D01*
G01X1606180Y185490D02*
Y183479D01*
G01X1605030Y185967D02*
Y183956D01*
G01X1606180Y183479D02*
X1605480Y182779D01*
G01X1605030Y183956D02*
X1604330Y183256D01*
G01X1605480Y182779D02*
Y179235D01*
G01X1604330Y183256D02*
Y179712D01*
G01X1605480Y179235D02*
X1601945Y175700D01*
G01X1604330Y179712D02*
X1601468Y176850D01*
G01X1601945Y175700D02*
X1596401D01*
G01X1601468Y176850D02*
X1595924D01*
G01X1588850Y168149D02*
Y164274D01*
G01X1621364Y185944D02*
Y187241D01*
G01X1620214Y185658D02*
Y186764D01*
G01X1621364Y187241D02*
X1620266Y188339D01*
G01X1620214Y186764D02*
X1619789Y187189D01*
G01X1620266Y188339D02*
X1607402D01*
G01X1619789Y187189D02*
X1607879D01*
G01X1607402Y188339D02*
X1605030Y185967D01*
G01X1607879Y187189D02*
X1606180Y185490D01*
G01X1605030Y185967D02*
Y183956D01*
G01X1606180Y185490D02*
Y183479D01*
G01X1605030Y183956D02*
X1604330Y183256D01*
G01X1606180Y183479D02*
X1605480Y182779D01*
G01X1604330Y183256D02*
Y179712D01*
G01X1605480Y182779D02*
Y179235D01*
G01X1604330Y179712D02*
X1601468Y176850D01*
G01X1605480Y179235D02*
X1601945Y175700D01*
G01X1601468Y176850D02*
X1595924D01*
G01X1601945Y175700D02*
X1596401D01*
G01X1588850Y168149D02*
Y164274D01*
G01X1594705Y208805D02*
X1619350Y233450D01*
G01X1595182Y207655D02*
X1619827Y232300D01*
G01X1595182Y207655D02*
X1619827Y232300D01*
G01X1594705Y208805D02*
X1619350Y233450D01*
G01X1624929Y219421D02*
Y217421D01*
G01D02*
X1613459Y205950D01*
G01X1623779Y217898D02*
X1612982Y207100D01*
G01X1613459Y205950D02*
X1602376D01*
G01X1612982Y207100D02*
X1601899D01*
G01X1602376Y205950D02*
X1597830Y201404D01*
G01X1601899Y207100D02*
X1597353Y202554D01*
G01X1624929Y219421D02*
Y217421D01*
G01X1623779Y217898D02*
X1612982Y207100D01*
G01X1624929Y217421D02*
X1613459Y205950D01*
G01X1612982Y207100D02*
X1601899D01*
G01X1613459Y205950D02*
X1602376D01*
G01X1601899Y207100D02*
X1597353Y202554D01*
G01X1602376Y205950D02*
X1597830Y201404D01*
G01X1620499Y230000D02*
X1608150Y217651D01*
G01X1620976Y228850D02*
X1609300Y217174D01*
G01X1608150Y217651D02*
Y213701D01*
G01X1609300Y217174D02*
Y213224D01*
G01X1608150Y213701D02*
X1604766Y210317D01*
G01X1609300Y213224D02*
X1605243Y209167D01*
G01X1604766Y210317D02*
X1600602D01*
G01X1605243Y209167D02*
X1601079D01*
G01X1600602Y210317D02*
X1595990Y205705D01*
G01D02*
X1595906D01*
G01X1601079Y209167D02*
X1596467Y204555D01*
G01X1595990Y205705D02*
X1595906D01*
G01X1620976Y228850D02*
X1609300Y217174D01*
G01X1620499Y230000D02*
X1608150Y217651D01*
G01X1609300Y217174D02*
Y213224D01*
G01X1608150Y217651D02*
Y213701D01*
G01X1609300Y213224D02*
X1605243Y209167D01*
G01X1608150Y213701D02*
X1604766Y210317D01*
G01X1605243Y209167D02*
X1601079D01*
G01X1604766Y210317D02*
X1600602D01*
G01X1601079Y209167D02*
X1596467Y204555D01*
G01X1600602Y210317D02*
X1595990Y205705D01*
G01X1601079Y209167D02*
X1596467Y204555D01*
G01X1595990Y205705D02*
X1595906D01*
G01X1650152Y206571D02*
X1649197Y205616D01*
G01X1647324Y203743D02*
X1646369Y202788D01*
G01X1644496Y200915D02*
X1643541Y199960D01*
G01X1641668Y198087D02*
X1640713Y197132D01*
G01X1657328Y212120D02*
X1641863Y196655D01*
G01X1640713Y197132D02*
Y194560D01*
G01X1641863Y196655D02*
Y194083D01*
G01X1640713Y194560D02*
X1638953Y192800D01*
G01X1641863Y194083D02*
X1639430Y191650D01*
G01X1638953Y192800D02*
X1632007D01*
G01X1639430Y191650D02*
X1631530D01*
G01X1632007Y192800D02*
X1631345Y193462D01*
G01X1631530Y191650D02*
X1630195Y192985D01*
G01X1631345Y193462D02*
Y194099D01*
G01X1630195Y192985D02*
Y194099D01*
G01X1657328Y212120D02*
X1641863Y196655D01*
G01X1657328Y212120D02*
X1641863Y196655D01*
G01X1650152Y206571D02*
X1649197Y205616D01*
G01X1657328Y212120D02*
X1641863Y196655D01*
G01X1647324Y203743D02*
X1646369Y202788D01*
G01X1657328Y212120D02*
X1641863Y196655D01*
G01X1644496Y200915D02*
X1643541Y199960D01*
G01X1657328Y212120D02*
X1641863Y196655D01*
G01X1641668Y198087D02*
X1640713Y197132D01*
G01X1641863Y196655D02*
Y194083D01*
G01X1640713Y197132D02*
Y194560D01*
G01X1641863Y194083D02*
X1639430Y191650D01*
G01X1640713Y194560D02*
X1638953Y192800D01*
G01X1639430Y191650D02*
X1631530D01*
G01X1638953Y192800D02*
X1632007D01*
G01X1631530Y191650D02*
X1630195Y192985D01*
G01X1632007Y192800D02*
X1631345Y193462D01*
G01X1630195Y192985D02*
Y194099D01*
G01X1631345Y193462D02*
Y194099D01*
G01X1638000Y184362D02*
Y181700D01*
G01X1636850Y183945D02*
Y182177D01*
G01X1638000Y181700D02*
X1636118Y179818D01*
G01X1636850Y182177D02*
X1635641Y180968D01*
G01X1636118Y179818D02*
X1633808D01*
G01D02*
X1631089Y182537D01*
G01X1635641Y180968D02*
X1634285D01*
G01X1633808Y179818D02*
X1631089Y182537D01*
G01X1634285Y180968D02*
X1632239Y183014D01*
G01X1631089Y182537D02*
Y186905D01*
G01X1632239Y183014D02*
Y187382D01*
G01X1631089Y186905D02*
X1624829Y193165D01*
G01X1632239Y187382D02*
X1625979Y193642D01*
G01X1624829Y193165D02*
Y196978D01*
G01X1625979Y193642D02*
Y196501D01*
G01X1624829Y196978D02*
X1630401Y202550D01*
G01X1625979Y196501D02*
X1630878Y201400D01*
G01X1630401Y202550D02*
X1639387D01*
G01X1630878Y201400D02*
X1639864D01*
G01X1639387Y202550D02*
X1650100Y213263D01*
G01X1639864Y201400D02*
X1651250Y212786D01*
G01X1650100Y213263D02*
Y219415D01*
G01X1636850Y183945D02*
Y182177D01*
G01X1638000Y184362D02*
Y181700D01*
G01X1636850Y182177D02*
X1635641Y180968D01*
G01X1638000Y181700D02*
X1636118Y179818D01*
G01X1635641Y180968D02*
X1634285D01*
G01X1636118Y179818D02*
X1633808D01*
G01X1635641Y180968D02*
X1634285D01*
G01D02*
X1632239Y183014D01*
G01X1633808Y179818D02*
X1631089Y182537D01*
G01X1632239Y183014D02*
Y187382D01*
G01X1631089Y182537D02*
Y186905D01*
G01X1632239Y187382D02*
X1625979Y193642D01*
G01X1631089Y186905D02*
X1624829Y193165D01*
G01X1625979Y193642D02*
Y196501D01*
G01X1624829Y193165D02*
Y196978D01*
G01X1625979Y196501D02*
X1630878Y201400D01*
G01X1624829Y196978D02*
X1630401Y202550D01*
G01X1630878Y201400D02*
X1639864D01*
G01X1630401Y202550D02*
X1639387D01*
G01X1639864Y201400D02*
X1651250Y212786D01*
G01X1639387Y202550D02*
X1650100Y213263D01*
G01D02*
Y219415D01*
G01X1648850Y230014D02*
Y274576D01*
G01X1650000Y229537D02*
Y274099D01*
G01X1648850Y274576D02*
X1651247Y276973D01*
G01X1650000Y274099D02*
X1652397Y276496D01*
G01X1650000Y229537D02*
Y274099D01*
G01X1648850Y230014D02*
Y274576D01*
G01X1650000Y274099D02*
X1652397Y276496D01*
G01X1648850Y274576D02*
X1651247Y276973D01*
G01X1603069Y228085D02*
X1615450Y240466D01*
G01X1602592Y229235D02*
X1614300Y240943D01*
G01X1615450Y240466D02*
Y261533D01*
G01X1614300Y240943D02*
Y262010D01*
G01X1615450Y261533D02*
X1616900Y262983D01*
G01X1614300Y262010D02*
X1615750Y263460D01*
G01X1616900Y262983D02*
Y270149D01*
G01X1615750Y263460D02*
Y269672D01*
G01X1616900Y270149D02*
X1615566Y271483D01*
G01X1615750Y269672D02*
X1614416Y271006D01*
G01X1615566Y271483D02*
Y276570D01*
G01X1614416Y271006D02*
Y277047D01*
G01X1615566Y276570D02*
X1621100Y282104D01*
G01X1614416Y277047D02*
X1619950Y282581D01*
G01X1649297Y320175D02*
Y278412D01*
G01X1648147Y319698D02*
Y278889D01*
G01X1649297Y278412D02*
X1647364Y276479D01*
G01D02*
X1647363D01*
G01D02*
X1646900Y276016D01*
G01X1648147Y278889D02*
X1645750Y276493D01*
G01X1646900Y276016D02*
Y230822D01*
G01X1645750Y276493D02*
Y231299D01*
G01X1648147Y319698D02*
Y278889D01*
G01X1649297Y320175D02*
Y278412D01*
G01X1648147Y278889D02*
X1645750Y276493D01*
G01X1649297Y278412D02*
X1647364Y276479D01*
G01X1648147Y278889D02*
X1645750Y276493D01*
G01X1647364Y276479D02*
X1647363D01*
G01X1648147Y278889D02*
X1645750Y276493D01*
G01X1647363Y276479D02*
X1646900Y276016D01*
G01X1645750Y276493D02*
Y231299D01*
G01X1646900Y276016D02*
Y230822D01*
G01X1596612Y287166D02*
X1606611Y272058D01*
G01X1596612Y287166D02*
X1606611Y272058D01*
G01X1596612Y287166D02*
X1606611Y272058D01*
G01X1599945Y280044D02*
X1600690Y278918D01*
G01X1596612Y287166D02*
X1606611Y272058D01*
G01X1602153Y276708D02*
X1602898Y275582D01*
G01X1596612Y287166D02*
X1606611Y272058D01*
G01X1604361Y273372D02*
X1605528Y271609D01*
G01X1606611Y272058D02*
X1607786Y266282D01*
G01X1605528Y271609D02*
X1606612Y266282D01*
G01X1607786D02*
X1603785Y246614D01*
G01X1606612Y266282D02*
X1604531Y256053D01*
G01X1607786Y266282D02*
X1603785Y246614D01*
G01X1604003Y253456D02*
X1603733Y252133D01*
G01X1607786Y266282D02*
X1603785Y246614D01*
G01X1603205Y249536D02*
X1602702Y247063D01*
G01X1603785Y246614D02*
X1600975Y242368D01*
G01X1602702Y247063D02*
X1600278Y243401D01*
G01X1600975Y242368D02*
X1591229Y240387D01*
G01X1600278Y243401D02*
X1590780Y241470D01*
G01X1599945Y280044D02*
X1600690Y278918D01*
G01X1602153Y276708D02*
X1602898Y275582D01*
G01X1604361Y273372D02*
X1605528Y271609D01*
G01X1596612Y287166D02*
X1606611Y272058D01*
G01X1605528Y271609D02*
X1606612Y266282D01*
G01X1606611Y272058D02*
X1607786Y266282D01*
G01X1606612D02*
X1604531Y256053D01*
G01X1604003Y253456D02*
X1603733Y252133D01*
G01X1603205Y249536D02*
X1602702Y247063D01*
G01X1607786Y266282D02*
X1603785Y246614D01*
G01X1602702Y247063D02*
X1600278Y243401D01*
G01X1603785Y246614D02*
X1600975Y242368D01*
G01X1600278Y243401D02*
X1590780Y241470D01*
G01X1600975Y242368D02*
X1591229Y240387D01*
G01X1588828Y294054D02*
X1592376Y277929D01*
G01X1592945Y275341D02*
X1593235Y274023D01*
G01X1593805Y271435D02*
X1594095Y270116D01*
G01X1594664Y267528D02*
X1594954Y266210D01*
G01X1595524Y263621D02*
X1595836Y262202D01*
G01X1589940Y294356D02*
X1597012Y262211D01*
G01X1595836Y262202D02*
X1595519Y260643D01*
G01X1595518D02*
X1594220Y254258D01*
G01X1597012Y262211D02*
X1595303Y253809D01*
G01X1589940Y294356D02*
X1597012Y262211D01*
G01X1588828Y294054D02*
X1592376Y277929D01*
G01X1589940Y294356D02*
X1597012Y262211D01*
G01X1592945Y275341D02*
X1593235Y274023D01*
G01X1589940Y294356D02*
X1597012Y262211D01*
G01X1593805Y271435D02*
X1594095Y270116D01*
G01X1589940Y294356D02*
X1597012Y262211D01*
G01X1594664Y267528D02*
X1594954Y266210D01*
G01X1589940Y294356D02*
X1597012Y262211D01*
G01X1595524Y263621D02*
X1595836Y262202D01*
G01X1597012Y262211D02*
X1595303Y253809D01*
G01X1595836Y262202D02*
X1595519Y260643D01*
G01X1597012Y262211D02*
X1595303Y253809D01*
G01X1595518Y260643D02*
X1594220Y254258D01*
G01X1599375Y222475D02*
X1617000Y240100D01*
G01X1599852Y221325D02*
X1618150Y239623D01*
G01X1617000Y240100D02*
Y259931D01*
G01X1618150Y239623D02*
Y259454D01*
G01X1617000Y259931D02*
X1619393Y262324D01*
G01X1618150Y259454D02*
X1620543Y261847D01*
G01X1619393Y262324D02*
Y274459D01*
G01X1620543Y261847D02*
Y273982D01*
G01X1619393Y274459D02*
X1621461Y276527D01*
G01X1620543Y273982D02*
X1621938Y275377D01*
G01X1621461Y276527D02*
X1623609D01*
G01X1621938Y275377D02*
X1624086D01*
G01X1623609Y276527D02*
X1625100Y278018D01*
G01X1624086Y275377D02*
X1626250Y277541D01*
G01X1625100Y278018D02*
Y282826D01*
G01X1626250Y277541D02*
Y282349D01*
G01X1619710Y239011D02*
Y245146D01*
G01X1620860Y238534D02*
Y244669D01*
G01X1619710Y245146D02*
X1623152Y248588D01*
G01X1620860Y244669D02*
X1624302Y248111D01*
G01X1623152Y248588D02*
Y249705D01*
G01Y252355D02*
Y253705D01*
G01Y256355D02*
Y265552D01*
G01X1624302Y248111D02*
Y265075D01*
G01X1623152Y265552D02*
X1624579Y266979D01*
G01X1626422Y268822D02*
X1628300Y270700D01*
G01X1624302Y265075D02*
X1629450Y270223D01*
G01X1628300Y270700D02*
Y281727D01*
G01X1629450Y270223D02*
Y281250D01*
G01X1599852Y221325D02*
X1618150Y239623D01*
G01X1599375Y222475D02*
X1617000Y240100D01*
G01X1618150Y239623D02*
Y259454D01*
G01X1617000Y240100D02*
Y259931D01*
G01X1618150Y259454D02*
X1620543Y261847D01*
G01X1617000Y259931D02*
X1619393Y262324D01*
G01X1620543Y261847D02*
Y273982D01*
G01X1619393Y262324D02*
Y274459D01*
G01X1620543Y273982D02*
X1621938Y275377D01*
G01X1619393Y274459D02*
X1621461Y276527D01*
G01X1621938Y275377D02*
X1624086D01*
G01X1621461Y276527D02*
X1623609D01*
G01X1624086Y275377D02*
X1626250Y277541D01*
G01X1623609Y276527D02*
X1625100Y278018D01*
G01X1626250Y277541D02*
Y282349D01*
G01X1625100Y278018D02*
Y282826D01*
G01X1620860Y238534D02*
Y244669D01*
G01X1619710Y239011D02*
Y245146D01*
G01X1620860Y244669D02*
X1624302Y248111D01*
G01X1619710Y245146D02*
X1623152Y248588D01*
G01X1624302Y248111D02*
Y265075D01*
G01X1623152Y248588D02*
Y249705D01*
G01X1624302Y248111D02*
Y265075D01*
G01X1623152Y252355D02*
Y253705D01*
G01X1624302Y248111D02*
Y265075D01*
G01X1623152Y256355D02*
Y265552D01*
G01X1624302Y265075D02*
X1629450Y270223D01*
G01X1623152Y265552D02*
X1624579Y266979D01*
G01X1624302Y265075D02*
X1629450Y270223D01*
G01X1626422Y268822D02*
X1628300Y270700D01*
G01X1629450Y270223D02*
Y281250D01*
G01X1628300Y270700D02*
Y281727D01*
G01X1602592Y229235D02*
X1614300Y240943D01*
G01X1603069Y228085D02*
X1615450Y240466D01*
G01X1614300Y240943D02*
Y262010D01*
G01X1615450Y240466D02*
Y261533D01*
G01X1614300Y262010D02*
X1615750Y263460D01*
G01X1615450Y261533D02*
X1616900Y262983D01*
G01X1615750Y263460D02*
Y269672D01*
G01X1616900Y262983D02*
Y270149D01*
G01X1615750Y269672D02*
X1614416Y271006D01*
G01X1616900Y270149D02*
X1615566Y271483D01*
G01X1614416Y271006D02*
Y277047D01*
G01X1615566Y271483D02*
Y276570D01*
G01X1614416Y277047D02*
X1619950Y282581D01*
G01X1615566Y276570D02*
X1621100Y282104D01*
G01X1608809Y284354D02*
Y276259D01*
G01X1609959Y284834D02*
Y276736D01*
G01X1608809Y276259D02*
X1611316Y273752D01*
G01X1609959Y276736D02*
X1612466Y274229D01*
G01X1611316Y273752D02*
Y269721D01*
G01X1612466Y274229D02*
Y270198D01*
G01X1611316Y269721D02*
X1612250Y268787D01*
G01X1612466Y270198D02*
X1613400Y269264D01*
G01X1612250Y268787D02*
Y264369D01*
G01X1613400Y269264D02*
Y263892D01*
G01X1612250Y264369D02*
X1610900Y263019D01*
G01X1613400Y263892D02*
X1612050Y262542D01*
G01X1610900Y263019D02*
Y241928D01*
G01X1612050Y262542D02*
Y241451D01*
G01X1610900Y241928D02*
X1601474Y232502D01*
G01X1612050Y241451D02*
X1601951Y231352D01*
G01X1609959Y284834D02*
Y276736D01*
G01X1608809Y284354D02*
Y276259D01*
G01X1609959Y276736D02*
X1612466Y274229D01*
G01X1608809Y276259D02*
X1611316Y273752D01*
G01X1612466Y274229D02*
Y270198D01*
G01X1611316Y273752D02*
Y269721D01*
G01X1612466Y270198D02*
X1613400Y269264D01*
G01X1611316Y269721D02*
X1612250Y268787D01*
G01X1613400Y269264D02*
Y263892D01*
G01X1612250Y268787D02*
Y264369D01*
G01X1613400Y263892D02*
X1612050Y262542D01*
G01X1612250Y264369D02*
X1610900Y263019D01*
G01X1612050Y262542D02*
Y241451D01*
G01X1610900Y263019D02*
Y241928D01*
G01X1612050Y241451D02*
X1601951Y231352D01*
G01X1610900Y241928D02*
X1601474Y232502D01*
G01X1619350Y233450D02*
X1628250D01*
G01X1619827Y232300D02*
X1628727D01*
G01X1628250Y233450D02*
X1631200Y236400D01*
G01X1628727Y232300D02*
X1632350Y235923D01*
G01X1631200Y236400D02*
Y260100D01*
G01X1632350Y235923D02*
Y255267D01*
G01X1631200Y236400D02*
Y260100D01*
G01X1632350Y257917D02*
Y259623D01*
G01X1631200Y260100D02*
X1633550Y262450D01*
G01X1632350Y259623D02*
X1634700Y261973D01*
G01X1633550Y262450D02*
Y284608D01*
G01X1634700Y261973D02*
Y284131D01*
G01X1619827Y232300D02*
X1628727D01*
G01X1619350Y233450D02*
X1628250D01*
G01X1628727Y232300D02*
X1632350Y235923D01*
G01X1628250Y233450D02*
X1631200Y236400D01*
G01X1632350Y235923D02*
Y255267D01*
G01Y257917D02*
Y259623D01*
G01X1631200Y236400D02*
Y260100D01*
G01X1632350Y259623D02*
X1634700Y261973D01*
G01X1631200Y260100D02*
X1633550Y262450D01*
G01X1634700Y261973D02*
Y284131D01*
G01X1633550Y262450D02*
Y284608D01*
G01X1646197Y279698D02*
X1643800Y277301D01*
G01X1645047Y280175D02*
X1642650Y277778D01*
G01X1643800Y277301D02*
Y249500D01*
G01X1642650Y277778D02*
Y249977D01*
G01X1643800Y249500D02*
X1641650Y247350D01*
G01X1642650Y249977D02*
X1640500Y247827D01*
G01X1641650Y247350D02*
Y240051D01*
G01X1640500Y247827D02*
Y240528D01*
G01X1641650Y240051D02*
X1638800Y237201D01*
G01X1640500Y240528D02*
X1637650Y237678D01*
G01X1638800Y237201D02*
Y227107D01*
G01X1637650Y237678D02*
Y227584D01*
G01X1638800Y227107D02*
X1633093Y221400D01*
G01X1637650Y227584D02*
X1632616Y222550D01*
G01X1633093Y221400D02*
X1626908D01*
G01X1632616Y222550D02*
X1626431D01*
G01X1626908Y221400D02*
X1624929Y219421D01*
G01X1626431Y222550D02*
X1623779Y219898D01*
G01D02*
Y217898D01*
G01X1645047Y280175D02*
X1642650Y277778D01*
G01X1646197Y279698D02*
X1643800Y277301D01*
G01X1642650Y277778D02*
Y249977D01*
G01X1643800Y277301D02*
Y249500D01*
G01X1642650Y249977D02*
X1640500Y247827D01*
G01X1643800Y249500D02*
X1641650Y247350D01*
G01X1640500Y247827D02*
Y240528D01*
G01X1641650Y247350D02*
Y240051D01*
G01X1640500Y240528D02*
X1637650Y237678D01*
G01X1641650Y240051D02*
X1638800Y237201D01*
G01X1637650Y237678D02*
Y227584D01*
G01X1638800Y237201D02*
Y227107D01*
G01X1637650Y227584D02*
X1632616Y222550D01*
G01X1638800Y227107D02*
X1633093Y221400D01*
G01X1632616Y222550D02*
X1626431D01*
G01X1633093Y221400D02*
X1626908D01*
G01X1626431Y222550D02*
X1623779Y219898D01*
G01X1626908Y221400D02*
X1624929Y219421D01*
G01X1623779Y219898D02*
Y217898D01*
G01X1641947Y281674D02*
X1639300Y279027D01*
G01X1643097Y281197D02*
X1640450Y278550D01*
G01X1639300Y279027D02*
Y251727D01*
G01X1640450Y278550D02*
Y251250D01*
G01X1639300Y251727D02*
X1634300Y246727D01*
G01X1640450Y251250D02*
X1635450Y246250D01*
G01X1634300Y246727D02*
Y235115D01*
G01X1635450Y246250D02*
Y234638D01*
G01X1634300Y235115D02*
X1629185Y230000D01*
G01X1635450Y234638D02*
X1629662Y228850D01*
G01X1629185Y230000D02*
X1620499D01*
G01X1629662Y228850D02*
X1620976D01*
G01X1643097Y281197D02*
X1640450Y278550D01*
G01X1641947Y281674D02*
X1639300Y279027D01*
G01X1640450Y278550D02*
Y251250D01*
G01X1639300Y279027D02*
Y251727D01*
G01X1640450Y251250D02*
X1635450Y246250D01*
G01X1639300Y251727D02*
X1634300Y246727D01*
G01X1635450Y246250D02*
Y234638D01*
G01X1634300Y246727D02*
Y235115D01*
G01X1635450Y234638D02*
X1629662Y228850D01*
G01X1634300Y235115D02*
X1629185Y230000D01*
G01X1629662Y228850D02*
X1620976D01*
G01X1629185Y230000D02*
X1620499D01*
G01X1650100Y219415D02*
X1656950Y226264D01*
G01X1650100Y219415D02*
X1656950Y226264D01*
G01X1621100Y282104D02*
Y287260D01*
G01X1619950Y282581D02*
Y287737D01*
G01X1621100Y287260D02*
X1628950Y295110D01*
G01X1619950Y287737D02*
X1627800Y295587D01*
G01X1628950Y295110D02*
Y311549D01*
G01X1627800Y295587D02*
Y311072D01*
G01X1628950Y311549D02*
X1613166Y327333D01*
G01X1627800Y311072D02*
X1612016Y326856D01*
G01X1613166Y327333D02*
Y347114D01*
G01X1612016Y326856D02*
Y347591D01*
G01X1650041Y354749D02*
Y337744D01*
G01X1648891Y354272D02*
Y338221D01*
G01X1650041Y337744D02*
X1648137Y335840D01*
G01X1648891Y338221D02*
X1646987Y336317D01*
G01X1648137Y335840D02*
Y321335D01*
G01X1646987Y336317D02*
Y320858D01*
G01X1648137Y321335D02*
X1649297Y320175D01*
G01X1646987Y320858D02*
X1648147Y319698D01*
G01X1648891Y354272D02*
Y338221D01*
G01X1650041Y354749D02*
Y337744D01*
G01X1648891Y338221D02*
X1646987Y336317D01*
G01X1650041Y337744D02*
X1648137Y335840D01*
G01X1646987Y336317D02*
Y320858D01*
G01X1648137Y335840D02*
Y321335D01*
G01X1646987Y320858D02*
X1648147Y319698D01*
G01X1648137Y321335D02*
X1649297Y320175D01*
G01X1605190Y353528D02*
X1596690Y311747D01*
G01X1604040Y353644D02*
X1599823Y332919D01*
G01X1605190Y353528D02*
X1596690Y311747D01*
G01X1599822Y332919D02*
X1595607Y312196D01*
G01X1596690Y311747D02*
X1595089Y309328D01*
G01X1595607Y312196D02*
X1593997Y309762D01*
G01X1595089Y309328D02*
X1593717Y301450D01*
G01X1593997Y309762D02*
X1592551Y301459D01*
G01X1593717Y301450D02*
X1593815Y300833D01*
G01X1592551Y301459D02*
X1592683Y300627D01*
G01X1593815Y300833D02*
X1595111Y294500D01*
G01X1592683Y300627D02*
X1593937Y294500D01*
G01X1595111D02*
X1596612Y287166D01*
G01X1593937Y294500D02*
X1595530Y286716D01*
G01D02*
X1596274Y285590D01*
G01X1597737Y283380D02*
X1598482Y282254D01*
G01X1604040Y353644D02*
X1599823Y332919D01*
G01X1599822D02*
X1595607Y312196D01*
G01X1605190Y353528D02*
X1596690Y311747D01*
G01X1595607Y312196D02*
X1593997Y309762D01*
G01X1596690Y311747D02*
X1595089Y309328D01*
G01X1593997Y309762D02*
X1592551Y301459D01*
G01X1595089Y309328D02*
X1593717Y301450D01*
G01X1592551Y301459D02*
X1592683Y300627D01*
G01X1593717Y301450D02*
X1593815Y300833D01*
G01X1592683Y300627D02*
X1593937Y294500D01*
G01X1593815Y300833D02*
X1595111Y294500D01*
G01X1593937D02*
X1595530Y286716D01*
G01X1595111Y294500D02*
X1596612Y287166D01*
G01X1595530Y286716D02*
X1596274Y285590D01*
G01X1597737Y283380D02*
X1598482Y282254D01*
G01X1600085Y352806D02*
X1596196Y333687D01*
G01X1596197D02*
X1592307Y314567D01*
G01X1601259Y352805D02*
X1593390Y314118D01*
G01X1592307Y314567D02*
X1590443Y311754D01*
G01X1593390Y314118D02*
X1591524Y311303D01*
G01D02*
X1589739Y302763D01*
G01D02*
X1590269Y299447D01*
G01D02*
X1589368Y296123D01*
G01D02*
X1589940Y294356D01*
G01X1601259Y352805D02*
X1593390Y314118D01*
G01X1600085Y352806D02*
X1596196Y333687D01*
G01X1601259Y352805D02*
X1593390Y314118D01*
G01X1596197Y333687D02*
X1592307Y314567D01*
G01X1593390Y314118D02*
X1591524Y311303D01*
G01X1592307Y314567D02*
X1590443Y311754D01*
G01X1591524Y311303D02*
X1589739Y302763D01*
G01D02*
X1590269Y299447D01*
G01D02*
X1589368Y296123D01*
G01D02*
X1589940Y294356D01*
G01X1589368Y296123D02*
X1589940Y294356D01*
G01X1625100Y282826D02*
X1627920Y285646D01*
G01X1626250Y282349D02*
X1629070Y285169D01*
G01X1627920Y285646D02*
Y291820D01*
G01X1629070Y285169D02*
Y291343D01*
G01X1627920Y291820D02*
X1630465Y294365D01*
G01X1629070Y291343D02*
X1631615Y293888D01*
G01X1630465Y294365D02*
Y314124D01*
G01X1631615Y293888D02*
Y314601D01*
G01X1630465Y314124D02*
X1629510Y315079D01*
G01X1627637Y316952D02*
X1626682Y317907D01*
G01X1624809Y319780D02*
X1615974Y328615D01*
G01X1631615Y314601D02*
X1617124Y329092D01*
G01X1615974Y328615D02*
Y345640D01*
G01X1617124Y329092D02*
Y345163D01*
G01X1628300Y281727D02*
X1630450Y283877D01*
G01X1629450Y281250D02*
X1631600Y283400D01*
G01X1630450Y283877D02*
Y290677D01*
G01X1631600Y283400D02*
Y290200D01*
G01X1630450Y290677D02*
X1632965Y293192D01*
G01X1631600Y290200D02*
X1634115Y292715D01*
G01X1632965Y293192D02*
Y315535D01*
G01X1634115Y292715D02*
Y316012D01*
G01X1632965Y315535D02*
X1627880Y320620D01*
G01X1634115Y316012D02*
X1629030Y321097D01*
G01X1627880Y320620D02*
Y330486D01*
G01X1629030Y321097D02*
Y330963D01*
G01X1627880Y330486D02*
X1622276Y336090D01*
G01X1629030Y330963D02*
X1623426Y336567D01*
G01X1622276Y336090D02*
Y348405D01*
G01X1623426Y336567D02*
Y347928D01*
G01X1626250Y282349D02*
X1629070Y285169D01*
G01X1625100Y282826D02*
X1627920Y285646D01*
G01X1629070Y285169D02*
Y291343D01*
G01X1627920Y285646D02*
Y291820D01*
G01X1629070Y291343D02*
X1631615Y293888D01*
G01X1627920Y291820D02*
X1630465Y294365D01*
G01X1631615Y293888D02*
Y314601D01*
G01X1630465Y294365D02*
Y314124D01*
G01X1631615Y314601D02*
X1617124Y329092D01*
G01X1630465Y314124D02*
X1629510Y315079D01*
G01X1631615Y314601D02*
X1617124Y329092D01*
G01X1627637Y316952D02*
X1626682Y317907D01*
G01X1631615Y314601D02*
X1617124Y329092D01*
G01X1624809Y319780D02*
X1615974Y328615D01*
G01X1617124Y329092D02*
Y345163D01*
G01X1615974Y328615D02*
Y345640D01*
G01X1629450Y281250D02*
X1631600Y283400D01*
G01X1628300Y281727D02*
X1630450Y283877D01*
G01X1631600Y283400D02*
Y290200D01*
G01X1630450Y283877D02*
Y290677D01*
G01X1631600Y290200D02*
X1634115Y292715D01*
G01X1630450Y290677D02*
X1632965Y293192D01*
G01X1634115Y292715D02*
Y316012D01*
G01X1632965Y293192D02*
Y315535D01*
G01X1634115Y316012D02*
X1629030Y321097D01*
G01X1632965Y315535D02*
X1627880Y320620D01*
G01X1629030Y321097D02*
Y330963D01*
G01X1627880Y320620D02*
Y330486D01*
G01X1629030Y330963D02*
X1623426Y336567D01*
G01X1627880Y330486D02*
X1622276Y336090D01*
G01X1623426Y336567D02*
Y347928D01*
G01X1622276Y336090D02*
Y348405D01*
G01X1619950Y282581D02*
Y287737D01*
G01X1621100Y282104D02*
Y287260D01*
G01X1619950Y287737D02*
X1627800Y295587D01*
G01X1621100Y287260D02*
X1628950Y295110D01*
G01X1627800Y295587D02*
Y311072D01*
G01X1628950Y295110D02*
Y311549D01*
G01X1627800Y311072D02*
X1612016Y326856D01*
G01X1628950Y311549D02*
X1613166Y327333D01*
G01X1612016Y326856D02*
Y347591D01*
G01X1613166Y327333D02*
Y347114D01*
G01X1605698Y346239D02*
Y317580D01*
G01X1606848Y346123D02*
Y317103D01*
G01X1605698Y317580D02*
X1599699Y311581D01*
G01X1606848Y317103D02*
X1604836Y315091D01*
G01X1605698Y317580D02*
X1599699Y311581D01*
G01X1604837Y315091D02*
X1600647Y310901D01*
G01X1599699Y311581D02*
X1597380Y306889D01*
G01X1600647Y310901D02*
X1598530Y306620D01*
G01X1597380Y306889D02*
Y299449D01*
G01X1598530Y306620D02*
Y299668D01*
G01X1597380Y299449D02*
X1599762Y293400D01*
G01X1598530Y299668D02*
X1600745Y294045D01*
G01X1599762Y293400D02*
X1608809Y284354D01*
G01X1600745Y294045D02*
X1609959Y284834D01*
G01X1606848Y346123D02*
Y317103D01*
G01X1605698Y346239D02*
Y317580D01*
G01X1606848Y317103D02*
X1604836Y315091D01*
G01X1604837D02*
X1600647Y310901D01*
G01X1605698Y317580D02*
X1599699Y311581D01*
G01X1600647Y310901D02*
X1598530Y306620D01*
G01X1599699Y311581D02*
X1597380Y306889D01*
G01X1598530Y306620D02*
Y299668D01*
G01X1597380Y306889D02*
Y299449D01*
G01X1598530Y299668D02*
X1600745Y294045D01*
G01X1597380Y299449D02*
X1599762Y293400D01*
G01X1600745Y294045D02*
X1609959Y284834D01*
G01X1599762Y293400D02*
X1608809Y284354D01*
G01X1633550Y284608D02*
X1635073Y286131D01*
G01X1634700Y284131D02*
X1635550Y284981D01*
G01X1635073Y286131D02*
X1637748D01*
G01X1635550Y284981D02*
X1638225D01*
G01X1637748Y286131D02*
X1638847Y287230D01*
G01X1638225Y284981D02*
X1639997Y286753D01*
G01X1638847Y287230D02*
Y305827D01*
G01X1639997Y286753D02*
Y306304D01*
G01X1638847Y305827D02*
X1636065Y308609D01*
G01X1639997Y306304D02*
X1637215Y309086D01*
G01X1636065Y308609D02*
Y317135D01*
G01X1637215Y309086D02*
Y317612D01*
G01X1636065Y317135D02*
X1632300Y320900D01*
G01X1637215Y317612D02*
X1633450Y321377D01*
G01X1632300Y320900D02*
Y326400D01*
G01X1633450Y321377D02*
Y325923D01*
G01X1632300Y326400D02*
X1632896Y326996D01*
G01X1633450Y325923D02*
X1634046Y326519D01*
G01X1632896Y326996D02*
Y329987D01*
G01X1634046Y326519D02*
Y330464D01*
G01X1632896Y329987D02*
X1625376Y337507D01*
G01X1634046Y330464D02*
X1626526Y337984D01*
G01X1625376Y337507D02*
Y346409D01*
G01X1626526Y337984D02*
Y345932D01*
G01X1634700Y284131D02*
X1635550Y284981D01*
G01X1633550Y284608D02*
X1635073Y286131D01*
G01X1635550Y284981D02*
X1638225D01*
G01X1635073Y286131D02*
X1637748D01*
G01X1638225Y284981D02*
X1639997Y286753D01*
G01X1637748Y286131D02*
X1638847Y287230D01*
G01X1639997Y286753D02*
Y306304D01*
G01X1638847Y287230D02*
Y305827D01*
G01X1639997Y306304D02*
X1637215Y309086D01*
G01X1638847Y305827D02*
X1636065Y308609D01*
G01X1637215Y309086D02*
Y317612D01*
G01X1636065Y308609D02*
Y317135D01*
G01X1637215Y317612D02*
X1633450Y321377D01*
G01X1636065Y317135D02*
X1632300Y320900D01*
G01X1633450Y321377D02*
Y325923D01*
G01X1632300Y320900D02*
Y326400D01*
G01X1633450Y325923D02*
X1634046Y326519D01*
G01X1632300Y326400D02*
X1632896Y326996D01*
G01X1634046Y326519D02*
Y330464D01*
G01X1632896Y326996D02*
Y329987D01*
G01X1634046Y330464D02*
X1626526Y337984D01*
G01X1632896Y329987D02*
X1625376Y337507D01*
G01X1626526Y337984D02*
Y345932D01*
G01X1625376Y337507D02*
Y346409D01*
G01X1646675Y341865D02*
X1644623Y339813D01*
G01X1645525Y342342D02*
X1643473Y340290D01*
G01X1644623Y339813D02*
Y320456D01*
G01X1643473Y340290D02*
Y319979D01*
G01X1644623Y320456D02*
X1646197Y318882D01*
G01X1643473Y319979D02*
X1645047Y318405D01*
G01X1646197Y318882D02*
Y279698D01*
G01X1645047Y318405D02*
Y280175D01*
G01X1645525Y342342D02*
X1643473Y340290D01*
G01X1646675Y341865D02*
X1644623Y339813D01*
G01X1643473Y340290D02*
Y319979D01*
G01X1644623Y339813D02*
Y320456D01*
G01X1643473Y319979D02*
X1645047Y318405D01*
G01X1644623Y320456D02*
X1646197Y318882D01*
G01X1645047Y318405D02*
Y280175D01*
G01X1646197Y318882D02*
Y279698D01*
G01X1638287Y346070D02*
Y330438D01*
G01X1639437Y346547D02*
Y330915D01*
G01X1638287Y330438D02*
X1639911Y328814D01*
G01X1639437Y330915D02*
X1641061Y329291D01*
G01X1639911Y328814D02*
Y318912D01*
G01X1641061Y329291D02*
Y319389D01*
G01X1639911Y318912D02*
X1641947Y316876D01*
G01X1641061Y319389D02*
X1643097Y317353D01*
G01X1641947Y316876D02*
Y281674D01*
G01X1643097Y317353D02*
Y281197D01*
G01X1639437Y346547D02*
Y330915D01*
G01X1638287Y346070D02*
Y330438D01*
G01X1639437Y330915D02*
X1641061Y329291D01*
G01X1638287Y330438D02*
X1639911Y328814D01*
G01X1641061Y329291D02*
Y319389D01*
G01X1639911Y328814D02*
Y318912D01*
G01X1641061Y319389D02*
X1643097Y317353D01*
G01X1639911Y318912D02*
X1641947Y316876D01*
G01X1643097Y317353D02*
Y281197D01*
G01X1641947Y316876D02*
Y281674D01*
G01X1655516Y365644D02*
X1650392Y370768D01*
G01D02*
Y372015D01*
G01D02*
X1647500Y374907D01*
G01X1651542Y372492D02*
X1648650Y375384D01*
G01X1647500Y374907D02*
Y425031D01*
G01X1648650Y375384D02*
Y424554D01*
G01X1655516Y365644D02*
X1650392Y370768D01*
G01D02*
Y372015D01*
G01X1651542Y372492D02*
X1648650Y375384D01*
G01X1650392Y372015D02*
X1647500Y374907D01*
G01X1648650Y375384D02*
Y424554D01*
G01X1647500Y374907D02*
Y425031D01*
G01X1613166Y347114D02*
X1617575Y351523D01*
G01X1612016Y347591D02*
X1616425Y352000D01*
G01X1617575Y351523D02*
Y381181D01*
G01X1616425Y352000D02*
Y381658D01*
G01X1617575Y381181D02*
X1619650Y383256D01*
G01X1616425Y381658D02*
X1618500Y383733D01*
G01X1619650Y383256D02*
Y395577D01*
G01X1618500Y383733D02*
Y395100D01*
G01X1619650Y395577D02*
X1617700Y397527D01*
G01X1618500Y395100D02*
X1616550Y397050D01*
G01X1617700Y397527D02*
Y402255D01*
G01X1616550Y397050D02*
Y401778D01*
G01X1617700Y402255D02*
X1615974Y403981D01*
G01X1616550Y401778D02*
X1614824Y403504D01*
G01X1645550Y428277D02*
Y374099D01*
G01Y428277D02*
Y374099D01*
G01X1644400Y402085D02*
Y400735D01*
G01X1645550Y428277D02*
Y374099D01*
G01X1644400Y398085D02*
Y396735D01*
G01X1645550Y428277D02*
Y374099D01*
G01X1644400Y394085D02*
Y392735D01*
G01X1645550Y428277D02*
Y374099D01*
G01X1644400Y390085D02*
Y373622D01*
G01X1645550Y374099D02*
X1648442Y371207D01*
G01X1644400Y373622D02*
X1647292Y370730D01*
G01X1648442Y371207D02*
Y356348D01*
G01X1647292Y370730D02*
Y355871D01*
G01X1648442Y356348D02*
X1650041Y354749D01*
G01X1647292Y355871D02*
X1648891Y354272D01*
G01X1644400Y402085D02*
Y400735D01*
G01Y398085D02*
Y396735D01*
G01Y394085D02*
Y392735D01*
G01Y390085D02*
Y373622D01*
G01X1645550Y428277D02*
Y374099D01*
G01X1644400Y373622D02*
X1647292Y370730D01*
G01X1645550Y374099D02*
X1648442Y371207D01*
G01X1647292Y370730D02*
Y355871D01*
G01X1648442Y371207D02*
Y356348D01*
G01X1647292Y355871D02*
X1648891Y354272D01*
G01X1648442Y356348D02*
X1650041Y354749D01*
G01X1607008Y404169D02*
X1611317Y399860D01*
G01X1605858Y403692D02*
X1610167Y399383D01*
G01X1611317Y399860D02*
Y385438D01*
G01X1610167Y399383D02*
Y385916D01*
G01X1611317Y385438D02*
X1608087Y382207D01*
G01X1610167Y385916D02*
X1609849Y385598D01*
G01X1611317Y385438D02*
X1608087Y382207D01*
G01X1609850Y385598D02*
X1607609Y383357D01*
G01X1608087Y382207D02*
X1606807D01*
G01X1607609Y383357D02*
X1606330D01*
G01X1606807Y382207D02*
X1605190Y380589D01*
G01X1606330Y383357D02*
X1604040Y381066D01*
G01X1605190Y380589D02*
Y353528D01*
G01X1604040Y381066D02*
Y353644D01*
G01X1605858Y403692D02*
X1610167Y399383D01*
G01X1607008Y404169D02*
X1611317Y399860D01*
G01X1610167Y399383D02*
Y385916D01*
G01X1611317Y399860D02*
Y385438D01*
G01X1610167Y385916D02*
X1609849Y385598D01*
G01X1609850D02*
X1607609Y383357D01*
G01X1611317Y385438D02*
X1608087Y382207D01*
G01X1607609Y383357D02*
X1606330D01*
G01X1608087Y382207D02*
X1606807D01*
G01X1606330Y383357D02*
X1604040Y381066D01*
G01X1606807Y382207D02*
X1605190Y380589D01*
G01X1604040Y381066D02*
Y353644D01*
G01X1605190Y380589D02*
Y353528D01*
G01X1599236Y406156D02*
X1595305Y400220D01*
G01X1600319Y405707D02*
X1596388Y399771D01*
G01X1595305Y400220D02*
X1594505Y396283D01*
G01X1596388Y399771D02*
X1595679Y396283D01*
G01X1594505D02*
X1595351Y392122D01*
G01X1595679Y396283D02*
X1596525Y392122D01*
G01X1595351D02*
X1592503Y378122D01*
G01X1596525Y392122D02*
X1593677Y378122D01*
G01X1592503D02*
X1594994Y365883D01*
G01X1593677Y378122D02*
X1596027Y366580D01*
G01X1594994Y365883D02*
X1597803Y364024D01*
G01X1596027Y366580D02*
X1598836Y364721D01*
G01X1597803Y364024D02*
X1600085Y352806D01*
G01X1598836Y364721D02*
X1601259Y352805D01*
G01X1600319Y405707D02*
X1596388Y399771D01*
G01X1599236Y406156D02*
X1595305Y400220D01*
G01X1596388Y399771D02*
X1595679Y396283D01*
G01X1595305Y400220D02*
X1594505Y396283D01*
G01X1595679D02*
X1596525Y392122D01*
G01X1594505Y396283D02*
X1595351Y392122D01*
G01X1596525D02*
X1593677Y378122D01*
G01X1595351Y392122D02*
X1592503Y378122D01*
G01X1593677D02*
X1596027Y366580D01*
G01X1592503Y378122D02*
X1594994Y365883D01*
G01X1596027Y366580D02*
X1598836Y364721D01*
G01X1594994Y365883D02*
X1597803Y364024D01*
G01X1598836Y364721D02*
X1601259Y352805D01*
G01X1597803Y364024D02*
X1600085Y352806D01*
G01X1615974Y345640D02*
X1622223Y351889D01*
G01X1617124Y345163D02*
X1623373Y351412D01*
G01X1622223Y351889D02*
Y363912D01*
G01X1623373Y351412D02*
Y363435D01*
G01X1622223Y363912D02*
X1623776Y365465D01*
G01X1623373Y363435D02*
X1624926Y364988D01*
G01X1623776Y365465D02*
Y398705D01*
G01X1624926Y364988D02*
Y398228D01*
G01X1623776Y398705D02*
X1624625Y399554D01*
G01X1624926Y398228D02*
X1625775Y399077D01*
G01X1624625Y399554D02*
Y404095D01*
G01X1625775Y399077D02*
Y404572D01*
G01X1622276Y348405D02*
X1624723Y350852D01*
G01X1623426Y347928D02*
X1625873Y350375D01*
G01X1624723Y350852D02*
Y361047D01*
G01X1625873Y350375D02*
Y360570D01*
G01X1624723Y361047D02*
X1626312Y362636D01*
G01X1625873Y360570D02*
X1627462Y362159D01*
G01X1626312Y362636D02*
Y397704D01*
G01X1627462Y362159D02*
Y397227D01*
G01X1626312Y397704D02*
X1627125Y398517D01*
G01X1627462Y397227D02*
X1628275Y398040D01*
G01X1627125Y398517D02*
Y405567D01*
G01X1628275Y398040D02*
Y406044D01*
G01X1617124Y345163D02*
X1623373Y351412D01*
G01X1615974Y345640D02*
X1622223Y351889D01*
G01X1623373Y351412D02*
Y363435D01*
G01X1622223Y351889D02*
Y363912D01*
G01X1623373Y363435D02*
X1624926Y364988D01*
G01X1622223Y363912D02*
X1623776Y365465D01*
G01X1624926Y364988D02*
Y398228D01*
G01X1623776Y365465D02*
Y398705D01*
G01X1624926Y398228D02*
X1625775Y399077D01*
G01X1623776Y398705D02*
X1624625Y399554D01*
G01X1625775Y399077D02*
Y404572D01*
G01X1624625Y399554D02*
Y404095D01*
G01X1623426Y347928D02*
X1625873Y350375D01*
G01X1622276Y348405D02*
X1624723Y350852D01*
G01X1625873Y350375D02*
Y360570D01*
G01X1624723Y350852D02*
Y361047D01*
G01X1625873Y360570D02*
X1627462Y362159D01*
G01X1624723Y361047D02*
X1626312Y362636D01*
G01X1627462Y362159D02*
Y397227D01*
G01X1626312Y362636D02*
Y397704D01*
G01X1627462Y397227D02*
X1628275Y398040D01*
G01X1626312Y397704D02*
X1627125Y398517D01*
G01X1628275Y398040D02*
Y406044D01*
G01X1627125Y398517D02*
Y405567D01*
G01X1612016Y347591D02*
X1616425Y352000D01*
G01X1613166Y347114D02*
X1617575Y351523D01*
G01X1616425Y352000D02*
Y381658D01*
G01X1617575Y351523D02*
Y381181D01*
G01X1616425Y381658D02*
X1618500Y383733D01*
G01X1617575Y381181D02*
X1619650Y383256D01*
G01X1618500Y383733D02*
Y395100D01*
G01X1619650Y383256D02*
Y395577D01*
G01X1618500Y395100D02*
X1616550Y397050D01*
G01X1619650Y395577D02*
X1617700Y397527D01*
G01X1616550Y397050D02*
Y401778D01*
G01X1617700Y397527D02*
Y402255D01*
G01X1616550Y401778D02*
X1614824Y403504D01*
G01X1617700Y402255D02*
X1615974Y403981D01*
G01X1609087Y404856D02*
X1613450Y400493D01*
G01X1610237Y405333D02*
X1614600Y400970D01*
G01X1613450Y400493D02*
Y394750D01*
G01X1614600Y400970D02*
Y395227D01*
G01X1613450Y394750D02*
X1615330Y392870D01*
G01X1614600Y395227D02*
X1616480Y393347D01*
G01X1615330Y392870D02*
Y389248D01*
G01X1615329Y389247D02*
Y388295D01*
G01X1615330Y388294D02*
Y385656D01*
G01X1616480Y393347D02*
Y385179D01*
G01X1615330Y385656D02*
X1613050Y383376D01*
G01X1616480Y385179D02*
X1614200Y382899D01*
G01X1613050Y383376D02*
Y356179D01*
G01X1614200Y382899D02*
Y355702D01*
G01X1613050Y356179D02*
X1606360Y349489D01*
G01X1614200Y355702D02*
X1607418Y348920D01*
G01X1606360Y349489D02*
X1605698Y346239D01*
G01X1607418Y348920D02*
X1606848Y346123D01*
G01X1610237Y405333D02*
X1614600Y400970D01*
G01X1609087Y404856D02*
X1613450Y400493D01*
G01X1614600Y400970D02*
Y395227D01*
G01X1613450Y400493D02*
Y394750D01*
G01X1614600Y395227D02*
X1616480Y393347D01*
G01X1613450Y394750D02*
X1615330Y392870D01*
G01X1616480Y393347D02*
Y385179D01*
G01X1615330Y392870D02*
Y389248D01*
G01X1616480Y393347D02*
Y385179D01*
G01X1615329Y389247D02*
Y388295D01*
G01X1616480Y393347D02*
Y385179D01*
G01X1615330Y388294D02*
Y385656D01*
G01X1616480Y385179D02*
X1614200Y382899D01*
G01X1615330Y385656D02*
X1613050Y383376D01*
G01X1614200Y382899D02*
Y355702D01*
G01X1613050Y383376D02*
Y356179D01*
G01X1614200Y355702D02*
X1607418Y348920D01*
G01X1613050Y356179D02*
X1606360Y349489D01*
G01X1607418Y348920D02*
X1606848Y346123D01*
G01X1606360Y349489D02*
X1605698Y346239D01*
G01X1625376Y346409D02*
X1632783Y353816D01*
G01X1626526Y345932D02*
X1633933Y353339D01*
G01X1632783Y353816D02*
Y405366D01*
G01X1633933Y353339D02*
Y405843D01*
G01X1626526Y345932D02*
X1633933Y353339D01*
G01X1625376Y346409D02*
X1632783Y353816D01*
G01X1633933Y353339D02*
Y405843D01*
G01X1632783Y353816D02*
Y405366D01*
G01X1641800Y425027D02*
Y373409D01*
G01X1640650Y424550D02*
Y372932D01*
G01X1641800Y373409D02*
X1642975Y372234D01*
G01X1640650Y372932D02*
X1641825Y371757D01*
G01X1642975Y372234D02*
Y371588D01*
G01X1641825Y371757D02*
Y371112D01*
G01X1642975Y371588D02*
X1645101Y369458D01*
G01X1641825Y371112D02*
X1643951Y368982D01*
G01X1645101Y369458D02*
Y354475D01*
G01X1643951Y368982D02*
Y353998D01*
G01X1645101Y354475D02*
X1646675Y352901D01*
G01X1643951Y353998D02*
X1645525Y352424D01*
G01X1646675Y352901D02*
Y341865D01*
G01X1645525Y352424D02*
Y342342D01*
G01X1640650Y424550D02*
Y372932D01*
G01X1641800Y425027D02*
Y373409D01*
G01X1640650Y372932D02*
X1641825Y371757D01*
G01X1641800Y373409D02*
X1642975Y372234D01*
G01X1641825Y371757D02*
Y371112D01*
G01X1642975Y372234D02*
Y371588D01*
G01X1641825Y371112D02*
X1643951Y368982D01*
G01X1642975Y371588D02*
X1645101Y369458D01*
G01X1643951Y368982D02*
Y353998D01*
G01X1645101Y369458D02*
Y354475D01*
G01X1643951Y353998D02*
X1645525Y352424D01*
G01X1645101Y354475D02*
X1646675Y352901D01*
G01X1645525Y352424D02*
Y342342D01*
G01X1646675Y352901D02*
Y341865D01*
G01X1636400Y424373D02*
Y353655D01*
G01Y424373D02*
Y353655D01*
G01Y424373D02*
Y353655D01*
G01Y424373D02*
Y353655D01*
G01X1637550Y407527D02*
Y353178D01*
G01X1636400Y353655D02*
X1636016Y353271D01*
G01X1637550Y353178D02*
X1637166Y352794D01*
G01X1636016Y353271D02*
Y348341D01*
G01X1637166Y352794D02*
Y348818D01*
G01X1636016Y348341D02*
X1638287Y346070D01*
G01X1637166Y348818D02*
X1639437Y346547D01*
G01X1637550Y407527D02*
Y353178D01*
G01X1636400Y424373D02*
Y353655D01*
G01X1637550Y353178D02*
X1637166Y352794D01*
G01X1636400Y353655D02*
X1636016Y353271D01*
G01X1637166Y352794D02*
Y348818D01*
G01X1636016Y353271D02*
Y348341D01*
G01X1637166Y348818D02*
X1639437Y346547D01*
G01X1636016Y348341D02*
X1638287Y346070D01*
G01X1647500Y425031D02*
X1649050Y426581D01*
G01X1648650Y424554D02*
X1650200Y426104D01*
G01X1649050Y426581D02*
Y454340D01*
G01X1650200Y426104D02*
Y453863D01*
G01X1649050Y426581D02*
Y454340D01*
G01X1650201Y453864D02*
Y454816D01*
G01X1649050Y454340D02*
X1648068Y455322D01*
G01X1646195Y457195D02*
X1645240Y458150D01*
G01X1643366Y460024D02*
X1636690Y466700D01*
G01X1650201Y454816D02*
X1637167Y467850D01*
G01X1643665Y464216D02*
X1644584D01*
G01D02*
X1645539Y463261D01*
G01X1646493Y461388D02*
X1647412D01*
G01D02*
X1648367Y460433D01*
G01X1649321Y458560D02*
X1650240D01*
G01D02*
X1652050Y456750D01*
G01X1632558Y477869D02*
X1653200Y457227D01*
G01X1648650Y424554D02*
X1650200Y426104D01*
G01X1647500Y425031D02*
X1649050Y426581D01*
G01X1650200Y426104D02*
Y453863D01*
G01X1650201Y453864D02*
Y454816D01*
G01X1649050Y426581D02*
Y454340D01*
G01X1650201Y454816D02*
X1637167Y467850D01*
G01X1649050Y454340D02*
X1648068Y455322D01*
G01X1650201Y454816D02*
X1637167Y467850D01*
G01X1646195Y457195D02*
X1645240Y458150D01*
G01X1650201Y454816D02*
X1637167Y467850D01*
G01X1643366Y460024D02*
X1636690Y466700D01*
G01X1632558Y477869D02*
X1653200Y457227D01*
G01X1632558Y477869D02*
X1653200Y457227D01*
G01X1632558Y477869D02*
X1653200Y457227D01*
G01X1632558Y477869D02*
X1653200Y457227D01*
G01X1632558Y477869D02*
X1653200Y457227D01*
G01X1632558Y477869D02*
X1653200Y457227D01*
G01X1643665Y464216D02*
X1644584D01*
G01X1632558Y477869D02*
X1653200Y457227D01*
G01X1644584Y464216D02*
X1645539Y463261D01*
G01X1632558Y477869D02*
X1653200Y457227D01*
G01X1646493Y461388D02*
X1647412D01*
G01X1632558Y477869D02*
X1653200Y457227D01*
G01X1647412Y461388D02*
X1648367Y460433D01*
G01X1632558Y477869D02*
X1653200Y457227D01*
G01X1649321Y458560D02*
X1650240D01*
G01X1632558Y477869D02*
X1653200Y457227D01*
G01X1650240Y458560D02*
X1652050Y456750D01*
G01X1615974Y403981D02*
Y423613D01*
G01X1614824Y403504D02*
Y423136D01*
G01X1615974Y423613D02*
X1612941Y426646D01*
G01X1614824Y423136D02*
X1612464Y425496D01*
G01X1612941Y426646D02*
X1612003D01*
G01X1612464Y425496D02*
X1611526D01*
G01X1612003Y426646D02*
X1609725Y428924D01*
G01X1611526Y425496D02*
X1608575Y428447D01*
G01X1609725Y428924D02*
Y442452D01*
G01X1608575Y428447D02*
Y441974D01*
G01X1609725Y442452D02*
X1607190Y444987D01*
G01X1605316Y446861D02*
X1604361Y447816D01*
G01X1602431Y449746D02*
X1600217Y451960D01*
G01X1608575Y441974D02*
X1599739Y450810D01*
G01X1600217Y451960D02*
X1596996D01*
G01X1599739Y450810D02*
X1596519D01*
G01X1596996Y451960D02*
X1592216Y456740D01*
G01X1596519Y450810D02*
X1591066Y456263D01*
G01X1592216Y456740D02*
Y459960D01*
G01X1591066Y456263D02*
Y459483D01*
G01X1627064Y469218D02*
X1631532Y464750D01*
G01X1625914Y468741D02*
X1631055Y463600D01*
G01D02*
X1633287D01*
G01X1633764Y464750D02*
X1637850Y460664D01*
G01X1633287Y463600D02*
X1636700Y460187D01*
G01X1637850Y460664D02*
Y452349D01*
G01X1636700Y460187D02*
Y451872D01*
G01X1637850Y452349D02*
X1643650Y446549D01*
G01X1636700Y451872D02*
X1642500Y446072D01*
G01X1643650Y446549D02*
Y430177D01*
G01X1642500Y446072D02*
Y442395D01*
G01X1643650Y446549D02*
Y430177D01*
G01X1642500Y439745D02*
Y429700D01*
G01X1643650Y430177D02*
X1645550Y428277D01*
G01X1642500Y429700D02*
X1644400Y427800D01*
G01D02*
Y404735D01*
G01X1625914Y468741D02*
X1631055Y463600D01*
G01X1627064Y469218D02*
X1631532Y464750D01*
G01X1631055Y463600D02*
X1633287D01*
G01D02*
X1636700Y460187D01*
G01X1633764Y464750D02*
X1637850Y460664D01*
G01X1636700Y460187D02*
Y451872D01*
G01X1637850Y460664D02*
Y452349D01*
G01X1636700Y451872D02*
X1642500Y446072D01*
G01X1637850Y452349D02*
X1643650Y446549D01*
G01X1642500Y446072D02*
Y442395D01*
G01Y439745D02*
Y429700D01*
G01X1643650Y446549D02*
Y430177D01*
G01X1642500Y429700D02*
X1644400Y427800D01*
G01X1643650Y430177D02*
X1645550Y428277D01*
G01X1644400Y427800D02*
Y404735D01*
G01X1591822Y443521D02*
X1593548D01*
G01D02*
X1595703Y442097D01*
G01X1591822Y442371D02*
X1593202D01*
G01X1593548Y443521D02*
X1595703Y442097D01*
G01X1593202Y442371D02*
X1594877Y441263D01*
G01X1595703Y442097D02*
X1600476Y435028D01*
G01X1594877Y441263D02*
X1599394Y434574D01*
G01X1600476Y435028D02*
X1601859Y428233D01*
G01X1599394Y434574D02*
X1600776Y427782D01*
G01X1601999Y428020D02*
X1600968Y422957D01*
G01X1600776Y427782D02*
X1599794Y422957D01*
G01X1600968D02*
X1601307Y421292D01*
G01X1599794Y422957D02*
X1600084Y421531D01*
G01X1600968Y422957D02*
X1601307Y421292D01*
G01X1600084Y421530D02*
X1600274Y420596D01*
G01X1601307Y421292D02*
X1606340Y417960D01*
G01X1600274Y420596D02*
X1605608Y417064D01*
G01X1606340Y417960D02*
X1607008Y417291D01*
G01X1605608Y417064D02*
X1605858Y416814D01*
G01X1607008Y417291D02*
Y404169D01*
G01X1605858Y416814D02*
Y403692D01*
G01X1591822Y442371D02*
X1593202D01*
G01X1591822Y443521D02*
X1593548D01*
G01X1591822Y442371D02*
X1593202D01*
G01D02*
X1594877Y441263D01*
G01X1593548Y443521D02*
X1595703Y442097D01*
G01X1594877Y441263D02*
X1599394Y434574D01*
G01X1595703Y442097D02*
X1600476Y435028D01*
G01X1599394Y434574D02*
X1600776Y427782D01*
G01X1600476Y435028D02*
X1601859Y428233D01*
G01X1600776Y427782D02*
X1599794Y422957D01*
G01X1601999Y428020D02*
X1600968Y422957D01*
G01X1599794D02*
X1600084Y421531D01*
G01Y421530D02*
X1600274Y420596D01*
G01X1600968Y422957D02*
X1601307Y421292D01*
G01X1600274Y420596D02*
X1605608Y417064D01*
G01X1601307Y421292D02*
X1606340Y417960D01*
G01X1605608Y417064D02*
X1605858Y416814D01*
G01X1606340Y417960D02*
X1607008Y417291D01*
G01X1605858Y416814D02*
Y403692D01*
G01X1607008Y417291D02*
Y404169D01*
G01X1591304Y436753D02*
X1594892Y434379D01*
G01X1591753Y437837D02*
X1595722Y435209D01*
G01X1594892Y434379D02*
X1595706Y433149D01*
G01X1595722Y435209D02*
X1596789Y433598D01*
G01X1595706Y433149D02*
X1596888Y427341D01*
G01X1596789Y433598D02*
X1598062Y427341D01*
G01X1596888D02*
X1595918Y422573D01*
G01X1598062Y427341D02*
X1597092Y422573D01*
G01X1595918D02*
X1597066Y416933D01*
G01X1597092Y422573D02*
X1598098Y417629D01*
G01X1597066Y416933D02*
X1599222Y415505D01*
G01X1598098Y417629D02*
X1600254Y416201D01*
G01X1599222Y415505D02*
X1600180Y410798D01*
G01X1600254Y416201D02*
X1601354Y410798D01*
G01X1600180D02*
X1599236Y406156D01*
G01X1601354Y410798D02*
X1600319Y405707D01*
G01X1591753Y437837D02*
X1595722Y435209D01*
G01X1591304Y436753D02*
X1594892Y434379D01*
G01X1595722Y435209D02*
X1596789Y433598D01*
G01X1594892Y434379D02*
X1595706Y433149D01*
G01X1596789Y433598D02*
X1598062Y427341D01*
G01X1595706Y433149D02*
X1596888Y427341D01*
G01X1598062D02*
X1597092Y422573D01*
G01X1596888Y427341D02*
X1595918Y422573D01*
G01X1597092D02*
X1598098Y417629D01*
G01X1595918Y422573D02*
X1597066Y416933D01*
G01X1598098Y417629D02*
X1600254Y416201D01*
G01X1597066Y416933D02*
X1599222Y415505D01*
G01X1600254Y416201D02*
X1601354Y410798D01*
G01X1599222Y415505D02*
X1600180Y410798D01*
G01X1601354D02*
X1600319Y405707D01*
G01X1600180Y410798D02*
X1599236Y406156D01*
G01X1624625Y404095D02*
X1621050Y407670D01*
G01X1625775Y404572D02*
X1622200Y408147D01*
G01X1621050Y407670D02*
Y410223D01*
G01X1622200Y408147D02*
Y410700D01*
G01X1621050Y410223D02*
X1617324Y413949D01*
G01X1622200Y410700D02*
X1618474Y414426D01*
G01X1617324Y413949D02*
Y424173D01*
G01X1618474Y414426D02*
Y424650D01*
G01X1617324Y424173D02*
X1614775Y426722D01*
G01X1618474Y424650D02*
X1615925Y427199D01*
G01X1614775Y426722D02*
Y446896D01*
G01X1615925Y427199D02*
Y447373D01*
G01X1614775Y446896D02*
X1613146Y448525D01*
G01X1615925Y447373D02*
X1613623Y449675D01*
G01X1613146Y448525D02*
X1608240D01*
G01X1613623Y449675D02*
X1608717D01*
G01X1608240Y448525D02*
X1607231Y449534D01*
G01X1605357Y451408D02*
X1604403Y452362D01*
G01X1602529Y454236D02*
X1601574Y455191D01*
G01X1599700Y457065D02*
X1598746Y458019D01*
G01X1596872Y459893D02*
X1591241Y465524D01*
G01X1608717Y449675D02*
X1592054Y466338D01*
G01X1627125Y405567D02*
X1623942Y408750D01*
G01X1628275Y406044D02*
X1625092Y409227D01*
G01X1623942Y408750D02*
Y428007D01*
G01X1625092Y409227D02*
Y428484D01*
G01X1623942Y428007D02*
X1622266Y429683D01*
G01X1625092Y428484D02*
X1622743Y430833D01*
G01X1622266Y429683D02*
X1619126D01*
G01X1622743Y430833D02*
X1619603D01*
G01X1619126Y429683D02*
X1617309Y431500D01*
G01X1619603Y430833D02*
X1618460Y431976D01*
G01X1617309Y431500D02*
Y432452D01*
G01X1617310Y432453D02*
Y447898D01*
G01X1618460Y431976D02*
Y448375D01*
G01X1617310Y447898D02*
X1614183Y451025D01*
G01X1618460Y448375D02*
X1614660Y452175D01*
G01X1614183Y451025D02*
X1609884D01*
G01X1614660Y452175D02*
X1610361D01*
G01X1609884Y451025D02*
X1607749Y453159D01*
G01X1610361Y452175D02*
X1608899Y453637D01*
G01X1607749Y453159D02*
Y455564D01*
G01X1608899Y453637D02*
Y456041D01*
G01X1607749Y455564D02*
X1605940Y457373D01*
G01X1604066Y459247D02*
X1603111Y460202D01*
G01X1601237Y462076D02*
X1600283Y463030D01*
G01X1608899Y456041D02*
X1595103Y469837D01*
G01X1625775Y404572D02*
X1622200Y408147D01*
G01X1624625Y404095D02*
X1621050Y407670D01*
G01X1622200Y408147D02*
Y410700D01*
G01X1621050Y407670D02*
Y410223D01*
G01X1622200Y410700D02*
X1618474Y414426D01*
G01X1621050Y410223D02*
X1617324Y413949D01*
G01X1618474Y414426D02*
Y424650D01*
G01X1617324Y413949D02*
Y424173D01*
G01X1618474Y424650D02*
X1615925Y427199D01*
G01X1617324Y424173D02*
X1614775Y426722D01*
G01X1615925Y427199D02*
Y447373D01*
G01X1614775Y426722D02*
Y446896D01*
G01X1615925Y447373D02*
X1613623Y449675D01*
G01X1614775Y446896D02*
X1613146Y448525D01*
G01X1613623Y449675D02*
X1608717D01*
G01X1613146Y448525D02*
X1608240D01*
G01X1608717Y449675D02*
X1592054Y466338D01*
G01X1608240Y448525D02*
X1607231Y449534D01*
G01X1608717Y449675D02*
X1592054Y466338D01*
G01X1605357Y451408D02*
X1604403Y452362D01*
G01X1608717Y449675D02*
X1592054Y466338D01*
G01X1602529Y454236D02*
X1601574Y455191D01*
G01X1608717Y449675D02*
X1592054Y466338D01*
G01X1599700Y457065D02*
X1598746Y458019D01*
G01X1608717Y449675D02*
X1592054Y466338D01*
G01X1596872Y459893D02*
X1591241Y465524D01*
G01X1628275Y406044D02*
X1625092Y409227D01*
G01X1627125Y405567D02*
X1623942Y408750D01*
G01X1625092Y409227D02*
Y428484D01*
G01X1623942Y408750D02*
Y428007D01*
G01X1625092Y428484D02*
X1622743Y430833D01*
G01X1623942Y428007D02*
X1622266Y429683D01*
G01X1622743Y430833D02*
X1619603D01*
G01X1622266Y429683D02*
X1619126D01*
G01X1619603Y430833D02*
X1618460Y431976D01*
G01X1619126Y429683D02*
X1617309Y431500D01*
G01X1618460Y431976D02*
Y448375D01*
G01X1617309Y431500D02*
Y432452D01*
G01X1618460Y431976D02*
Y448375D01*
G01X1617310Y432453D02*
Y447898D01*
G01X1618460Y448375D02*
X1614660Y452175D01*
G01X1617310Y447898D02*
X1614183Y451025D01*
G01X1614660Y452175D02*
X1610361D01*
G01X1614183Y451025D02*
X1609884D01*
G01X1610361Y452175D02*
X1608899Y453637D01*
G01X1609884Y451025D02*
X1607749Y453159D01*
G01X1608899Y453637D02*
Y456041D01*
G01X1607749Y453159D02*
Y455564D01*
G01X1608899Y456041D02*
X1595103Y469837D01*
G01X1607749Y455564D02*
X1605940Y457373D01*
G01X1608899Y456041D02*
X1595103Y469837D01*
G01X1604066Y459247D02*
X1603111Y460202D01*
G01X1608899Y456041D02*
X1595103Y469837D01*
G01X1601237Y462076D02*
X1600283Y463030D01*
G01X1608899Y456041D02*
X1595103Y469837D01*
G01X1608899Y456041D02*
X1595103Y469837D01*
G01X1614824Y403504D02*
Y423136D01*
G01X1615974Y403981D02*
Y423613D01*
G01X1614824Y423136D02*
X1612464Y425496D01*
G01X1615974Y423613D02*
X1612941Y426646D01*
G01X1612464Y425496D02*
X1611526D01*
G01X1612941Y426646D02*
X1612003D01*
G01X1611526Y425496D02*
X1608575Y428447D01*
G01X1612003Y426646D02*
X1609725Y428924D01*
G01X1608575Y428447D02*
Y441974D01*
G01X1609725Y428924D02*
Y442452D01*
G01X1608575Y441974D02*
X1599739Y450810D01*
G01X1609725Y442452D02*
X1607190Y444987D01*
G01X1608575Y441974D02*
X1599739Y450810D01*
G01X1605316Y446861D02*
X1604361Y447816D01*
G01X1608575Y441974D02*
X1599739Y450810D01*
G01X1602431Y449746D02*
X1600217Y451960D01*
G01X1599739Y450810D02*
X1596519D01*
G01X1600217Y451960D02*
X1596996D01*
G01X1596519Y450810D02*
X1591066Y456263D01*
G01X1596996Y451960D02*
X1592216Y456740D01*
G01X1591066Y456263D02*
Y459483D01*
G01X1592216Y456740D02*
Y459960D01*
G01X1593533Y448538D02*
X1605475Y436596D01*
G01X1594010Y449688D02*
X1606625Y437073D01*
G01X1605475Y436596D02*
Y421816D01*
G01X1606625Y437073D02*
Y422293D01*
G01X1605475Y421816D02*
X1609087Y418204D01*
G01X1606625Y422293D02*
X1610237Y418681D01*
G01X1609087Y418204D02*
Y404856D01*
G01X1610237Y418681D02*
Y405333D01*
G01X1594010Y449688D02*
X1606625Y437073D01*
G01X1593533Y448538D02*
X1605475Y436596D01*
G01X1606625Y437073D02*
Y422293D01*
G01X1605475Y436596D02*
Y421816D01*
G01X1606625Y422293D02*
X1610237Y418681D01*
G01X1605475Y421816D02*
X1609087Y418204D01*
G01X1610237Y418681D02*
Y405333D01*
G01X1609087Y418204D02*
Y404856D01*
G01X1632783Y405366D02*
X1627145Y411004D01*
G01X1633933Y405843D02*
X1628295Y411481D01*
G01X1627145Y411004D02*
Y430729D01*
G01X1628295Y411481D02*
Y431206D01*
G01X1627145Y430729D02*
X1623342Y434532D01*
G01X1628295Y431206D02*
X1624492Y435009D01*
G01X1623342Y434532D02*
Y452257D01*
G01X1624492Y435009D02*
Y452734D01*
G01X1623342Y452257D02*
X1620349Y455250D01*
G01X1624492Y452734D02*
X1620826Y456400D01*
G01X1620349Y455250D02*
X1615100D01*
G01X1620826Y456400D02*
X1615577D01*
G01X1615100Y455250D02*
X1612250Y458100D01*
G01X1615577Y456400D02*
X1612727Y459250D01*
G01X1612250Y458100D02*
X1609892D01*
G01X1612727Y459250D02*
X1610369D01*
G01X1609892Y458100D02*
X1606644Y461348D01*
G01X1610369Y459250D02*
X1607794Y461825D01*
G01X1606644Y461348D02*
Y468844D01*
G01X1607794Y461825D02*
Y464367D01*
G01X1606644Y461348D02*
Y468844D01*
G01X1633933Y405843D02*
X1628295Y411481D01*
G01X1632783Y405366D02*
X1627145Y411004D01*
G01X1628295Y411481D02*
Y431206D01*
G01X1627145Y411004D02*
Y430729D01*
G01X1628295Y431206D02*
X1624492Y435009D01*
G01X1627145Y430729D02*
X1623342Y434532D01*
G01X1624492Y435009D02*
Y452734D01*
G01X1623342Y434532D02*
Y452257D01*
G01X1624492Y452734D02*
X1620826Y456400D01*
G01X1623342Y452257D02*
X1620349Y455250D01*
G01X1620826Y456400D02*
X1615577D01*
G01X1620349Y455250D02*
X1615100D01*
G01X1615577Y456400D02*
X1612727Y459250D01*
G01X1615100Y455250D02*
X1612250Y458100D01*
G01X1612727Y459250D02*
X1610369D01*
G01X1612250Y458100D02*
X1609892D01*
G01X1610369Y459250D02*
X1607794Y461825D01*
G01X1609892Y458100D02*
X1606644Y461348D01*
G01X1607794Y461825D02*
Y464367D01*
G01X1606644Y461348D02*
Y468844D01*
G01X1625344Y466463D02*
X1630257Y461550D01*
G01X1624867Y465313D02*
X1629780Y460400D01*
G01X1630257Y461550D02*
X1632338D01*
G01X1629780Y460400D02*
X1631861D01*
G01X1632338Y461550D02*
X1634650Y459238D01*
G01X1631861Y460400D02*
X1633500Y458761D01*
G01X1634650Y459238D02*
Y439350D01*
G01X1633500Y458761D02*
Y438873D01*
G01X1634650Y439350D02*
X1636575Y437425D01*
G01X1633500Y438873D02*
X1635425Y436948D01*
G01X1636575Y437425D02*
Y430252D01*
G01X1635425Y436948D02*
Y429775D01*
G01X1636575Y430252D02*
X1641800Y425027D01*
G01X1635425Y429775D02*
X1640650Y424550D01*
G01X1624867Y465313D02*
X1629780Y460400D01*
G01X1625344Y466463D02*
X1630257Y461550D01*
G01X1629780Y460400D02*
X1631861D01*
G01X1630257Y461550D02*
X1632338D01*
G01X1631861Y460400D02*
X1633500Y458761D01*
G01X1632338Y461550D02*
X1634650Y459238D01*
G01X1633500Y458761D02*
Y438873D01*
G01X1634650Y459238D02*
Y439350D01*
G01X1633500Y438873D02*
X1635425Y436948D01*
G01X1634650Y439350D02*
X1636575Y437425D01*
G01X1635425Y436948D02*
Y429775D01*
G01X1636575Y437425D02*
Y430252D01*
G01X1635425Y429775D02*
X1640650Y424550D01*
G01X1636575Y430252D02*
X1641800Y425027D01*
G01X1617448Y469104D02*
Y461555D01*
G01X1618598Y468936D02*
Y462032D01*
G01X1617448Y461555D02*
X1620153Y458850D01*
G01X1618598Y462032D02*
X1620630Y460000D01*
G01X1620153Y458850D02*
X1622022D01*
G01X1620630Y460000D02*
X1622499D01*
G01X1622022Y458850D02*
X1626500Y454372D01*
G01X1622499Y460000D02*
X1627650Y454849D01*
G01X1626500Y454372D02*
Y436000D01*
G01X1627650Y454849D02*
Y436477D01*
G01X1626500Y436000D02*
X1632325Y430175D01*
G01X1627650Y436477D02*
X1633475Y430652D01*
G01X1632325Y430175D02*
Y428448D01*
G01X1633475Y430652D02*
Y428925D01*
G01X1632325Y428448D02*
X1636400Y424373D01*
G01X1633475Y428925D02*
X1637550Y424850D01*
G01D02*
Y418177D01*
G01Y415527D02*
Y414177D01*
G01Y411527D02*
Y410177D01*
G01X1618598Y468936D02*
Y462032D01*
G01X1617448Y469104D02*
Y461555D01*
G01X1618598Y462032D02*
X1620630Y460000D01*
G01X1617448Y461555D02*
X1620153Y458850D01*
G01X1620630Y460000D02*
X1622499D01*
G01X1620153Y458850D02*
X1622022D01*
G01X1622499Y460000D02*
X1627650Y454849D01*
G01X1622022Y458850D02*
X1626500Y454372D01*
G01X1627650Y454849D02*
Y436477D01*
G01X1626500Y454372D02*
Y436000D01*
G01X1627650Y436477D02*
X1633475Y430652D01*
G01X1626500Y436000D02*
X1632325Y430175D01*
G01X1633475Y430652D02*
Y428925D01*
G01X1632325Y430175D02*
Y428448D01*
G01X1633475Y428925D02*
X1637550Y424850D01*
G01X1632325Y428448D02*
X1636400Y424373D01*
G01X1637550Y424850D02*
Y418177D01*
G01Y415527D02*
Y414177D01*
G01Y411527D02*
Y410177D01*
G01X1636690Y466700D02*
X1632340D01*
G01X1637167Y467850D02*
X1632817D01*
G01X1632340Y466700D02*
X1629158Y469882D01*
G01X1632817Y467850D02*
X1630308Y470359D01*
G01X1629158Y469882D02*
Y473453D01*
G01X1630308Y470359D02*
Y473930D01*
G01X1629158Y473453D02*
X1618361Y484250D01*
G01X1630308Y473930D02*
X1618838Y485400D01*
G01X1590049Y487650D02*
X1591249Y488850D01*
G01X1589572Y488800D02*
X1590772Y490000D01*
G01X1591249Y488850D02*
X1606923D01*
G01X1590772Y490000D02*
X1607400D01*
G01X1606923Y488850D02*
X1608886Y486887D01*
G01X1607400Y490000D02*
X1609363Y488037D01*
G01X1608886Y486887D02*
X1619556D01*
G01X1609363Y488037D02*
X1620033D01*
G01X1619556Y486887D02*
X1629724Y476719D01*
G01X1620033Y488037D02*
X1630201Y477869D01*
G01X1629724Y476719D02*
X1632081D01*
G01X1630201Y477869D02*
X1632558D01*
G01X1632081Y476719D02*
X1637054Y471746D01*
G01X1638009Y469872D02*
X1638928D01*
G01D02*
X1639883Y468917D01*
G01X1640837Y467044D02*
X1641756D01*
G01D02*
X1642711Y466089D01*
G01X1592050Y493450D02*
X1592483Y493017D01*
G01X1591573Y492300D02*
X1592006Y491867D01*
G01X1592483Y493017D02*
X1618748D01*
G01X1592006Y491867D02*
X1618271D01*
G01X1618748Y493017D02*
X1630965Y480800D01*
G01X1618271Y491867D02*
X1630488Y479650D01*
G01X1630965Y480800D02*
X1639543D01*
G01X1630488Y479650D02*
X1639066D01*
G01X1639543Y480800D02*
X1642086Y478257D01*
G01X1639066Y479650D02*
X1640936Y477780D01*
G01X1642086Y478257D02*
Y474614D01*
G01X1640936Y477780D02*
Y474137D01*
G01X1642086Y474614D02*
X1656100Y460600D01*
G01X1640936Y474137D02*
X1643636Y471437D01*
G01X1642086Y474614D02*
X1656100Y460600D01*
G01X1645510Y469563D02*
X1646465Y468608D01*
G01X1642086Y474614D02*
X1656100Y460600D01*
G01X1648338Y466735D02*
X1649293Y465780D01*
G01X1642086Y474614D02*
X1656100Y460600D01*
G01X1642086Y474614D02*
X1656100Y460600D01*
G01X1637167Y467850D02*
X1632817D01*
G01X1636690Y466700D02*
X1632340D01*
G01X1632817Y467850D02*
X1630308Y470359D01*
G01X1632340Y466700D02*
X1629158Y469882D01*
G01X1630308Y470359D02*
Y473930D01*
G01X1629158Y469882D02*
Y473453D01*
G01X1630308Y473930D02*
X1618838Y485400D01*
G01X1629158Y473453D02*
X1618361Y484250D01*
G01X1589572Y488800D02*
X1590772Y490000D01*
G01X1590049Y487650D02*
X1591249Y488850D01*
G01X1590772Y490000D02*
X1607400D01*
G01X1591249Y488850D02*
X1606923D01*
G01X1607400Y490000D02*
X1609363Y488037D01*
G01X1606923Y488850D02*
X1608886Y486887D01*
G01X1609363Y488037D02*
X1620033D01*
G01X1608886Y486887D02*
X1619556D01*
G01X1620033Y488037D02*
X1630201Y477869D01*
G01X1619556Y486887D02*
X1629724Y476719D01*
G01X1630201Y477869D02*
X1632558D01*
G01X1629724Y476719D02*
X1632081D01*
G01D02*
X1637054Y471746D01*
G01X1638009Y469872D02*
X1638928D01*
G01D02*
X1639883Y468917D01*
G01X1640837Y467044D02*
X1641756D01*
G01D02*
X1642711Y466089D01*
G01X1591573Y492300D02*
X1592006Y491867D01*
G01X1592050Y493450D02*
X1592483Y493017D01*
G01X1592006Y491867D02*
X1618271D01*
G01X1592483Y493017D02*
X1618748D01*
G01X1618271Y491867D02*
X1630488Y479650D01*
G01X1618748Y493017D02*
X1630965Y480800D01*
G01X1630488Y479650D02*
X1639066D01*
G01X1630965Y480800D02*
X1639543D01*
G01X1639066Y479650D02*
X1640936Y477780D01*
G01X1639543Y480800D02*
X1642086Y478257D01*
G01X1640936Y477780D02*
Y474137D01*
G01X1642086Y478257D02*
Y474614D01*
G01X1640936Y474137D02*
X1643636Y471437D01*
G01X1645510Y469563D02*
X1646465Y468608D01*
G01X1648338Y466735D02*
X1649293Y465780D01*
G01X1642086Y474614D02*
X1656100Y460600D01*
G01X1607879Y481150D02*
X1610967D01*
G01X1611444Y482300D02*
X1614405Y479339D01*
G01X1610967Y481150D02*
X1613928Y478189D01*
G01X1614405Y479339D02*
X1620514D01*
G01X1613928Y478189D02*
X1620037D01*
G01X1620514Y479339D02*
X1627064Y472789D01*
G01X1620037Y478189D02*
X1625914Y472312D01*
G01X1627064Y472789D02*
Y469218D01*
G01X1625914Y472312D02*
Y468741D01*
G01X1631532Y464750D02*
X1633764D01*
G01X1607879Y481150D02*
X1610967D01*
G01D02*
X1613928Y478189D01*
G01X1611444Y482300D02*
X1614405Y479339D01*
G01X1613928Y478189D02*
X1620037D01*
G01X1614405Y479339D02*
X1620514D01*
G01X1620037Y478189D02*
X1625914Y472312D01*
G01X1620514Y479339D02*
X1627064Y472789D01*
G01X1625914Y472312D02*
Y468741D01*
G01X1627064Y472789D02*
Y469218D01*
G01X1631532Y464750D02*
X1633764D01*
G01X1598409Y464904D02*
X1597454Y465859D01*
G01X1595581Y467732D02*
X1594626Y468687D01*
G01X1598409Y464904D02*
X1597454Y465859D01*
G01X1595581Y467732D02*
X1594626Y468687D01*
G01X1626820Y507950D02*
X1592769D01*
G01X1592292Y506800D02*
X1626343D01*
G01X1629649Y505121D02*
X1626820Y507950D01*
G01X1626343Y506800D02*
X1629172Y503971D01*
G01X1638374Y505121D02*
X1629649D01*
G01X1629172Y503971D02*
X1637897D01*
G01X1640976Y502519D02*
X1638374Y505121D01*
G01X1637897Y503971D02*
X1640499Y501369D01*
G01X1656225Y502519D02*
X1640976D01*
G01X1640499Y501369D02*
X1655748D01*
G01X1640499D02*
X1655748D01*
G01X1656225Y502519D02*
X1640976D01*
G01X1637897Y503971D02*
X1640499Y501369D01*
G01X1640976Y502519D02*
X1638374Y505121D01*
G01X1629172Y503971D02*
X1637897D01*
G01X1638374Y505121D02*
X1629649D01*
G01X1626343Y506800D02*
X1629172Y503971D01*
G01X1629649Y505121D02*
X1626820Y507950D01*
G01X1592292Y506800D02*
X1626343D01*
G01X1626820Y507950D02*
X1592769D01*
G01X1655282Y499925D02*
X1638183D01*
G01X1655282D02*
X1638183D01*
G01X1648682Y498775D02*
X1647332D01*
G01X1655282Y499925D02*
X1638183D01*
G01X1644682Y498775D02*
X1643332D01*
G01X1655282Y499925D02*
X1638183D01*
G01X1640682Y498775D02*
X1637706D01*
G01X1638183Y499925D02*
X1635589Y502519D01*
G01X1637706Y498775D02*
X1635112Y501369D01*
G01X1635589Y502519D02*
X1628650D01*
G01X1635112Y501369D02*
X1628173D01*
G01X1628650Y502519D02*
X1625719Y505450D01*
G01X1628173Y501369D02*
X1625242Y504300D01*
G01X1625719Y505450D02*
X1591662D01*
G01X1625242Y504300D02*
X1591185D01*
G01X1648682Y498775D02*
X1647332D01*
G01X1644682D02*
X1643332D01*
G01X1640682D02*
X1637706D01*
G01X1655282Y499925D02*
X1638183D01*
G01X1637706Y498775D02*
X1635112Y501369D01*
G01X1638183Y499925D02*
X1635589Y502519D01*
G01X1635112Y501369D02*
X1628173D01*
G01X1635589Y502519D02*
X1628650D01*
G01X1628173Y501369D02*
X1625242Y504300D01*
G01X1628650Y502519D02*
X1625719Y505450D01*
G01X1625242Y504300D02*
X1591185D01*
G01X1625719Y505450D02*
X1591662D01*
G01X1607794Y467017D02*
Y468367D01*
G01X1606644Y468844D02*
X1610482Y472682D01*
G01X1607794Y468367D02*
X1610959Y471532D01*
G01X1610482Y472682D02*
X1614656D01*
G01X1610959Y471532D02*
X1615133D01*
G01X1614656Y472682D02*
X1615232Y473258D01*
G01X1615133Y471532D02*
X1616382Y472781D01*
G01X1615232Y473258D02*
Y474738D01*
G01X1616382Y472781D02*
Y474639D01*
G01X1607794Y467017D02*
Y468367D01*
G01D02*
X1610959Y471532D01*
G01X1606644Y468844D02*
X1610482Y472682D01*
G01X1610959Y471532D02*
X1615133D01*
G01X1610482Y472682D02*
X1614656D01*
G01X1615133Y471532D02*
X1616382Y472781D01*
G01X1614656Y472682D02*
X1615232Y473258D01*
G01X1616382Y472781D02*
Y474639D01*
G01X1615232Y473258D02*
Y474738D01*
G01X1624301Y466463D02*
X1625344D01*
G01X1624160Y465313D02*
X1624867D01*
G01X1624160D02*
X1624867D01*
G01X1624301Y466463D02*
X1625344D01*
G01X1589890Y501200D02*
X1623885D01*
G01X1590367Y502350D02*
X1624362D01*
G01X1623885Y501200D02*
X1626846Y498239D01*
G01X1624362Y502350D02*
X1627323Y499389D01*
G01X1626846Y498239D02*
X1631633D01*
G01X1627323Y499389D02*
X1632110D01*
G01X1631633Y498239D02*
X1636208Y493664D01*
G01X1632110Y499389D02*
X1636685Y494814D01*
G01X1636208Y493664D02*
X1639370D01*
G01X1636685Y494814D02*
X1639847D01*
G01X1639370Y493664D02*
X1640136Y492898D01*
G01X1639847Y494814D02*
X1640613Y494048D01*
G01X1640136Y492898D02*
X1644703D01*
G01X1640613Y494048D02*
X1645180D01*
G01X1644703Y492898D02*
X1646574Y491027D01*
G01X1645180Y494048D02*
X1647724Y491504D01*
G01X1646574Y491027D02*
Y482927D01*
G01X1647724Y491504D02*
Y483404D01*
G01X1646574Y482927D02*
X1648580Y480921D01*
G01X1647724Y483404D02*
X1649730Y481398D01*
G01X1648580Y480921D02*
Y476558D01*
G01X1649730Y481398D02*
Y477035D01*
G01X1648580Y476558D02*
X1665864Y459274D01*
G01X1649730Y477035D02*
X1667014Y459751D01*
G01X1590367Y502350D02*
X1624362D01*
G01X1589890Y501200D02*
X1623885D01*
G01X1624362Y502350D02*
X1627323Y499389D01*
G01X1623885Y501200D02*
X1626846Y498239D01*
G01X1627323Y499389D02*
X1632110D01*
G01X1626846Y498239D02*
X1631633D01*
G01X1632110Y499389D02*
X1636685Y494814D01*
G01X1631633Y498239D02*
X1636208Y493664D01*
G01X1636685Y494814D02*
X1639847D01*
G01X1636208Y493664D02*
X1639370D01*
G01X1639847Y494814D02*
X1640613Y494048D01*
G01X1639370Y493664D02*
X1640136Y492898D01*
G01X1640613Y494048D02*
X1645180D01*
G01X1640136Y492898D02*
X1644703D01*
G01X1645180Y494048D02*
X1647724Y491504D01*
G01X1644703Y492898D02*
X1646574Y491027D01*
G01X1647724Y491504D02*
Y483404D01*
G01X1646574Y491027D02*
Y482927D01*
G01X1647724Y483404D02*
X1649730Y481398D01*
G01X1646574Y482927D02*
X1648580Y480921D01*
G01X1649730Y481398D02*
Y477035D01*
G01X1648580Y480921D02*
Y476558D01*
G01X1649730Y477035D02*
X1667014Y459751D01*
G01X1648580Y476558D02*
X1665864Y459274D01*
G01X1657945Y461715D02*
X1644036Y475624D01*
G01X1659095Y462192D02*
X1645186Y476101D01*
G01X1644036Y475624D02*
Y479065D01*
G01X1645186Y476101D02*
Y479542D01*
G01X1644036Y479065D02*
X1640327Y482774D01*
G01X1645186Y479542D02*
X1640804Y483924D01*
G01X1640327Y482774D02*
X1631811D01*
G01X1640804Y483924D02*
X1632288D01*
G01X1631811Y482774D02*
X1619534Y495051D01*
G01X1632288Y483924D02*
X1620011Y496201D01*
G01X1619534Y495051D02*
X1607722D01*
G01X1620011Y496201D02*
X1612199D01*
G01X1619534Y495051D02*
X1607722D01*
G01X1609549Y496201D02*
X1608199D01*
G01X1607722Y495051D02*
X1604673Y498100D01*
G01X1608199Y496201D02*
X1605150Y499250D01*
G01X1604673Y498100D02*
X1591460D01*
G01X1605150Y499250D02*
X1590983D01*
G01X1591460Y498100D02*
X1591100Y497740D01*
G01X1590983Y499250D02*
X1589950Y498217D01*
G01X1591100Y497740D02*
Y497471D01*
G01X1589950Y498217D02*
Y497540D01*
G01X1659095Y462192D02*
X1645186Y476101D01*
G01X1657945Y461715D02*
X1644036Y475624D01*
G01X1645186Y476101D02*
Y479542D01*
G01X1644036Y475624D02*
Y479065D01*
G01X1645186Y479542D02*
X1640804Y483924D01*
G01X1644036Y479065D02*
X1640327Y482774D01*
G01X1640804Y483924D02*
X1632288D01*
G01X1640327Y482774D02*
X1631811D01*
G01X1632288Y483924D02*
X1620011Y496201D01*
G01X1631811Y482774D02*
X1619534Y495051D01*
G01X1620011Y496201D02*
X1612199D01*
G01X1609549D02*
X1608199D01*
G01X1619534Y495051D02*
X1607722D01*
G01X1608199Y496201D02*
X1605150Y499250D01*
G01X1607722Y495051D02*
X1604673Y498100D01*
G01X1605150Y499250D02*
X1590983D01*
G01X1604673Y498100D02*
X1591460D01*
G01X1590983Y499250D02*
X1589950Y498217D01*
G01X1591460Y498100D02*
X1591100Y497740D01*
G01X1589950Y498217D02*
Y497540D01*
G01X1591100Y497740D02*
Y497471D01*
G01X1595540Y543603D02*
X1621935Y538413D01*
G01X1595652Y544753D02*
X1621916Y539589D01*
G01X1621935Y538413D02*
X1634593Y541334D01*
G01X1621916Y539589D02*
X1634591Y542514D01*
G01X1634593Y541334D02*
X1640208Y540062D01*
G01X1634591Y542514D02*
X1640200Y541243D01*
G01X1640208Y540062D02*
X1642209Y540542D01*
G01D02*
X1642210D01*
G01X1640200Y541243D02*
X1642315Y541751D01*
G01X1642209Y540542D02*
X1642210D01*
G01D02*
X1654721Y535085D01*
G01X1642316Y541751D02*
X1655533Y535988D01*
G01X1595782Y546109D02*
X1621719Y541009D01*
G01X1595897Y547259D02*
X1621703Y542185D01*
G01X1621722Y541009D02*
X1634425Y543942D01*
G01X1621703Y542185D02*
X1634423Y545122D01*
G01X1634426Y543942D02*
X1640192Y542633D01*
G01X1634423Y545122D02*
X1640184Y543815D01*
G01X1640192Y542633D02*
X1642465Y543180D01*
G01X1640184Y543815D02*
X1642571Y544389D01*
G01X1642465Y543180D02*
X1656490Y537064D01*
G01X1642571Y544389D02*
X1657303Y537965D01*
G01X1596511Y553627D02*
X1621592Y548696D01*
G01X1596620Y554778D02*
X1621573Y549872D01*
G01X1621595Y548696D02*
X1634411Y551654D01*
G01X1621573Y549872D02*
X1634409Y552834D01*
G01X1634411Y551654D02*
X1640141Y550353D01*
G01X1634409Y552834D02*
X1640133Y551535D01*
G01X1640141Y550353D02*
X1643157Y551080D01*
G01X1640133Y551535D02*
X1643263Y552289D01*
G01X1643157Y551080D02*
X1674030Y537618D01*
G01X1643263Y552289D02*
X1674366Y538727D01*
G01X1643157Y551080D02*
X1674030Y537618D01*
G01X1654305Y553532D02*
X1646406Y555624D01*
G01X1654294Y552345D02*
X1646393Y554437D01*
G01X1646406Y555624D02*
X1640116Y554109D01*
G01X1646393Y554437D02*
X1640124Y552928D01*
G01X1640116Y554109D02*
X1634401Y555404D01*
G01X1640124Y552928D02*
X1634403Y554224D01*
G01X1634401Y555404D02*
X1621535Y552434D01*
G01X1634403Y554224D02*
X1621554Y551258D01*
G01X1621535Y552434D02*
X1596699Y557317D01*
G01X1621554Y551258D02*
X1596587Y556167D01*
G01X1599914Y576042D02*
X1602867Y574820D01*
G01X1600030Y577239D02*
X1603096Y575970D01*
G01X1602867Y574820D02*
X1608665D01*
G01X1603096Y575970D02*
X1608188D01*
G01X1608665Y574820D02*
X1612595Y578750D01*
G01X1608188Y575970D02*
X1612118Y579900D01*
G01X1612595Y578750D02*
X1623323D01*
G01X1612118Y579900D02*
X1623800D01*
G01X1623323Y578750D02*
X1627253Y574820D01*
G01X1623800Y579900D02*
X1627730Y575970D01*
G01X1627253Y574820D02*
X1643852D01*
G01X1627730Y575970D02*
X1644082D01*
G01X1643853Y574819D02*
X1646243Y573828D01*
G01X1644082Y575970D02*
X1646895Y574804D01*
G01X1646243Y573828D02*
X1647921Y572150D01*
G01X1646895Y574804D02*
X1648897Y572802D01*
G01X1647921Y572150D02*
X1649550Y568222D01*
G01X1648897Y572802D02*
X1650700Y568451D01*
G01X1649550Y568222D02*
Y560724D01*
G01D02*
X1652326Y557947D01*
G01X1591735Y582833D02*
X1598784Y585752D01*
G01X1591852Y581636D02*
X1599013Y584602D01*
G01X1598784Y585752D02*
X1606950D01*
G01X1599013Y584602D02*
X1606721D01*
G01X1606950Y585752D02*
X1614476Y582635D01*
G01X1606721Y584602D02*
X1614247Y581485D01*
G01X1614476Y582635D02*
X1616744D01*
G01X1614247Y581485D02*
X1617221D01*
G01X1616744Y582635D02*
X1624990Y590881D01*
G01X1617221Y581485D02*
X1625467Y589731D01*
G01X1643573Y590881D02*
X1655997Y585733D01*
G01X1643344Y589731D02*
X1655433Y584721D01*
G01X1596266Y551122D02*
X1621640Y546133D01*
G01X1596381Y552272D02*
X1621621Y547309D01*
G01X1621640Y546133D02*
X1634416Y549083D01*
G01X1621621Y547309D02*
X1634414Y550263D01*
G01X1634416Y549083D02*
X1640153Y547781D01*
G01X1634414Y550263D02*
X1640148Y548962D01*
G01X1640155Y547780D02*
X1642926Y548445D01*
G01Y548446D02*
X1642927D01*
G01X1640148Y548962D02*
X1643033Y549655D01*
G01X1642926Y548446D02*
X1642927D01*
G01D02*
X1665424Y538635D01*
G01X1643033Y549655D02*
X1665978Y539649D01*
G01X1596027Y548615D02*
X1621678Y543572D01*
G01X1596141Y549765D02*
X1621659Y544748D01*
G01X1621678Y543572D02*
X1634418Y546512D01*
G01X1621659Y544748D02*
X1634416Y547692D01*
G01X1634418Y546512D02*
X1640175Y545206D01*
G01X1634418Y547692D02*
X1640167Y546388D01*
G01X1640175Y545206D02*
X1642697Y545813D01*
G01X1640167Y546388D02*
X1642803Y547022D01*
G01X1642697Y545813D02*
X1658280Y539015D01*
G01X1642803Y547022D02*
X1659095Y539915D01*
G01X1595652Y544753D02*
X1621916Y539589D01*
G01X1595540Y543603D02*
X1621935Y538413D01*
G01X1621916Y539589D02*
X1634591Y542514D01*
G01X1621935Y538413D02*
X1634593Y541334D01*
G01X1634591Y542514D02*
X1640200Y541243D01*
G01X1634593Y541334D02*
X1640208Y540062D01*
G01X1640200Y541243D02*
X1642315Y541751D01*
G01X1640208Y540062D02*
X1642209Y540542D01*
G01X1640200Y541243D02*
X1642315Y541751D01*
G01X1642316D02*
X1655533Y535988D01*
G01X1642209Y540542D02*
X1642210D01*
G01X1642316Y541751D02*
X1655533Y535988D01*
G01X1642210Y540542D02*
X1654721Y535085D01*
G01X1595897Y547259D02*
X1621703Y542185D01*
G01X1595782Y546109D02*
X1621719Y541009D01*
G01X1621703Y542185D02*
X1634423Y545122D01*
G01X1621722Y541009D02*
X1634425Y543942D01*
G01X1634423Y545122D02*
X1640184Y543815D01*
G01X1634426Y543942D02*
X1640192Y542633D01*
G01X1640184Y543815D02*
X1642571Y544389D01*
G01X1640192Y542633D02*
X1642465Y543180D01*
G01X1642571Y544389D02*
X1657303Y537965D01*
G01X1642465Y543180D02*
X1656490Y537064D01*
G01X1596620Y554778D02*
X1621573Y549872D01*
G01X1596511Y553627D02*
X1621592Y548696D01*
G01X1621573Y549872D02*
X1634409Y552834D01*
G01X1621595Y548696D02*
X1634411Y551654D01*
G01X1634409Y552834D02*
X1640133Y551535D01*
G01X1634411Y551654D02*
X1640141Y550353D01*
G01X1640133Y551535D02*
X1643263Y552289D01*
G01X1640141Y550353D02*
X1643157Y551080D01*
G01X1643263Y552289D02*
X1674366Y538727D01*
G01X1643157Y551080D02*
X1674030Y537618D01*
G01X1654294Y552345D02*
X1646393Y554437D01*
G01X1654305Y553532D02*
X1646406Y555624D01*
G01X1646393Y554437D02*
X1640124Y552928D01*
G01X1646406Y555624D02*
X1640116Y554109D01*
G01X1640124Y552928D02*
X1634403Y554224D01*
G01X1640116Y554109D02*
X1634401Y555404D01*
G01X1634403Y554224D02*
X1621554Y551258D01*
G01X1634401Y555404D02*
X1621535Y552434D01*
G01X1621554Y551258D02*
X1596587Y556167D01*
G01X1621535Y552434D02*
X1596699Y557317D01*
G01X1600030Y577239D02*
X1603096Y575970D01*
G01X1599914Y576042D02*
X1602867Y574820D01*
G01X1603096Y575970D02*
X1608188D01*
G01X1602867Y574820D02*
X1608665D01*
G01X1608188Y575970D02*
X1612118Y579900D01*
G01X1608665Y574820D02*
X1612595Y578750D01*
G01X1612118Y579900D02*
X1623800D01*
G01X1612595Y578750D02*
X1623323D01*
G01X1623800Y579900D02*
X1627730Y575970D01*
G01X1623323Y578750D02*
X1627253Y574820D01*
G01X1627730Y575970D02*
X1644082D01*
G01X1627253Y574820D02*
X1643852D01*
G01X1644082Y575970D02*
X1646895Y574804D01*
G01X1643853Y574819D02*
X1646243Y573828D01*
G01X1646895Y574804D02*
X1648897Y572802D01*
G01X1646243Y573828D02*
X1647921Y572150D01*
G01X1648897Y572802D02*
X1650700Y568451D01*
G01X1647921Y572150D02*
X1649550Y568222D01*
G01D02*
Y560724D01*
G01D02*
X1652326Y557947D01*
G01X1591852Y581636D02*
X1599013Y584602D01*
G01X1591735Y582833D02*
X1598784Y585752D01*
G01X1599013Y584602D02*
X1606721D01*
G01X1598784Y585752D02*
X1606950D01*
G01X1606721Y584602D02*
X1614247Y581485D01*
G01X1606950Y585752D02*
X1614476Y582635D01*
G01X1614247Y581485D02*
X1617221D01*
G01X1614476Y582635D02*
X1616744D01*
G01X1617221Y581485D02*
X1625467Y589731D01*
G01X1616744Y582635D02*
X1624990Y590881D01*
G01X1643344Y589731D02*
X1655433Y584721D01*
G01X1643573Y590881D02*
X1655997Y585733D01*
G01X1596381Y552272D02*
X1621621Y547309D01*
G01X1596266Y551122D02*
X1621640Y546133D01*
G01X1621621Y547309D02*
X1634414Y550263D01*
G01X1621640Y546133D02*
X1634416Y549083D01*
G01X1634414Y550263D02*
X1640148Y548962D01*
G01X1634416Y549083D02*
X1640153Y547781D01*
G01X1640148Y548962D02*
X1643033Y549655D01*
G01X1640155Y547780D02*
X1642926Y548445D01*
G01X1640148Y548962D02*
X1643033Y549655D01*
G01D02*
X1665978Y539649D01*
G01X1642926Y548446D02*
X1642927D01*
G01X1643033Y549655D02*
X1665978Y539649D01*
G01X1642927Y548446D02*
X1665424Y538635D01*
G01X1596141Y549765D02*
X1621659Y544748D01*
G01X1596027Y548615D02*
X1621678Y543572D01*
G01X1621659Y544748D02*
X1634416Y547692D01*
G01X1621678Y543572D02*
X1634418Y546512D01*
G01Y547692D02*
X1640167Y546388D01*
G01X1634418Y546512D02*
X1640175Y545206D01*
G01X1640167Y546388D02*
X1642803Y547022D01*
G01X1640175Y545206D02*
X1642697Y545813D01*
G01X1642803Y547022D02*
X1659095Y539915D01*
G01X1642697Y545813D02*
X1658280Y539015D01*
G01X1624990Y590881D02*
X1643573D01*
G01X1625467Y589731D02*
X1643344D01*
G01X1625467D02*
X1643344D01*
G01X1624990Y590881D02*
X1643573D01*
G01X1662848Y221626D02*
X1656178Y214956D01*
G01X1663998Y221149D02*
X1657328Y214479D01*
G01X1656178Y214956D02*
Y212597D01*
G01X1657328Y214479D02*
Y212120D01*
G01X1656178Y212597D02*
X1652025Y208444D01*
G01X1663998Y221149D02*
X1657328Y214479D01*
G01X1662848Y221626D02*
X1656178Y214956D01*
G01X1657328Y214479D02*
Y212120D01*
G01X1656178Y214956D02*
Y212597D01*
G01D02*
X1652025Y208444D01*
G01X1651250Y212786D02*
Y218938D01*
G01Y212786D02*
Y218938D01*
G01X1651247Y276973D02*
Y314626D01*
G01X1652397Y276496D02*
Y314149D01*
G01X1653747Y313471D02*
Y275274D01*
G01X1654897Y312994D02*
Y274797D01*
G01X1653747Y275274D02*
X1651350Y272877D01*
G01X1654897Y274797D02*
X1652500Y272400D01*
G01X1651350Y272877D02*
Y228977D01*
G01X1652500Y272400D02*
Y228500D01*
G01X1661227Y296757D02*
Y256270D01*
G01X1660077Y296280D02*
Y256747D01*
G01X1661227Y256270D02*
X1655000Y250043D01*
G01X1660077Y256747D02*
X1653850Y250520D01*
G01X1655000Y250043D02*
Y227073D01*
G01X1653850Y250520D02*
Y227550D01*
G01X1652397Y276496D02*
Y314149D01*
G01X1651247Y276973D02*
Y314626D01*
G01X1654897Y312994D02*
Y274797D01*
G01X1653747Y313471D02*
Y275274D01*
G01X1654897Y274797D02*
X1652500Y272400D01*
G01X1653747Y275274D02*
X1651350Y272877D01*
G01X1652500Y272400D02*
Y228500D01*
G01X1651350Y272877D02*
Y228977D01*
G01X1660077Y296280D02*
Y256747D01*
G01X1661227Y296757D02*
Y256270D01*
G01X1660077Y256747D02*
X1653850Y250520D01*
G01X1661227Y256270D02*
X1655000Y250043D01*
G01X1653850Y250520D02*
Y227550D01*
G01X1655000Y250043D02*
Y227073D01*
G01X1666296Y313194D02*
Y264355D01*
G01X1667446Y312717D02*
Y264832D01*
G01X1666296Y264355D02*
X1672654Y257997D01*
G01X1667446Y264832D02*
X1673804Y258474D01*
G01X1672654Y257997D02*
Y253840D01*
G01X1673804Y258474D02*
Y253363D01*
G01X1672654Y253840D02*
X1668925Y250111D01*
G01X1673804Y253363D02*
X1670075Y249634D01*
G01X1668925Y250111D02*
Y242211D01*
G01X1670075Y249634D02*
Y241734D01*
G01X1668925Y242211D02*
X1668170Y241456D01*
G01X1670075Y241734D02*
X1669320Y240979D01*
G01X1668170Y241158D02*
X1667102Y240090D01*
G01X1669320Y240681D02*
X1667579Y238940D01*
G01X1666804Y240090D02*
X1662848Y236134D01*
G01X1667579Y238940D02*
X1667281D01*
G01X1666804Y240090D02*
X1662848Y236134D01*
G01X1667281Y238940D02*
X1663998Y235657D01*
G01X1662848Y236134D02*
Y221626D01*
G01X1663998Y235657D02*
Y221149D01*
G01X1667446Y312717D02*
Y264832D01*
G01X1666296Y313194D02*
Y264355D01*
G01X1667446Y264832D02*
X1673804Y258474D01*
G01X1666296Y264355D02*
X1672654Y257997D01*
G01X1673804Y258474D02*
Y253363D01*
G01X1672654Y257997D02*
Y253840D01*
G01X1673804Y253363D02*
X1670075Y249634D01*
G01X1672654Y253840D02*
X1668925Y250111D01*
G01X1670075Y249634D02*
Y241734D01*
G01X1668925Y250111D02*
Y242211D01*
G01X1670075Y241734D02*
X1669320Y240979D01*
G01X1668925Y242211D02*
X1668170Y241456D01*
G01X1669320Y240681D02*
X1667579Y238940D01*
G01X1668170Y241158D02*
X1667102Y240090D01*
G01X1667579Y238940D02*
X1667281D01*
G01D02*
X1663998Y235657D01*
G01X1666804Y240090D02*
X1662848Y236134D01*
G01X1663998Y235657D02*
Y221149D01*
G01X1662848Y236134D02*
Y221626D01*
G01X1651250Y218938D02*
X1658100Y225787D01*
G01X1656950Y226264D02*
Y249235D01*
G01X1658100Y225787D02*
Y248758D01*
G01X1656950Y249235D02*
X1663177Y255462D01*
G01X1658100Y248758D02*
X1664327Y254985D01*
G01X1663177Y255462D02*
Y305624D01*
G01X1664327Y254985D02*
Y306101D01*
G01X1651250Y218938D02*
X1658100Y225787D01*
G01D02*
Y248758D01*
G01X1656950Y226264D02*
Y249235D01*
G01X1658100Y248758D02*
X1664327Y254985D01*
G01X1656950Y249235D02*
X1663177Y255462D01*
G01X1664327Y254985D02*
Y306101D01*
G01X1663177Y255462D02*
Y305624D01*
G01X1651247Y314626D02*
X1655516Y318895D01*
G01X1652397Y314149D02*
X1656666Y318418D01*
G01X1655516Y318895D02*
Y337373D01*
G01Y340023D02*
Y341373D01*
G01X1656666Y318418D02*
Y366121D01*
G01X1658200Y366497D02*
Y317924D01*
G01X1659350Y366974D02*
Y317447D01*
G01X1658200Y317924D02*
X1653747Y313471D01*
G01X1659350Y317447D02*
X1654897Y312994D01*
G01X1661999Y367862D02*
Y316559D01*
G01X1660849Y367385D02*
Y317036D01*
G01X1661999Y316559D02*
X1657639Y312199D01*
G01X1660849Y317036D02*
X1656489Y312676D01*
G01X1657639Y312199D02*
Y308404D01*
G01X1656489Y312676D02*
Y307927D01*
G01X1657639Y308404D02*
X1660488Y305555D01*
G01X1656489Y307927D02*
X1659338Y305078D01*
G01X1660488Y305555D02*
Y297496D01*
G01X1659338Y305078D02*
Y297019D01*
G01X1660488Y297496D02*
X1661227Y296757D01*
G01X1659338Y297019D02*
X1660077Y296280D01*
G01X1652397Y314149D02*
X1656666Y318418D01*
G01X1651247Y314626D02*
X1655516Y318895D01*
G01X1656666Y318418D02*
Y366121D01*
G01X1655516Y318895D02*
Y337373D01*
G01X1656666Y318418D02*
Y366121D01*
G01X1655516Y340023D02*
Y341373D01*
G01X1656666Y318418D02*
Y366121D01*
G01Y318418D02*
Y366121D01*
G01Y318418D02*
Y366121D01*
G01X1659350Y366974D02*
Y317447D01*
G01X1658200Y366497D02*
Y317924D01*
G01X1659350Y317447D02*
X1654897Y312994D01*
G01X1658200Y317924D02*
X1653747Y313471D01*
G01X1660849Y367385D02*
Y317036D01*
G01X1661999Y367862D02*
Y316559D01*
G01X1660849Y317036D02*
X1656489Y312676D01*
G01X1661999Y316559D02*
X1657639Y312199D01*
G01X1656489Y312676D02*
Y307927D01*
G01X1657639Y312199D02*
Y308404D01*
G01X1656489Y307927D02*
X1659338Y305078D01*
G01X1657639Y308404D02*
X1660488Y305555D01*
G01X1659338Y305078D02*
Y297019D01*
G01X1660488Y305555D02*
Y297496D01*
G01X1659338Y297019D02*
X1660077Y296280D01*
G01X1660488Y297496D02*
X1661227Y296757D01*
G01X1667099Y408273D02*
Y313997D01*
G01X1668249Y408750D02*
Y313520D01*
G01X1667099Y313997D02*
X1666296Y313194D01*
G01X1668249Y313520D02*
X1667446Y312717D01*
G01X1668249Y408750D02*
Y313520D01*
G01X1667099Y408273D02*
Y313997D01*
G01X1668249Y313520D02*
X1667446Y312717D01*
G01X1667099Y313997D02*
X1666296Y313194D01*
G01X1663177Y305624D02*
X1661104Y307697D01*
G01X1664327Y306101D02*
X1662254Y308174D01*
G01X1661104Y307697D02*
Y312444D01*
G01X1662254Y308174D02*
Y311967D01*
G01X1661104Y312444D02*
X1663974Y315314D01*
G01X1662254Y311967D02*
X1665124Y314837D01*
G01X1663974Y315314D02*
Y368645D01*
G01X1665124Y314837D02*
Y369122D01*
G01X1664327Y306101D02*
X1662254Y308174D01*
G01X1663177Y305624D02*
X1661104Y307697D01*
G01X1662254Y308174D02*
Y311967D01*
G01X1661104Y307697D02*
Y312444D01*
G01X1662254Y311967D02*
X1665124Y314837D01*
G01X1661104Y312444D02*
X1663974Y315314D01*
G01X1665124Y314837D02*
Y369122D01*
G01X1663974Y315314D02*
Y368645D01*
G01X1655516Y344023D02*
Y345373D01*
G01Y348023D02*
Y349373D01*
G01Y352023D02*
Y365644D01*
G01X1656666Y366121D02*
X1651542Y371245D01*
G01D02*
Y372492D01*
G01X1655500Y406300D02*
X1651900Y402700D01*
G01X1650750Y403177D02*
Y375194D01*
G01X1651900Y402700D02*
Y375671D01*
G01X1650750Y375194D02*
X1652892Y373052D01*
G01X1651900Y375671D02*
X1654042Y373529D01*
G01X1652892Y373052D02*
Y371805D01*
G01X1654042Y373529D02*
Y372282D01*
G01X1652892Y371805D02*
X1658200Y366497D01*
G01X1654042Y372282D02*
X1659350Y366974D01*
G01X1658400Y430151D02*
Y394384D01*
G01X1657250Y429674D02*
Y394861D01*
G01X1658400Y394384D02*
X1656542Y392526D01*
G01X1657250Y394861D02*
X1655392Y393003D01*
G01X1656542Y392526D02*
Y373319D01*
G01X1655392Y393003D02*
Y372842D01*
G01X1656542Y373319D02*
X1661999Y367862D01*
G01X1655392Y372842D02*
X1660849Y367385D01*
G01X1655516Y344023D02*
Y345373D01*
G01Y348023D02*
Y349373D01*
G01Y352023D02*
Y365644D01*
G01X1656666Y366121D02*
X1651542Y371245D01*
G01D02*
Y372492D01*
G01X1655500Y406300D02*
X1651900Y402700D01*
G01D02*
Y375671D01*
G01X1650750Y403177D02*
Y375194D01*
G01X1651900Y375671D02*
X1654042Y373529D01*
G01X1650750Y375194D02*
X1652892Y373052D01*
G01X1654042Y373529D02*
Y372282D01*
G01X1652892Y373052D02*
Y371805D01*
G01X1654042Y372282D02*
X1659350Y366974D01*
G01X1652892Y371805D02*
X1658200Y366497D01*
G01X1657250Y429674D02*
Y394861D01*
G01X1658400Y430151D02*
Y394384D01*
G01X1657250Y394861D02*
X1655392Y393003D01*
G01X1658400Y394384D02*
X1656542Y392526D01*
G01X1655392Y393003D02*
Y372842D01*
G01X1656542Y392526D02*
Y373319D01*
G01X1655392Y372842D02*
X1660849Y367385D01*
G01X1656542Y373319D02*
X1661999Y367862D01*
G01X1663974Y368645D02*
X1658537Y374082D01*
G01X1665124Y369122D02*
X1659687Y374559D01*
G01X1658537Y374082D02*
Y382429D01*
G01X1659687Y374559D02*
Y381952D01*
G01X1658537Y382429D02*
X1663341Y387233D01*
G01X1659687Y381952D02*
X1664491Y386756D01*
G01X1663341Y387233D02*
Y407431D01*
G01X1664491Y386756D02*
Y407908D01*
G01X1665124Y369122D02*
X1659687Y374559D01*
G01X1663974Y368645D02*
X1658537Y374082D01*
G01X1659687Y374559D02*
Y381952D01*
G01X1658537Y374082D02*
Y382429D01*
G01X1659687Y381952D02*
X1664491Y386756D01*
G01X1658537Y382429D02*
X1663341Y387233D01*
G01X1664491Y386756D02*
Y407908D01*
G01X1663341Y387233D02*
Y407431D01*
G01X1652050Y456750D02*
Y430690D01*
G01X1653200Y457227D02*
Y431167D01*
G01X1652050Y430690D02*
X1654350Y428390D01*
G01X1653200Y431167D02*
X1655500Y428867D01*
G01X1654350Y428390D02*
Y406777D01*
G01X1655500Y428867D02*
Y406300D01*
G01X1654350Y406777D02*
X1650750Y403177D01*
G01X1651167Y463906D02*
X1652122Y462951D01*
G01X1653995Y461078D02*
X1654950Y460123D01*
G01X1656100Y460600D02*
Y432451D01*
G01X1654950Y460123D02*
Y431974D01*
G01X1656100Y432451D02*
X1658400Y430151D01*
G01X1654950Y431974D02*
X1657250Y429674D01*
G01X1653200Y457227D02*
Y431167D01*
G01X1652050Y456750D02*
Y430690D01*
G01X1653200Y431167D02*
X1655500Y428867D01*
G01X1652050Y430690D02*
X1654350Y428390D01*
G01X1655500Y428867D02*
Y406300D01*
G01X1654350Y428390D02*
Y406777D01*
G01D02*
X1650750Y403177D01*
G01X1651167Y463906D02*
X1652122Y462951D01*
G01X1653995Y461078D02*
X1654950Y460123D01*
G01D02*
Y431974D01*
G01X1656100Y460600D02*
Y432451D01*
G01X1654950Y431974D02*
X1657250Y429674D01*
G01X1656100Y432451D02*
X1658400Y430151D01*
G01X1665864Y459274D02*
Y450035D01*
G01X1667014Y459751D02*
Y449558D01*
G01X1665864Y450035D02*
X1661150Y445321D01*
G01X1667014Y449558D02*
X1662300Y444844D01*
G01X1661150Y445321D02*
Y435411D01*
G01X1662300Y444844D02*
Y435888D01*
G01X1661150Y435411D02*
X1664012Y432549D01*
G01X1662300Y435888D02*
X1665162Y433026D01*
G01X1664012Y432549D02*
Y411360D01*
G01X1665162Y433026D02*
Y411837D01*
G01X1664012Y411360D02*
X1667099Y408273D01*
G01X1665162Y411837D02*
X1668249Y408750D01*
G01X1667014Y459751D02*
Y449558D01*
G01X1665864Y459274D02*
Y450035D01*
G01X1667014Y449558D02*
X1662300Y444844D01*
G01X1665864Y450035D02*
X1661150Y445321D01*
G01X1662300Y444844D02*
Y435888D01*
G01X1661150Y445321D02*
Y435411D01*
G01X1662300Y435888D02*
X1665162Y433026D01*
G01X1661150Y435411D02*
X1664012Y432549D01*
G01X1665162Y433026D02*
Y411837D01*
G01X1664012Y432549D02*
Y411360D01*
G01X1665162Y411837D02*
X1668249Y408750D01*
G01X1664012Y411360D02*
X1667099Y408273D01*
G01X1663341Y407431D02*
X1660637Y410135D01*
G01X1664491Y407908D02*
X1661787Y410612D01*
G01X1660637Y410135D02*
Y430998D01*
G01X1661787Y410612D02*
Y431475D01*
G01X1660637Y430998D02*
X1658050Y433585D01*
G01X1661787Y431475D02*
X1659200Y434062D01*
G01X1658050Y433585D02*
Y461408D01*
G01X1659200Y434062D02*
Y461885D01*
G01X1664491Y407908D02*
X1661787Y410612D01*
G01X1663341Y407431D02*
X1660637Y410135D01*
G01X1661787Y410612D02*
Y431475D01*
G01X1660637Y410135D02*
Y430998D01*
G01X1661787Y431475D02*
X1659200Y434062D01*
G01X1660637Y430998D02*
X1658050Y433585D01*
G01X1659200Y434062D02*
Y461885D01*
G01X1658050Y433585D02*
Y461408D01*
G01X1656859Y531292D02*
X1663276Y519907D01*
G01X1655533Y535988D02*
X1664138Y520721D01*
G01X1663276Y519907D02*
X1668504Y516556D01*
G01X1664138Y520721D02*
X1668958Y517631D01*
G01X1668504Y516556D02*
X1682340Y513318D01*
G01X1668958Y517631D02*
X1682809Y514390D01*
G01X1682340Y513318D02*
X1696201Y503948D01*
G01X1682809Y514390D02*
X1697155Y504692D01*
G01X1696201Y503948D02*
X1701390Y489669D01*
G01X1697155Y504692D02*
X1702298Y490538D01*
G01X1701390Y489669D02*
X1738605Y474254D01*
G01X1702298Y490538D02*
X1738940Y475360D01*
G01X1656490Y537064D02*
X1665157Y521686D01*
G01X1657303Y537965D02*
X1666019Y522500D01*
G01X1665157Y521686D02*
X1669297Y519030D01*
G01X1666019Y522500D02*
X1669752Y520105D01*
G01X1669297Y519030D02*
X1683186Y515780D01*
G01X1669752Y520105D02*
X1683655Y516852D01*
G01X1683186Y515780D02*
X1695221Y507643D01*
G01X1683655Y516852D02*
X1695714Y508699D01*
G01X1695221Y507643D02*
X1706625Y504379D01*
G01X1695714Y508699D02*
X1707444Y505342D01*
G01X1706625Y504379D02*
X1714758Y487084D01*
G01X1707444Y505342D02*
X1715610Y487977D01*
G01X1682437Y529240D02*
X1699890Y525749D01*
G01D02*
X1702299Y523909D01*
G01X1700378Y526825D02*
X1703260Y524623D01*
G01X1702299Y523909D02*
X1707288Y510631D01*
G01X1703260Y524623D02*
X1708231Y511394D01*
G01X1707288Y510631D02*
X1710062Y508852D01*
G01X1708231Y511393D02*
X1710962Y509641D01*
G01X1710062Y508852D02*
X1718387Y491147D01*
G01X1710962Y509641D02*
X1719235Y492047D01*
G01X1658280Y539015D02*
X1667045Y523472D01*
G01X1659095Y539915D02*
X1667907Y524286D01*
G01X1667045Y523472D02*
X1670272Y521401D01*
G01X1667907Y524286D02*
X1670727Y522476D01*
G01X1670272Y521401D02*
X1684194Y518144D01*
G01X1670727Y522476D02*
X1684663Y519216D01*
G01X1684194Y518144D02*
X1696346Y509929D01*
G01X1684663Y519216D02*
X1696839Y510985D01*
G01X1696346Y509929D02*
X1708409Y506477D01*
G01X1696839Y510985D02*
X1709228Y507440D01*
G01X1708409Y506477D02*
X1716586Y489086D01*
G01X1709228Y507440D02*
X1717438Y489979D01*
G01X1655533Y535988D02*
X1664138Y520721D01*
G01X1655533Y535988D02*
X1664138Y520721D01*
G01X1656859Y531292D02*
X1663276Y519907D01*
G01X1664138Y520721D02*
X1668958Y517631D01*
G01X1663276Y519907D02*
X1668504Y516556D01*
G01X1668958Y517631D02*
X1682809Y514390D01*
G01X1668504Y516556D02*
X1682340Y513318D01*
G01X1682809Y514390D02*
X1697155Y504692D01*
G01X1682340Y513318D02*
X1696201Y503948D01*
G01X1697155Y504692D02*
X1702298Y490538D01*
G01X1696201Y503948D02*
X1701390Y489669D01*
G01X1702298Y490538D02*
X1738940Y475360D01*
G01X1701390Y489669D02*
X1738605Y474254D01*
G01X1657303Y537965D02*
X1666019Y522500D01*
G01X1656490Y537064D02*
X1665157Y521686D01*
G01X1666019Y522500D02*
X1669752Y520105D01*
G01X1665157Y521686D02*
X1669297Y519030D01*
G01X1669752Y520105D02*
X1683655Y516852D01*
G01X1669297Y519030D02*
X1683186Y515780D01*
G01X1683655Y516852D02*
X1695714Y508699D01*
G01X1683186Y515780D02*
X1695221Y507643D01*
G01X1695714Y508699D02*
X1707444Y505342D01*
G01X1695221Y507643D02*
X1706625Y504379D01*
G01X1707444Y505342D02*
X1715610Y487977D01*
G01X1706625Y504379D02*
X1714758Y487084D01*
G01X1682437Y529240D02*
X1699890Y525749D01*
G01X1700378Y526825D02*
X1703260Y524623D01*
G01X1699890Y525749D02*
X1702299Y523909D01*
G01X1703260Y524623D02*
X1708231Y511394D01*
G01X1702299Y523909D02*
X1707288Y510631D01*
G01X1708231Y511393D02*
X1710962Y509641D01*
G01X1707288Y510631D02*
X1710062Y508852D01*
G01X1710962Y509641D02*
X1719235Y492047D01*
G01X1710062Y508852D02*
X1718387Y491147D01*
G01X1659095Y539915D02*
X1667907Y524286D01*
G01X1658280Y539015D02*
X1667045Y523472D01*
G01X1667907Y524286D02*
X1670727Y522476D01*
G01X1667045Y523472D02*
X1670272Y521401D01*
G01X1670727Y522476D02*
X1684663Y519216D01*
G01X1670272Y521401D02*
X1684194Y518144D01*
G01X1684663Y519216D02*
X1696839Y510985D01*
G01X1684194Y518144D02*
X1696346Y509929D01*
G01X1696839Y510985D02*
X1709228Y507440D01*
G01X1696346Y509929D02*
X1708409Y506477D01*
G01X1709228Y507440D02*
X1717438Y489979D01*
G01X1708409Y506477D02*
X1716586Y489086D01*
G01X1665150Y493594D02*
X1656225Y502519D01*
G01X1655748Y501369D02*
X1664000Y493117D01*
G01X1665150Y484050D02*
Y493594D01*
G01X1664000Y493117D02*
Y483573D01*
G01X1670250Y478950D02*
X1665150Y484050D01*
G01X1664000Y483573D02*
X1669773Y477800D01*
G01X1676246Y478950D02*
X1670250D01*
G01X1669773Y477800D02*
X1676723D01*
G01X1677425Y480129D02*
X1676246Y478950D01*
G01X1676723Y477800D02*
X1677902Y478979D01*
G01X1683445Y480129D02*
X1677425D01*
G01X1677902Y478979D02*
X1682968D01*
G01X1685190Y478384D02*
X1683445Y480129D01*
G01X1682968Y478979D02*
X1684713Y477234D01*
G01X1720744Y478384D02*
X1685190D01*
G01X1684713Y477234D02*
X1720267D01*
G01X1684713D02*
X1720267D01*
G01X1720744Y478384D02*
X1685190D01*
G01X1682968Y478979D02*
X1684713Y477234D01*
G01X1685190Y478384D02*
X1683445Y480129D01*
G01X1677902Y478979D02*
X1682968D01*
G01X1683445Y480129D02*
X1677425D01*
G01X1676723Y477800D02*
X1677902Y478979D01*
G01X1677425Y480129D02*
X1676246Y478950D01*
G01X1669773Y477800D02*
X1676723D01*
G01X1676246Y478950D02*
X1670250D01*
G01X1664000Y483573D02*
X1669773Y477800D01*
G01X1670250Y478950D02*
X1665150Y484050D01*
G01X1664000Y493117D02*
Y483573D01*
G01X1665150Y484050D02*
Y493594D01*
G01X1655748Y501369D02*
X1664000Y493117D01*
G01X1665150Y493594D02*
X1656225Y502519D01*
G01X1722901Y463876D02*
X1712229Y474548D01*
G01X1712706Y475698D02*
X1684214D01*
G01X1712229Y474548D02*
X1683737D01*
G01X1684214Y475698D02*
X1682344Y477568D01*
G01X1683737Y474548D02*
X1681867Y476418D01*
G01X1682344Y477568D02*
X1678401D01*
G01X1681867Y476418D02*
X1678878D01*
G01X1678401Y477568D02*
X1677233Y476400D01*
G01X1678878Y476418D02*
X1677710Y475250D01*
G01X1677233Y476400D02*
X1667800D01*
G01X1677710Y475250D02*
X1667323D01*
G01X1667800Y476400D02*
X1662650Y481550D01*
G01X1667323Y475250D02*
X1661500Y481073D01*
G01X1662650Y481550D02*
Y492557D01*
G01X1661500Y481073D02*
Y484080D01*
G01X1662650Y481550D02*
Y492557D01*
G01X1661500Y486730D02*
Y488080D01*
G01X1662650Y481550D02*
Y492557D01*
G01X1661500Y490730D02*
Y492080D01*
G01X1662650Y492557D02*
X1655282Y499925D01*
G01X1661500Y492080D02*
X1660461Y493119D01*
G01X1662650Y492557D02*
X1655282Y499925D01*
G01X1658588Y494992D02*
X1657633Y495947D01*
G01X1662650Y492557D02*
X1655282Y499925D01*
G01X1655760Y497820D02*
X1654805Y498775D01*
G01D02*
X1651332D01*
G01X1722901Y463876D02*
X1712229Y474548D01*
G01D02*
X1683737D01*
G01X1712706Y475698D02*
X1684214D01*
G01X1683737Y474548D02*
X1681867Y476418D01*
G01X1684214Y475698D02*
X1682344Y477568D01*
G01X1681867Y476418D02*
X1678878D01*
G01X1682344Y477568D02*
X1678401D01*
G01X1678878Y476418D02*
X1677710Y475250D01*
G01X1678401Y477568D02*
X1677233Y476400D01*
G01X1677710Y475250D02*
X1667323D01*
G01X1677233Y476400D02*
X1667800D01*
G01X1667323Y475250D02*
X1661500Y481073D01*
G01X1667800Y476400D02*
X1662650Y481550D01*
G01X1661500Y481073D02*
Y484080D01*
G01Y486730D02*
Y488080D01*
G01Y490730D02*
Y492080D01*
G01X1662650Y481550D02*
Y492557D01*
G01X1661500Y492080D02*
X1660461Y493119D01*
G01X1658588Y494992D02*
X1657633Y495947D01*
G01X1655760Y497820D02*
X1654805Y498775D01*
G01X1662650Y492557D02*
X1655282Y499925D01*
G01X1654805Y498775D02*
X1651332D01*
G01X1654721Y535085D02*
X1656859Y531291D01*
G01X1674030Y537618D02*
X1675164Y537416D01*
G01D02*
X1694715Y543102D01*
G01X1674366Y538727D02*
X1675101Y538596D01*
G01X1675164Y537416D02*
X1694715Y543102D01*
G01X1675101Y538596D02*
X1694657Y544283D01*
G01X1694715Y543102D02*
X1702835Y541582D01*
G01X1694657Y544283D02*
X1702824Y542755D01*
G01X1702835Y541582D02*
X1715025Y544100D01*
G01X1702824Y542755D02*
X1715239Y545319D01*
G01X1717947Y549609D02*
X1699603Y554770D01*
G01X1717947Y549609D02*
X1699603Y554770D01*
G01X1713437Y549682D02*
X1712138Y550048D01*
G01X1717947Y549609D02*
X1699603Y554770D01*
G01X1709587Y550766D02*
X1708287Y551131D01*
G01X1717947Y549609D02*
X1699603Y554770D01*
G01X1705736Y551849D02*
X1699590Y553578D01*
G01X1699603Y554770D02*
X1694749Y553516D01*
G01X1699590Y553578D02*
X1694789Y552338D01*
G01X1694749Y553516D02*
X1686084Y555141D01*
G01X1694789Y552338D02*
X1686117Y553964D01*
G01X1686084Y555141D02*
X1681088Y553931D01*
G01X1686117Y553964D02*
X1681092Y552748D01*
G01X1681088Y553931D02*
X1677865Y554685D01*
G01X1681092Y552748D02*
X1677849Y553507D01*
G01X1677865Y554685D02*
X1672310Y553543D01*
G01X1677849Y553507D02*
X1672320Y552371D01*
G01X1672310Y553543D02*
X1662156Y555450D01*
G01X1672320Y552371D02*
X1662188Y554273D01*
G01X1662156Y555450D02*
X1654305Y553532D01*
G01X1662188Y554273D02*
X1654294Y552345D01*
G01X1650700Y568451D02*
Y561201D01*
G01D02*
X1652933Y558968D01*
G01X1652326Y557947D02*
X1657741Y556347D01*
G01X1652933Y558968D02*
X1657766Y557540D01*
G01X1657741Y556347D02*
X1660938Y557151D01*
G01X1657766Y557540D02*
X1660902Y558328D01*
G01X1660938Y557151D02*
X1672532Y554972D01*
G01X1660902Y558328D02*
X1672522Y556145D01*
G01X1672532Y554972D02*
X1677884Y556073D01*
G01X1672522Y556145D02*
X1677900Y557251D01*
G01X1677884Y556073D02*
X1681081Y555324D01*
G01X1677900Y557251D02*
X1681077Y556507D01*
G01X1681081Y555324D02*
X1686049Y556526D01*
G01X1681077Y556507D02*
X1686018Y557702D01*
G01X1686049Y556526D02*
X1694703Y554904D01*
G01X1686018Y557702D02*
X1694663Y556082D01*
G01X1694703Y554904D02*
X1699901Y556246D01*
G01X1694663Y556082D02*
X1699915Y557438D01*
G01X1699901Y556246D02*
X1718594Y550955D01*
G01X1699915Y557438D02*
X1719253Y551964D01*
G01X1655997Y585733D02*
X1661632Y581680D01*
G01X1655435Y584719D02*
X1661061Y580674D01*
G01X1661632Y581680D02*
X1671247Y577506D01*
G01X1661061Y580674D02*
X1670916Y576395D01*
G01X1671247Y577506D02*
X1694744Y573490D01*
G01X1670916Y576395D02*
X1694814Y572311D01*
G01X1694744Y573490D02*
X1705296Y576614D01*
G01X1694814Y572311D02*
X1705389Y575442D01*
G01X1705296Y576614D02*
X1709096Y576118D01*
G01X1705389Y575442D02*
X1708706Y575009D01*
G01X1709096Y576118D02*
X1713172Y573637D01*
G01X1708706Y575009D02*
X1710455Y573944D01*
G01X1709096Y576118D02*
X1713172Y573637D01*
G01X1710455Y573944D02*
X1710456D01*
G01X1709096Y576118D02*
X1713172Y573637D01*
G01X1710456Y573944D02*
X1712204Y572879D01*
G01D02*
X1715133Y563564D01*
G01X1665424Y538635D02*
X1672531Y533897D01*
G01X1665978Y539649D02*
X1672980Y534981D01*
G01X1672531Y533897D02*
X1676695Y533067D01*
G01X1672980Y534981D02*
X1677144Y534151D01*
G01X1676695Y533067D02*
X1682437Y529240D01*
G01X1677144Y534151D02*
X1682886Y530323D01*
G01D02*
X1700378Y526825D01*
G01X1654721Y535085D02*
X1656859Y531291D01*
G01X1674366Y538727D02*
X1675101Y538596D01*
G01X1674366Y538727D02*
X1675101Y538596D01*
G01X1674030Y537618D02*
X1675164Y537416D01*
G01X1674366Y538727D02*
X1675101Y538596D01*
G01D02*
X1694657Y544283D01*
G01X1675164Y537416D02*
X1694715Y543102D01*
G01X1694657Y544283D02*
X1702824Y542755D01*
G01X1694715Y543102D02*
X1702835Y541582D01*
G01X1702824Y542755D02*
X1715239Y545319D01*
G01X1702835Y541582D02*
X1715025Y544100D01*
G01X1713437Y549682D02*
X1712138Y550048D01*
G01X1709587Y550766D02*
X1708287Y551131D01*
G01X1705736Y551849D02*
X1699590Y553578D01*
G01X1717947Y549609D02*
X1699603Y554770D01*
G01X1699590Y553578D02*
X1694789Y552338D01*
G01X1699603Y554770D02*
X1694749Y553516D01*
G01X1694789Y552338D02*
X1686117Y553964D01*
G01X1694749Y553516D02*
X1686084Y555141D01*
G01X1686117Y553964D02*
X1681092Y552748D01*
G01X1686084Y555141D02*
X1681088Y553931D01*
G01X1681092Y552748D02*
X1677849Y553507D01*
G01X1681088Y553931D02*
X1677865Y554685D01*
G01X1677849Y553507D02*
X1672320Y552371D01*
G01X1677865Y554685D02*
X1672310Y553543D01*
G01X1672320Y552371D02*
X1662188Y554273D01*
G01X1672310Y553543D02*
X1662156Y555450D01*
G01X1662188Y554273D02*
X1654294Y552345D01*
G01X1662156Y555450D02*
X1654305Y553532D01*
G01X1650700Y568451D02*
Y561201D01*
G01D02*
X1652933Y558968D01*
G01D02*
X1657766Y557540D01*
G01X1652326Y557947D02*
X1657741Y556347D01*
G01X1657766Y557540D02*
X1660902Y558328D01*
G01X1657741Y556347D02*
X1660938Y557151D01*
G01X1660902Y558328D02*
X1672522Y556145D01*
G01X1660938Y557151D02*
X1672532Y554972D01*
G01X1672522Y556145D02*
X1677900Y557251D01*
G01X1672532Y554972D02*
X1677884Y556073D01*
G01X1677900Y557251D02*
X1681077Y556507D01*
G01X1677884Y556073D02*
X1681081Y555324D01*
G01X1681077Y556507D02*
X1686018Y557702D01*
G01X1681081Y555324D02*
X1686049Y556526D01*
G01X1686018Y557702D02*
X1694663Y556082D01*
G01X1686049Y556526D02*
X1694703Y554904D01*
G01X1694663Y556082D02*
X1699915Y557438D01*
G01X1694703Y554904D02*
X1699901Y556246D01*
G01X1699915Y557438D02*
X1719253Y551964D01*
G01X1699901Y556246D02*
X1718594Y550955D01*
G01X1655435Y584719D02*
X1661061Y580674D01*
G01X1655997Y585733D02*
X1661632Y581680D01*
G01X1661061Y580674D02*
X1670916Y576395D01*
G01X1661632Y581680D02*
X1671247Y577506D01*
G01X1670916Y576395D02*
X1694814Y572311D01*
G01X1671247Y577506D02*
X1694744Y573490D01*
G01X1694814Y572311D02*
X1705389Y575442D01*
G01X1694744Y573490D02*
X1705296Y576614D01*
G01X1705389Y575442D02*
X1708706Y575009D01*
G01X1705296Y576614D02*
X1709096Y576118D01*
G01X1708706Y575009D02*
X1710455Y573944D01*
G01D02*
X1710456D01*
G01D02*
X1712204Y572879D01*
G01X1709096Y576118D02*
X1713172Y573637D01*
G01X1712204Y572879D02*
X1715133Y563564D01*
G01X1665978Y539649D02*
X1672980Y534981D01*
G01X1665424Y538635D02*
X1672531Y533897D01*
G01X1672980Y534981D02*
X1677144Y534151D01*
G01X1672531Y533897D02*
X1676695Y533067D01*
G01X1677144Y534151D02*
X1682886Y530323D01*
G01X1676695Y533067D02*
X1682437Y529240D01*
G01X1682886Y530323D02*
X1700378Y526825D01*
G01X1741154Y467619D02*
Y464298D01*
G01X1743654Y463425D02*
X1742304Y464775D01*
G01X1741154Y464298D02*
X1743177Y462275D01*
G01X1748168Y463425D02*
X1743654D01*
G01X1743177Y462275D02*
X1748645D01*
G01X1749518Y464775D02*
X1748168Y463425D01*
G01X1748645Y462275D02*
X1750668Y464298D01*
G01D02*
Y467819D01*
G01X1753868Y464266D02*
Y468296D01*
G01X1752718Y467819D02*
Y463789D01*
G01X1755218Y462916D02*
X1753868Y464266D01*
G01X1752718Y463789D02*
X1754741Y461766D01*
G01X1758706Y462916D02*
X1755218D01*
G01X1754741Y461766D02*
X1759183D01*
G01X1763668Y467878D02*
X1758706Y462916D01*
G01X1759183Y461766D02*
X1764145Y466728D01*
G01X1766895Y464328D02*
Y466755D01*
G01X1765745Y466278D02*
Y463851D01*
G01X1768245Y462978D02*
X1766895Y464328D01*
G01X1765745Y463851D02*
X1767768Y461828D01*
G01X1773887Y462978D02*
X1768245D01*
G01X1767768Y461828D02*
X1774364D01*
G01X1775237Y464328D02*
X1773887Y462978D01*
G01X1775237Y464328D02*
X1773887Y462978D01*
G01X1767768Y461828D02*
X1774364D01*
G01X1773887Y462978D02*
X1768245D01*
G01X1765745Y463851D02*
X1767768Y461828D01*
G01X1768245Y462978D02*
X1766895Y464328D01*
G01X1765745Y466278D02*
Y463851D01*
G01X1766895Y464328D02*
Y466755D01*
G01X1759183Y461766D02*
X1764145Y466728D01*
G01X1763668Y467878D02*
X1758706Y462916D01*
G01X1754741Y461766D02*
X1759183D01*
G01X1758706Y462916D02*
X1755218D01*
G01X1752718Y463789D02*
X1754741Y461766D01*
G01X1755218Y462916D02*
X1753868Y464266D01*
G01X1752718Y467819D02*
Y463789D01*
G01X1753868Y464266D02*
Y468296D01*
G01X1750668Y464298D02*
Y467819D01*
G01X1748645Y462275D02*
X1750668Y464298D01*
G01X1749518Y464775D02*
X1748168Y463425D01*
G01X1743177Y462275D02*
X1748645D01*
G01X1748168Y463425D02*
X1743654D01*
G01X1741154Y464298D02*
X1743177Y462275D01*
G01X1743654Y463425D02*
X1742304Y464775D01*
G01X1741154Y467619D02*
Y464298D01*
G01X1774952Y457101D02*
X1772325D01*
G01X1775429Y455951D02*
X1771848D01*
G01X1772325Y457101D02*
X1769945Y459481D01*
G01X1771848Y455951D02*
X1769468Y458331D01*
G01X1769945Y459481D02*
X1766368D01*
G01X1769468Y458331D02*
X1766845D01*
G01X1766368Y459481D02*
X1763988Y457101D01*
G01X1766845Y458331D02*
X1764465Y455951D01*
G01X1763988Y457101D02*
X1761361D01*
G01X1764465Y455951D02*
X1760884D01*
G01X1761361Y457101D02*
X1758981Y459481D01*
G01X1760884Y455951D02*
X1758504Y458331D01*
G01X1758981Y459481D02*
X1755404D01*
G01X1758504Y458331D02*
X1755881D01*
G01X1755404Y459481D02*
X1753022Y457099D01*
G01X1755881Y458331D02*
X1753499Y455949D01*
G01X1753022Y457099D02*
X1750399D01*
G01X1753499Y455949D02*
X1749922D01*
G01X1750399Y457099D02*
X1748017Y459481D01*
G01X1749922Y455949D02*
X1747540Y458331D01*
G01X1748017Y459481D02*
X1744440D01*
G01X1747540Y458331D02*
X1744917D01*
G01X1744440Y459481D02*
X1742058Y457099D01*
G01X1744917Y458331D02*
X1742535Y455949D01*
G01X1742058Y457099D02*
X1739279D01*
G01X1742535Y455949D02*
X1738802D01*
G01X1739279Y457099D02*
X1737442Y458936D01*
G01X1738802Y455949D02*
X1736292Y458459D01*
G01X1737442Y458936D02*
Y463592D01*
G01X1736292Y458459D02*
Y463115D01*
G01X1737442Y463592D02*
X1736008Y465026D01*
G01X1736292Y463115D02*
X1735531Y463876D01*
G01D02*
X1722901D01*
G01X1775429Y455951D02*
X1771848D01*
G01X1774952Y457101D02*
X1772325D01*
G01X1771848Y455951D02*
X1769468Y458331D01*
G01X1772325Y457101D02*
X1769945Y459481D01*
G01X1769468Y458331D02*
X1766845D01*
G01X1769945Y459481D02*
X1766368D01*
G01X1766845Y458331D02*
X1764465Y455951D01*
G01X1766368Y459481D02*
X1763988Y457101D01*
G01X1764465Y455951D02*
X1760884D01*
G01X1763988Y457101D02*
X1761361D01*
G01X1760884Y455951D02*
X1758504Y458331D01*
G01X1761361Y457101D02*
X1758981Y459481D01*
G01X1758504Y458331D02*
X1755881D01*
G01X1758981Y459481D02*
X1755404D01*
G01X1755881Y458331D02*
X1753499Y455949D01*
G01X1755404Y459481D02*
X1753022Y457099D01*
G01X1753499Y455949D02*
X1749922D01*
G01X1753022Y457099D02*
X1750399D01*
G01X1749922Y455949D02*
X1747540Y458331D01*
G01X1750399Y457099D02*
X1748017Y459481D01*
G01X1747540Y458331D02*
X1744917D01*
G01X1748017Y459481D02*
X1744440D01*
G01X1744917Y458331D02*
X1742535Y455949D01*
G01X1744440Y459481D02*
X1742058Y457099D01*
G01X1742535Y455949D02*
X1738802D01*
G01X1742058Y457099D02*
X1739279D01*
G01X1738802Y455949D02*
X1736292Y458459D01*
G01X1739279Y457099D02*
X1737442Y458936D01*
G01X1736292Y458459D02*
Y463115D01*
G01X1737442Y458936D02*
Y463592D01*
G01X1736292Y463115D02*
X1735531Y463876D01*
G01X1737442Y463592D02*
X1736008Y465026D01*
G01X1735531Y463876D02*
X1722901D01*
G01X1738605Y474254D02*
X1760239Y469950D01*
G01X1738940Y475360D02*
X1745294Y474096D01*
G01X1738605Y474254D02*
X1760239Y469950D01*
G01X1745295Y474097D02*
X1751650Y472833D01*
G01X1738605Y474254D02*
X1760239Y469950D01*
G01X1753798Y472405D02*
X1755149Y472136D01*
G01X1738605Y474254D02*
X1760239Y469950D01*
G01X1757359Y471696D02*
X1760353Y471100D01*
G01X1760239Y469950D02*
X1762977D01*
G01X1760353Y471100D02*
X1762500D01*
G01X1762977Y469950D02*
X1764906Y471879D01*
G01X1762500Y471100D02*
X1763756Y472356D01*
G01X1764906Y471879D02*
Y474740D01*
G01X1763756Y472356D02*
Y474780D01*
G01X1714758Y487084D02*
X1735989Y478289D01*
G01X1715610Y487977D02*
X1736325Y479395D01*
G01X1735989Y478289D02*
X1744695Y476548D01*
G01X1736325Y479395D02*
X1744695Y477721D01*
G01Y476548D02*
X1760199Y479644D01*
G01X1744695Y477721D02*
X1760192Y480816D01*
G01X1760199Y479644D02*
X1768033Y478138D01*
G01X1760192Y480817D02*
X1761568Y480552D01*
G01X1760199Y479644D02*
X1768033Y478138D01*
G01D02*
X1768034D01*
G01X1764170Y480052D02*
X1768599Y479201D01*
G01X1768034Y478138D02*
X1769303Y476870D01*
G01X1768599Y479201D02*
X1770453Y477347D01*
G01X1769303Y476870D02*
Y471300D01*
G01X1770453Y477347D02*
Y475236D01*
G01X1769303Y476870D02*
Y471300D01*
G01X1770453Y473018D02*
Y471777D01*
G01X1769303Y471300D02*
X1771333Y469270D01*
G01X1770453Y471777D02*
X1771810Y470420D01*
G01X1771333Y469270D02*
X1775869D01*
G01X1771810Y470420D02*
X1775392D01*
G01X1725962Y527009D02*
X1741309Y511663D01*
G01X1726938Y527661D02*
X1742026Y512573D01*
G01X1741309Y511663D02*
X1770962Y493525D01*
G01X1742026Y512573D02*
X1771882Y494312D01*
G01X1770962Y493525D02*
X1774015Y486157D01*
G01X1771882Y494312D02*
X1774991Y486809D01*
G01X1776712Y487560D02*
X1773431Y495481D01*
G01X1774349Y496273D02*
X1744101Y514409D01*
G01X1773431Y495481D02*
X1743392Y513492D01*
G01X1744101Y514409D02*
X1729278Y528949D01*
G01X1743392Y513492D02*
X1728252Y528343D01*
G01X1733379Y527570D02*
X1754059Y517275D01*
G01X1734259Y528418D02*
X1754664Y518260D01*
G01X1754059Y517275D02*
X1773737Y502627D01*
G01X1754664Y518260D02*
X1774679Y503360D01*
G01X1773737Y502627D02*
X1779534Y488638D01*
G01X1736298Y530710D02*
X1760086Y518565D01*
G01X1735410Y529872D02*
X1759476Y517584D01*
G01X1760086Y518565D02*
X1776096Y506647D01*
G01X1759476Y517584D02*
X1766147Y512618D01*
G01X1760086Y518565D02*
X1776096Y506647D01*
G01X1767363Y510903D02*
X1768272Y511036D01*
G01X1760086Y518565D02*
X1776096Y506647D01*
G01X1768272Y511036D02*
X1775619Y505568D01*
G01X1718387Y491147D02*
X1734907Y484300D01*
G01X1719235Y492047D02*
X1720528Y491510D01*
G01X1718387Y491147D02*
X1734907Y484300D01*
G01X1723022Y490475D02*
X1724315Y489938D01*
G01X1718387Y491147D02*
X1734907Y484300D01*
G01X1726808Y488903D02*
X1735136Y485450D01*
G01X1734907Y484300D02*
X1738500D01*
G01X1735136Y485450D02*
X1738023D01*
G01X1738500Y484300D02*
X1739975Y485775D01*
G01X1738023Y485450D02*
X1738825Y486252D01*
G01X1739975Y485775D02*
Y487305D01*
G01X1738825Y486252D02*
Y487267D01*
G01X1716588Y489084D02*
X1733761Y481974D01*
G01X1717438Y489979D02*
X1734097Y483080D01*
G01X1733761Y481974D02*
X1738203Y481086D01*
G01D02*
X1738316D01*
G01X1734097Y483080D02*
X1738320Y482236D01*
G01X1733761Y481974D02*
X1738203Y481086D01*
G01D02*
X1738316D01*
G01D02*
X1747275Y481051D01*
G01X1738320Y482236D02*
X1739168Y482233D01*
G01X1738316Y481086D02*
X1747275Y481051D01*
G01X1741818Y482223D02*
X1743168Y482217D01*
G01X1738316Y481086D02*
X1747275Y481051D01*
G01X1745818Y482207D02*
X1747168Y482202D01*
G01X1747275Y481051D02*
X1750582Y481682D01*
G01X1747168Y482202D02*
X1750018Y482746D01*
G01X1750582Y481682D02*
X1752412Y483513D01*
G01X1750018Y482746D02*
X1751262Y483990D01*
G01X1752412Y483513D02*
Y486888D01*
G01X1751262Y483990D02*
Y486888D01*
G01X1738940Y475360D02*
X1745294Y474096D01*
G01X1745295Y474097D02*
X1751650Y472833D01*
G01X1753798Y472405D02*
X1755149Y472136D01*
G01X1757359Y471696D02*
X1760353Y471100D01*
G01X1738605Y474254D02*
X1760239Y469950D01*
G01X1760353Y471100D02*
X1762500D01*
G01X1760239Y469950D02*
X1762977D01*
G01X1762500Y471100D02*
X1763756Y472356D01*
G01X1762977Y469950D02*
X1764906Y471879D01*
G01X1763756Y472356D02*
Y474780D01*
G01X1764906Y471879D02*
Y474740D01*
G01X1715610Y487977D02*
X1736325Y479395D01*
G01X1714758Y487084D02*
X1735989Y478289D01*
G01X1736325Y479395D02*
X1744695Y477721D01*
G01X1735989Y478289D02*
X1744695Y476548D01*
G01Y477721D02*
X1760192Y480816D01*
G01X1744695Y476548D02*
X1760199Y479644D01*
G01X1760192Y480817D02*
X1761568Y480552D01*
G01X1764170Y480052D02*
X1768599Y479201D01*
G01X1760199Y479644D02*
X1768033Y478138D01*
G01X1764170Y480052D02*
X1768599Y479201D01*
G01X1768033Y478138D02*
X1768034D01*
G01X1768599Y479201D02*
X1770453Y477347D01*
G01X1768034Y478138D02*
X1769303Y476870D01*
G01X1770453Y477347D02*
Y475236D01*
G01Y473018D02*
Y471777D01*
G01X1769303Y476870D02*
Y471300D01*
G01X1770453Y471777D02*
X1771810Y470420D01*
G01X1769303Y471300D02*
X1771333Y469270D01*
G01X1771810Y470420D02*
X1775392D01*
G01X1771333Y469270D02*
X1775869D01*
G01X1726938Y527661D02*
X1742026Y512573D01*
G01X1725962Y527009D02*
X1741309Y511663D01*
G01X1742026Y512573D02*
X1771882Y494312D01*
G01X1741309Y511663D02*
X1770962Y493525D01*
G01X1771882Y494312D02*
X1774991Y486809D01*
G01X1770962Y493525D02*
X1774015Y486157D01*
G01X1776712Y487560D02*
X1773431Y495481D01*
G01D02*
X1743392Y513492D01*
G01X1774349Y496273D02*
X1744101Y514409D01*
G01X1743392Y513492D02*
X1728252Y528343D01*
G01X1744101Y514409D02*
X1729278Y528949D01*
G01X1734259Y528418D02*
X1754664Y518260D01*
G01X1733379Y527570D02*
X1754059Y517275D01*
G01X1754664Y518260D02*
X1774679Y503360D01*
G01X1754059Y517275D02*
X1773737Y502627D01*
G01D02*
X1779534Y488638D01*
G01X1735410Y529872D02*
X1759476Y517584D01*
G01X1736298Y530710D02*
X1760086Y518565D01*
G01X1759476Y517584D02*
X1766147Y512618D01*
G01X1767363Y510903D02*
X1768272Y511036D01*
G01D02*
X1775619Y505568D01*
G01X1760086Y518565D02*
X1776096Y506647D01*
G01X1719235Y492047D02*
X1720528Y491510D01*
G01X1723022Y490475D02*
X1724315Y489938D01*
G01X1726808Y488903D02*
X1735136Y485450D01*
G01X1718387Y491147D02*
X1734907Y484300D01*
G01X1735136Y485450D02*
X1738023D01*
G01X1734907Y484300D02*
X1738500D01*
G01X1738023Y485450D02*
X1738825Y486252D01*
G01X1738500Y484300D02*
X1739975Y485775D01*
G01X1738825Y486252D02*
Y487267D01*
G01X1739975Y485775D02*
Y487305D01*
G01X1717438Y489979D02*
X1734097Y483080D01*
G01X1716588Y489084D02*
X1733761Y481974D01*
G01X1734097Y483080D02*
X1738320Y482236D01*
G01D02*
X1739168Y482233D01*
G01X1733761Y481974D02*
X1738203Y481086D01*
G01X1734097Y483080D02*
X1738320Y482236D01*
G01D02*
X1739168Y482233D01*
G01X1738203Y481086D02*
X1738316D01*
G01X1738320Y482236D02*
X1739168Y482233D01*
G01X1741818Y482223D02*
X1743168Y482217D01*
G01X1745818Y482207D02*
X1747168Y482202D01*
G01X1738316Y481086D02*
X1747275Y481051D01*
G01X1747168Y482202D02*
X1750018Y482746D01*
G01X1747275Y481051D02*
X1750582Y481682D01*
G01X1750018Y482746D02*
X1751262Y483990D01*
G01X1750582Y481682D02*
X1752412Y483513D01*
G01X1751262Y483990D02*
Y486888D01*
G01X1752412Y483513D02*
Y486888D01*
G01X1726078Y473050D02*
X1720744Y478384D01*
G01X1720267Y477234D02*
X1725601Y471900D01*
G01X1735896Y473050D02*
X1726078D01*
G01X1725601Y471900D02*
X1735419D01*
G01X1740813Y469587D02*
X1739359D01*
G01D02*
X1735896Y473050D01*
G01X1735419Y471900D02*
X1738882Y468437D01*
G01X1740813Y469587D02*
X1739359D01*
G01X1738882Y468437D02*
X1740336D01*
G01X1742304Y468096D02*
X1740813Y469587D01*
G01X1740336Y468437D02*
X1741154Y467619D01*
G01X1742304Y464775D02*
Y468096D01*
G01X1749518Y468296D02*
Y464775D01*
G01X1750641Y469419D02*
X1749518Y468296D01*
G01X1750668Y467819D02*
X1751118Y468269D01*
G01X1752745Y469419D02*
X1750641D01*
G01X1751118Y468269D02*
X1752268D01*
G01X1753868Y468296D02*
X1752745Y469419D01*
G01X1752268Y468269D02*
X1752718Y467819D01*
G01X1765772Y467878D02*
X1763668D01*
G01X1764145Y466728D02*
X1765295D01*
G01X1766895Y466755D02*
X1765772Y467878D01*
G01X1765295Y466728D02*
X1765745Y466278D01*
G01X1765295Y466728D02*
X1765745Y466278D01*
G01X1766895Y466755D02*
X1765772Y467878D01*
G01X1764145Y466728D02*
X1765295D01*
G01X1765772Y467878D02*
X1763668D01*
G01X1752268Y468269D02*
X1752718Y467819D01*
G01X1753868Y468296D02*
X1752745Y469419D01*
G01X1751118Y468269D02*
X1752268D01*
G01X1752745Y469419D02*
X1750641D01*
G01X1750668Y467819D02*
X1751118Y468269D01*
G01X1750641Y469419D02*
X1749518Y468296D01*
G01D02*
Y464775D01*
G01X1742304D02*
Y468096D01*
G01X1740336Y468437D02*
X1741154Y467619D01*
G01X1742304Y468096D02*
X1740813Y469587D01*
G01X1735419Y471900D02*
X1738882Y468437D01*
G01D02*
X1740336D01*
G01X1740813Y469587D02*
X1739359D01*
G01X1735419Y471900D02*
X1738882Y468437D01*
G01X1739359Y469587D02*
X1735896Y473050D01*
G01X1725601Y471900D02*
X1735419D01*
G01X1735896Y473050D02*
X1726078D01*
G01X1720267Y477234D02*
X1725601Y471900D01*
G01X1726078Y473050D02*
X1720744Y478384D01*
G01X1736008Y465026D02*
X1723378D01*
G01D02*
X1712706Y475698D01*
G01X1736008Y465026D02*
X1723378D01*
G01D02*
X1712706Y475698D01*
G01X1715025Y544100D02*
X1720201Y540919D01*
G01X1715239Y545319D02*
X1721121Y541704D01*
G01X1720201Y540919D02*
X1725962Y527009D01*
G01X1721121Y541704D02*
X1726938Y527661D01*
G01X1729278Y528949D02*
X1726365Y539393D01*
G01X1728252Y528343D02*
X1725322Y538849D01*
G01X1726365Y539393D02*
X1717947Y549609D01*
G01X1725322Y538849D02*
X1717288Y548599D01*
G01D02*
X1715988Y548965D01*
G01X1718594Y550955D02*
X1727935Y539618D01*
G01X1719253Y551964D02*
X1728921Y540232D01*
G01X1727935Y539618D02*
X1733379Y527570D01*
G01X1728921Y540232D02*
X1734259Y528418D01*
G01X1713172Y573637D02*
X1716191Y564037D01*
G01D02*
X1720251Y557193D01*
G01X1715133Y563564D02*
X1719457Y556277D01*
G01X1720251Y557193D02*
X1723111Y556008D01*
G01X1719457Y556277D02*
X1722319Y555091D01*
G01X1723111Y556008D02*
X1730873Y543036D01*
G01X1722319Y555091D02*
X1729849Y542507D01*
G01X1730873Y543036D02*
X1736298Y530710D01*
G01X1729849Y542507D02*
X1735410Y529872D01*
G01X1715239Y545319D02*
X1721121Y541704D01*
G01X1715025Y544100D02*
X1720201Y540919D01*
G01X1721121Y541704D02*
X1726938Y527661D01*
G01X1720201Y540919D02*
X1725962Y527009D01*
G01X1728252Y528343D02*
X1725322Y538849D01*
G01X1729278Y528949D02*
X1726365Y539393D01*
G01X1725322Y538849D02*
X1717288Y548599D01*
G01X1726365Y539393D02*
X1717947Y549609D01*
G01X1717288Y548599D02*
X1715988Y548965D01*
G01X1719253Y551964D02*
X1728921Y540232D01*
G01X1718594Y550955D02*
X1727935Y539618D01*
G01X1728921Y540232D02*
X1734259Y528418D01*
G01X1727935Y539618D02*
X1733379Y527570D01*
G01X1713172Y573637D02*
X1716191Y564037D01*
G01X1715133Y563564D02*
X1719457Y556277D01*
G01X1716191Y564037D02*
X1720251Y557193D01*
G01X1719457Y556277D02*
X1722319Y555091D01*
G01X1720251Y557193D02*
X1723111Y556008D01*
G01X1722319Y555091D02*
X1729849Y542507D01*
G01X1723111Y556008D02*
X1730873Y543036D01*
G01X1729849Y542507D02*
X1735410Y529872D01*
G01X1730873Y543036D02*
X1736298Y530710D01*
G01X1774364Y461828D02*
X1776387Y463851D01*
G01X1775237Y466023D02*
Y464328D01*
G01X1776387Y463851D02*
Y465546D01*
G01X1779587Y464327D02*
Y466023D01*
G01X1778437Y465546D02*
Y463850D01*
G01X1780937Y462977D02*
X1779587Y464327D01*
G01X1778437Y463850D02*
X1780460Y461827D01*
G01X1785672Y462977D02*
X1780937D01*
G01X1780460Y461827D02*
X1786149D01*
G01X1787022Y464327D02*
X1785672Y462977D01*
G01X1786149Y461827D02*
X1788172Y463850D01*
G01X1787022Y469948D02*
Y464327D01*
G01X1788172Y463850D02*
Y469471D01*
G01X1791772Y464266D02*
Y469948D01*
G01X1790622Y469471D02*
Y463789D01*
G01X1793122Y462916D02*
X1791772Y464266D01*
G01X1790622Y463789D02*
X1792645Y461766D01*
G01X1795865Y462916D02*
X1793122D01*
G01X1792645Y461766D02*
X1796342D01*
G01X1799737Y466788D02*
X1795865Y462916D01*
G01X1796342Y461766D02*
X1800887Y466311D01*
G01X1805837Y464639D02*
X1804487Y465989D01*
G01X1803337Y465512D02*
X1805360Y463489D01*
G01X1810187Y464639D02*
X1805837D01*
G01X1805360Y463489D02*
X1810664D01*
G01X1811879Y466331D02*
X1810187Y464639D01*
G01X1810664Y463489D02*
X1813029Y465854D01*
G01X1810664Y463489D02*
X1813029Y465854D01*
G01X1811879Y466331D02*
X1810187Y464639D01*
G01X1805360Y463489D02*
X1810664D01*
G01X1810187Y464639D02*
X1805837D01*
G01X1803337Y465512D02*
X1805360Y463489D01*
G01X1805837Y464639D02*
X1804487Y465989D01*
G01X1796342Y461766D02*
X1800887Y466311D01*
G01X1799737Y466788D02*
X1795865Y462916D01*
G01X1792645Y461766D02*
X1796342D01*
G01X1795865Y462916D02*
X1793122D01*
G01X1790622Y463789D02*
X1792645Y461766D01*
G01X1793122Y462916D02*
X1791772Y464266D01*
G01X1790622Y469471D02*
Y463789D01*
G01X1791772Y464266D02*
Y469948D01*
G01X1788172Y463850D02*
Y469471D01*
G01X1787022Y469948D02*
Y464327D01*
G01X1786149Y461827D02*
X1788172Y463850D01*
G01X1787022Y464327D02*
X1785672Y462977D01*
G01X1780460Y461827D02*
X1786149D01*
G01X1785672Y462977D02*
X1780937D01*
G01X1778437Y463850D02*
X1780460Y461827D01*
G01X1780937Y462977D02*
X1779587Y464327D01*
G01X1778437Y465546D02*
Y463850D01*
G01X1779587Y464327D02*
Y466023D01*
G01X1776387Y463851D02*
Y465546D01*
G01X1775237Y466023D02*
Y464328D01*
G01X1774364Y461828D02*
X1776387Y463851D01*
G01X1829513Y465666D02*
X1831086Y464093D01*
G01D02*
X1836216D01*
G01X1837957Y456555D02*
X1835434D01*
G01X1835911Y457705D02*
X1834861Y458755D01*
G01X1835434Y456555D02*
X1833711Y458278D01*
G01X1834861Y458755D02*
Y459978D01*
G01X1833711Y458278D02*
Y459501D01*
G01X1834861Y459978D02*
X1833738Y461101D01*
G01X1833711Y459501D02*
X1833261Y459951D01*
G01X1833738Y461101D02*
X1828988D01*
G01X1833261Y459951D02*
X1828511D01*
G01X1828988Y461101D02*
X1827363Y462726D01*
G01X1828511Y459951D02*
X1826213Y462249D01*
G01X1827363Y462726D02*
Y463912D01*
G01X1826213Y462249D02*
Y463435D01*
G01X1827363Y463912D02*
X1826340Y464935D01*
G01X1826213Y463435D02*
X1825863Y463785D01*
G01D02*
X1824113D01*
G01X1823636Y464935D02*
X1822613Y463912D01*
G01X1824113Y463785D02*
X1823763Y463435D01*
G01X1822613Y463912D02*
Y462428D01*
G01X1823763Y463435D02*
Y461951D01*
G01X1822613Y462428D02*
X1817286Y457101D01*
G01X1823763Y461951D02*
X1817763Y455951D01*
G01X1817286Y457101D02*
X1805217D01*
G01X1817763Y455951D02*
X1804740D01*
G01X1805217Y457101D02*
X1802837Y459481D01*
G01X1804740Y455951D02*
X1802360Y458331D01*
G01X1802837Y459481D02*
X1799260D01*
G01X1802360Y458331D02*
X1799737D01*
G01X1799260Y459481D02*
X1796880Y457101D01*
G01X1799737Y458331D02*
X1797357Y455951D01*
G01X1796880Y457101D02*
X1794253D01*
G01X1797357Y455951D02*
X1793776D01*
G01X1794253Y457101D02*
X1791873Y459481D01*
G01X1793776Y455951D02*
X1791396Y458331D01*
G01X1791873Y459481D02*
X1788296D01*
G01X1791396Y458331D02*
X1788773D01*
G01X1788296Y459481D02*
X1785916Y457101D01*
G01X1788773Y458331D02*
X1786393Y455951D01*
G01X1785916Y457101D02*
X1783289D01*
G01X1786393Y455951D02*
X1782812D01*
G01X1783289Y457101D02*
X1780909Y459481D01*
G01X1782812Y455951D02*
X1780432Y458331D01*
G01X1780909Y459481D02*
X1777332D01*
G01X1780432Y458331D02*
X1777809D01*
G01X1777332Y459481D02*
X1774952Y457101D01*
G01X1777809Y458331D02*
X1775429Y455951D01*
G01X1829513Y465666D02*
X1831086Y464093D01*
G01D02*
X1836216D01*
G01X1837957Y456555D02*
X1835434D01*
G01D02*
X1833711Y458278D01*
G01X1835911Y457705D02*
X1834861Y458755D01*
G01X1833711Y458278D02*
Y459501D01*
G01X1834861Y458755D02*
Y459978D01*
G01X1833711Y459501D02*
X1833261Y459951D01*
G01X1834861Y459978D02*
X1833738Y461101D01*
G01X1833261Y459951D02*
X1828511D01*
G01X1833738Y461101D02*
X1828988D01*
G01X1828511Y459951D02*
X1826213Y462249D01*
G01X1828988Y461101D02*
X1827363Y462726D01*
G01X1826213Y462249D02*
Y463435D01*
G01X1827363Y462726D02*
Y463912D01*
G01X1826213Y463435D02*
X1825863Y463785D01*
G01X1827363Y463912D02*
X1826340Y464935D01*
G01X1825863Y463785D02*
X1824113D01*
G01D02*
X1823763Y463435D01*
G01X1823636Y464935D02*
X1822613Y463912D01*
G01X1823763Y463435D02*
Y461951D01*
G01X1822613Y463912D02*
Y462428D01*
G01X1823763Y461951D02*
X1817763Y455951D01*
G01X1822613Y462428D02*
X1817286Y457101D01*
G01X1817763Y455951D02*
X1804740D01*
G01X1817286Y457101D02*
X1805217D01*
G01X1804740Y455951D02*
X1802360Y458331D01*
G01X1805217Y457101D02*
X1802837Y459481D01*
G01X1802360Y458331D02*
X1799737D01*
G01X1802837Y459481D02*
X1799260D01*
G01X1799737Y458331D02*
X1797357Y455951D01*
G01X1799260Y459481D02*
X1796880Y457101D01*
G01X1797357Y455951D02*
X1793776D01*
G01X1796880Y457101D02*
X1794253D01*
G01X1793776Y455951D02*
X1791396Y458331D01*
G01X1794253Y457101D02*
X1791873Y459481D01*
G01X1791396Y458331D02*
X1788773D01*
G01X1791873Y459481D02*
X1788296D01*
G01X1788773Y458331D02*
X1786393Y455951D01*
G01X1788296Y459481D02*
X1785916Y457101D01*
G01X1786393Y455951D02*
X1782812D01*
G01X1785916Y457101D02*
X1783289D01*
G01X1782812Y455951D02*
X1780432Y458331D01*
G01X1783289Y457101D02*
X1780909Y459481D01*
G01X1780432Y458331D02*
X1777809D01*
G01X1780909Y459481D02*
X1777332D01*
G01X1777809Y458331D02*
X1775429Y455951D01*
G01X1777332Y459481D02*
X1774952Y457101D01*
G01X1775869Y469270D02*
X1777350Y470751D01*
G01X1775392Y470420D02*
X1776200Y471228D01*
G01X1777350Y470751D02*
Y474549D01*
G01X1776200Y471228D02*
Y474421D01*
G01X1774015Y486157D02*
X1786623Y473550D01*
G01X1774991Y486809D02*
X1781964Y479836D01*
G01X1774015Y486157D02*
X1786623Y473550D01*
G01X1781964Y479836D02*
X1782602D01*
G01X1774015Y486157D02*
X1786623Y473550D01*
G01X1783556Y478244D02*
X1784510Y477290D01*
G01X1774015Y486157D02*
X1786623Y473550D01*
G01X1784510Y477290D02*
X1785148D01*
G01X1774015Y486157D02*
X1786623Y473550D01*
G01X1786102Y475698D02*
X1787100Y474700D01*
G01X1786623Y473550D02*
X1790849D01*
G01X1787100Y474700D02*
X1790372D01*
G01X1790849Y473550D02*
X1793050Y475751D01*
G01X1790372Y474700D02*
X1791900Y476228D01*
G01X1793050Y475751D02*
Y478850D01*
G01X1791900Y476228D02*
Y478850D01*
G01X1804600Y474405D02*
Y477256D01*
G01X1803450Y474405D02*
Y476779D01*
G01X1804600Y477256D02*
X1800904Y480952D01*
G01X1803450Y476779D02*
X1800252Y479976D01*
G01X1800904Y480952D02*
X1795234Y483300D01*
G01X1800252Y479976D02*
X1795005Y482150D01*
G01X1795234Y483300D02*
X1782600D01*
G01X1795005Y482150D02*
X1782123D01*
G01X1782600Y483300D02*
X1777688Y488212D01*
G01X1782123Y482150D02*
X1776712Y487560D01*
G01X1777688Y488212D02*
X1774349Y496273D01*
G01X1774679Y503360D02*
X1780510Y489290D01*
G01X1779534Y488638D02*
X1782922Y485250D01*
G01X1780510Y489290D02*
X1783399Y486400D01*
G01X1782922Y485250D02*
X1795976D01*
G01X1783399Y486400D02*
X1796205D01*
G01X1795976Y485250D02*
X1802902Y482380D01*
G01X1796205Y486400D02*
X1799858Y484887D01*
G01X1795976Y485250D02*
X1802902Y482380D01*
G01X1802307Y483873D02*
X1803554Y483356D01*
G01X1802902Y482380D02*
X1810433Y474850D01*
G01X1803554Y483356D02*
X1804730Y482180D01*
G01X1802902Y482380D02*
X1810433Y474850D01*
G01X1804730Y482180D02*
X1805374D01*
G01X1802902Y482380D02*
X1810433Y474850D01*
G01X1806328Y480582D02*
X1807298Y479612D01*
G01X1802902Y482380D02*
X1810433Y474850D01*
G01X1807298Y479612D02*
X1807862D01*
G01X1802902Y482380D02*
X1810433Y474850D01*
G01X1808816Y478094D02*
X1810910Y476000D01*
G01X1810433Y474850D02*
X1814049D01*
G01X1810910Y476000D02*
X1813572D01*
G01X1814049Y474850D02*
X1815475Y476276D01*
G01X1813572Y476000D02*
X1814325Y476753D01*
G01X1815475Y476276D02*
Y477775D01*
G01X1814325Y476753D02*
Y477775D01*
G01X1776096Y506647D02*
X1805365Y500830D01*
G01X1775619Y505568D02*
X1793147Y502085D01*
G01X1776096Y506647D02*
X1805365Y500830D01*
G01X1795746Y501568D02*
X1797070Y501305D01*
G01X1776096Y506647D02*
X1805365Y500830D01*
G01X1799669Y500789D02*
X1800993Y500526D01*
G01X1776096Y506647D02*
X1805365Y500830D01*
G01X1803592Y500009D02*
X1804916Y499746D01*
G01X1805365Y500830D02*
X1816150Y493627D01*
G01X1804916Y499746D02*
X1806039Y498996D01*
G01X1805365Y500830D02*
X1816150Y493627D01*
G01X1807341Y497345D02*
X1808242Y497525D01*
G01X1805365Y500830D02*
X1816150Y493627D01*
G01X1808242Y497525D02*
X1809365Y496775D01*
G01X1805365Y500830D02*
X1816150Y493627D01*
G01X1810667Y495124D02*
X1811568Y495304D01*
G01X1805365Y500830D02*
X1816150Y493627D01*
G01X1811568Y495304D02*
X1815000Y493012D01*
G01X1816150Y493627D02*
Y487377D01*
G01X1815000Y493012D02*
Y486900D01*
G01X1816150Y487377D02*
X1818277Y485250D01*
G01X1815000Y486900D02*
X1817800Y484100D01*
G01X1818277Y485250D02*
X1822377D01*
G01X1817800Y484100D02*
X1821900D01*
G01X1822377Y485250D02*
X1828075Y479552D01*
G01X1821900Y484100D02*
X1826925Y479075D01*
G01X1828075Y479552D02*
Y477565D01*
G01X1826925Y479075D02*
Y477585D01*
G01X1775392Y470420D02*
X1776200Y471228D01*
G01X1775869Y469270D02*
X1777350Y470751D01*
G01X1776200Y471228D02*
Y474421D01*
G01X1777350Y470751D02*
Y474549D01*
G01X1774991Y486809D02*
X1781964Y479836D01*
G01D02*
X1782602D01*
G01X1783556Y478244D02*
X1784510Y477290D01*
G01D02*
X1785148D01*
G01X1786102Y475698D02*
X1787100Y474700D01*
G01X1774015Y486157D02*
X1786623Y473550D01*
G01X1787100Y474700D02*
X1790372D01*
G01X1786623Y473550D02*
X1790849D01*
G01X1790372Y474700D02*
X1791900Y476228D01*
G01X1790849Y473550D02*
X1793050Y475751D01*
G01X1791900Y476228D02*
Y478850D01*
G01X1793050Y475751D02*
Y478850D01*
G01X1803450Y474405D02*
Y476779D01*
G01X1804600Y474405D02*
Y477256D01*
G01X1803450Y476779D02*
X1800252Y479976D01*
G01X1804600Y477256D02*
X1800904Y480952D01*
G01X1800252Y479976D02*
X1795005Y482150D01*
G01X1800904Y480952D02*
X1795234Y483300D01*
G01X1795005Y482150D02*
X1782123D01*
G01X1795234Y483300D02*
X1782600D01*
G01X1782123Y482150D02*
X1776712Y487560D01*
G01X1782600Y483300D02*
X1777688Y488212D01*
G01D02*
X1774349Y496273D01*
G01X1774679Y503360D02*
X1780510Y489290D01*
G01D02*
X1783399Y486400D01*
G01X1779534Y488638D02*
X1782922Y485250D01*
G01X1783399Y486400D02*
X1796205D01*
G01X1782922Y485250D02*
X1795976D01*
G01X1796205Y486400D02*
X1799858Y484887D01*
G01X1802307Y483873D02*
X1803554Y483356D01*
G01X1795976Y485250D02*
X1802902Y482380D01*
G01X1803554Y483356D02*
X1804730Y482180D01*
G01D02*
X1805374D01*
G01X1806328Y480582D02*
X1807298Y479612D01*
G01D02*
X1807862D01*
G01X1808816Y478094D02*
X1810910Y476000D01*
G01X1802902Y482380D02*
X1810433Y474850D01*
G01X1810910Y476000D02*
X1813572D01*
G01X1810433Y474850D02*
X1814049D01*
G01X1813572Y476000D02*
X1814325Y476753D01*
G01X1814049Y474850D02*
X1815475Y476276D01*
G01X1814325Y476753D02*
Y477775D01*
G01X1815475Y476276D02*
Y477775D01*
G01X1775619Y505568D02*
X1793147Y502085D01*
G01X1795746Y501568D02*
X1797070Y501305D01*
G01X1799669Y500789D02*
X1800993Y500526D01*
G01X1803592Y500009D02*
X1804916Y499746D01*
G01X1776096Y506647D02*
X1805365Y500830D01*
G01X1804916Y499746D02*
X1806039Y498996D01*
G01X1807341Y497345D02*
X1808242Y497525D01*
G01D02*
X1809365Y496775D01*
G01X1810667Y495124D02*
X1811568Y495304D01*
G01D02*
X1815000Y493012D01*
G01X1805365Y500830D02*
X1816150Y493627D01*
G01X1815000Y493012D02*
Y486900D01*
G01X1816150Y493627D02*
Y487377D01*
G01X1815000Y486900D02*
X1817800Y484100D01*
G01X1816150Y487377D02*
X1818277Y485250D01*
G01X1817800Y484100D02*
X1821900D01*
G01X1818277Y485250D02*
X1822377D01*
G01X1821900Y484100D02*
X1826925Y479075D01*
G01X1822377Y485250D02*
X1828075Y479552D01*
G01X1826925Y479075D02*
Y477585D01*
G01X1828075Y479552D02*
Y477565D01*
G01X1776360Y467146D02*
X1775237Y466023D01*
G01X1776387Y465546D02*
X1776837Y465996D01*
G01X1778464Y467146D02*
X1776360D01*
G01X1776837Y465996D02*
X1777987D01*
G01X1779587Y466023D02*
X1778464Y467146D01*
G01X1777987Y465996D02*
X1778437Y465546D01*
G01X1788145Y471071D02*
X1787022Y469948D01*
G01X1788172Y469471D02*
X1788622Y469921D01*
G01X1790649Y471071D02*
X1788145D01*
G01X1788622Y469921D02*
X1790172D01*
G01X1791772Y469948D02*
X1790649Y471071D01*
G01X1790172Y469921D02*
X1790622Y469471D01*
G01X1799737Y467877D02*
Y466788D01*
G01X1800887Y466311D02*
Y467400D01*
G01X1800860Y469000D02*
X1799737Y467877D01*
G01X1800887Y467400D02*
X1801337Y467850D01*
G01X1803364Y469000D02*
X1800860D01*
G01X1801337Y467850D02*
X1802887D01*
G01X1804487Y467877D02*
X1803364Y469000D01*
G01X1802887Y467850D02*
X1803337Y467400D01*
G01X1804487Y465989D02*
Y467877D01*
G01X1803337Y467400D02*
Y465512D01*
G01X1811879Y467909D02*
Y466331D01*
G01X1813029Y465854D02*
Y468386D01*
G01X1810285Y469503D02*
X1811879Y467909D01*
G01X1813029Y468386D02*
X1811435Y469980D01*
G01X1810285Y471091D02*
Y469503D01*
G01X1811435Y469980D02*
Y470614D01*
G01X1811776Y472582D02*
X1810285Y471091D01*
G01X1811435Y470614D02*
X1812253Y471432D01*
G01X1815696Y472582D02*
X1811776D01*
G01X1812253Y471432D02*
X1816173D01*
G01X1819511Y476397D02*
X1815696Y472582D01*
G01X1816173Y471432D02*
X1819988Y475247D01*
G01X1822015Y476397D02*
X1819511D01*
G01D02*
X1815696Y472582D01*
G01X1819988Y475247D02*
X1821538D01*
G01X1823138Y475274D02*
X1822015Y476397D01*
G01X1821538Y475247D02*
X1821988Y474797D01*
G01X1823138Y472266D02*
Y475274D01*
G01X1821988Y474797D02*
Y471789D01*
G01X1824488Y470916D02*
X1823138Y472266D01*
G01X1821988Y471789D02*
X1824011Y469766D01*
G01X1826078Y470916D02*
X1824488D01*
G01X1824011Y469766D02*
X1826555D01*
G01X1829418Y474256D02*
X1826078Y470916D01*
G01D02*
X1824488D01*
G01X1826555Y469766D02*
X1829895Y473106D01*
G01X1830939Y474256D02*
X1829418D01*
G01D02*
X1826078Y470916D01*
G01X1829895Y473106D02*
X1831416D01*
G01X1832765Y476082D02*
X1830939Y474256D01*
G01D02*
X1829418D01*
G01X1831416Y473106D02*
X1833915Y475605D01*
G01X1832765Y494066D02*
Y476082D01*
G01X1833915Y475605D02*
Y481589D01*
G01X1832765Y494066D02*
Y476082D01*
G01X1833915Y484239D02*
Y485589D01*
G01X1832765Y494066D02*
Y476082D01*
G01X1833915Y488239D02*
Y489589D01*
G01X1832765Y494066D02*
Y476082D01*
G01X1833915Y492239D02*
Y493589D01*
G01X1841198Y502499D02*
X1832765Y494066D01*
G01X1833915Y493589D02*
X1837698Y497372D01*
G01X1841198Y502499D02*
X1832765Y494066D01*
G01X1833915Y493589D02*
X1837698Y497372D01*
G01X1841198Y502499D02*
X1832765Y494066D01*
G01X1833915Y475605D02*
Y481589D01*
G01Y484239D02*
Y485589D01*
G01Y488239D02*
Y489589D01*
G01Y492239D02*
Y493589D01*
G01X1832765Y494066D02*
Y476082D01*
G01X1831416Y473106D02*
X1833915Y475605D01*
G01X1832765Y476082D02*
X1830939Y474256D01*
G01X1829895Y473106D02*
X1831416D01*
G01D02*
X1833915Y475605D01*
G01X1830939Y474256D02*
X1829418D01*
G01X1826555Y469766D02*
X1829895Y473106D01*
G01D02*
X1831416D01*
G01X1829418Y474256D02*
X1826078Y470916D01*
G01X1824011Y469766D02*
X1826555D01*
G01D02*
X1829895Y473106D01*
G01X1826078Y470916D02*
X1824488D01*
G01X1821988Y471789D02*
X1824011Y469766D01*
G01X1824488Y470916D02*
X1823138Y472266D01*
G01X1821988Y474797D02*
Y471789D01*
G01X1823138Y472266D02*
Y475274D01*
G01X1821538Y475247D02*
X1821988Y474797D01*
G01X1823138Y475274D02*
X1822015Y476397D01*
G01X1819988Y475247D02*
X1821538D01*
G01X1822015Y476397D02*
X1819511D01*
G01X1816173Y471432D02*
X1819988Y475247D01*
G01D02*
X1821538D01*
G01X1819511Y476397D02*
X1815696Y472582D01*
G01X1812253Y471432D02*
X1816173D01*
G01X1815696Y472582D02*
X1811776D01*
G01X1811435Y470614D02*
X1812253Y471432D01*
G01X1811776Y472582D02*
X1810285Y471091D01*
G01X1811435Y469980D02*
Y470614D01*
G01X1810285Y471091D02*
Y469503D01*
G01X1813029Y468386D02*
X1811435Y469980D01*
G01X1810285Y469503D02*
X1811879Y467909D01*
G01X1813029Y465854D02*
Y468386D01*
G01X1811879Y467909D02*
Y466331D01*
G01X1803337Y467400D02*
Y465512D01*
G01X1804487Y465989D02*
Y467877D01*
G01X1802887Y467850D02*
X1803337Y467400D01*
G01X1804487Y467877D02*
X1803364Y469000D01*
G01X1801337Y467850D02*
X1802887D01*
G01X1803364Y469000D02*
X1800860D01*
G01X1800887Y467400D02*
X1801337Y467850D01*
G01X1800860Y469000D02*
X1799737Y467877D01*
G01X1800887Y466311D02*
Y467400D01*
G01X1799737Y467877D02*
Y466788D01*
G01X1790172Y469921D02*
X1790622Y469471D01*
G01X1791772Y469948D02*
X1790649Y471071D01*
G01X1788622Y469921D02*
X1790172D01*
G01X1790649Y471071D02*
X1788145D01*
G01X1788172Y469471D02*
X1788622Y469921D01*
G01X1788145Y471071D02*
X1787022Y469948D01*
G01X1777987Y465996D02*
X1778437Y465546D01*
G01X1779587Y466023D02*
X1778464Y467146D01*
G01X1776837Y465996D02*
X1777987D01*
G01X1778464Y467146D02*
X1776360D01*
G01X1776387Y465546D02*
X1776837Y465996D01*
G01X1776360Y467146D02*
X1775237Y466023D01*
G01X1844629Y484088D02*
X1829513Y468972D01*
G01X1845106Y482938D02*
X1830663Y468495D01*
G01X1829513Y468972D02*
Y465666D01*
G01X1830663Y468495D02*
Y466143D01*
G01D02*
X1831563Y465243D01*
G01D02*
X1836693D01*
G01X1826340Y464935D02*
X1823636D01*
G01X1845106Y482938D02*
X1830663Y468495D01*
G01X1844629Y484088D02*
X1829513Y468972D01*
G01X1830663Y468495D02*
Y466143D01*
G01X1829513Y468972D02*
Y465666D01*
G01X1830663Y466143D02*
X1831563Y465243D01*
G01D02*
X1836693D01*
G01X1826340Y464935D02*
X1823636D01*
G01X1848896Y460952D02*
Y469922D01*
G01X1847746Y470399D02*
Y461429D01*
G01X1843750Y455806D02*
X1848896Y460952D01*
G01X1847746Y461429D02*
X1842600Y456283D01*
G01X1843750Y455201D02*
Y455806D01*
G01X1842600Y456283D02*
Y455291D01*
G01Y456283D02*
Y455291D01*
G01X1843750Y455201D02*
Y455806D01*
G01X1847746Y461429D02*
X1842600Y456283D01*
G01X1843750Y455806D02*
X1848896Y460952D01*
G01X1847746Y470399D02*
Y461429D01*
G01X1848896Y460952D02*
Y469922D01*
G01X1836216Y464093D02*
X1838530Y461779D01*
G01X1836693Y465243D02*
X1839680Y462256D01*
G01X1838530Y461779D02*
Y458755D01*
G01X1839680Y462256D02*
Y458278D01*
G01X1838530Y458755D02*
X1837480Y457705D01*
G01X1839680Y458278D02*
X1837957Y456555D01*
G01X1837480Y457705D02*
X1835911D01*
G01X1836693Y465243D02*
X1839680Y462256D01*
G01X1836216Y464093D02*
X1838530Y461779D01*
G01X1839680Y462256D02*
Y458278D01*
G01X1838530Y461779D02*
Y458755D01*
G01X1839680Y458278D02*
X1837957Y456555D01*
G01X1838530Y458755D02*
X1837480Y457705D01*
G01D02*
X1835911D01*
G01X1839572Y499246D02*
X1841675Y501349D01*
G01X1847000Y502499D02*
X1841198D01*
G01X1841675Y501349D02*
X1847477D01*
G01X1848550Y504049D02*
X1847000Y502499D01*
G01X1847477Y501349D02*
X1849700Y503572D01*
G01X1848550Y510209D02*
Y504049D01*
G01X1849700Y503572D02*
Y509732D01*
G01X1850256Y511915D02*
X1848550Y510209D01*
G01X1849700Y509732D02*
X1850733Y510765D01*
G01X1856064Y511915D02*
X1850256D01*
G01X1850733Y510765D02*
X1855587D01*
G01X1864725Y503254D02*
X1856064Y511915D01*
G01X1855587Y510765D02*
X1863575Y502777D01*
G01X1864725Y492935D02*
Y503254D01*
G01X1863575Y502777D02*
Y493412D01*
G01X1853926Y482136D02*
X1864725Y492935D01*
G01X1863575Y493412D02*
X1861393Y491230D01*
G01X1853926Y482136D02*
X1864725Y492935D01*
G01X1861393Y491230D02*
X1860474D01*
G01X1853926Y482136D02*
X1864725Y492935D01*
G01X1859520Y489357D02*
X1858565Y488402D01*
G01X1853926Y482136D02*
X1864725Y492935D01*
G01X1858565Y488402D02*
X1857646D01*
G01X1853926Y482136D02*
X1864725Y492935D01*
G01X1856691Y486528D02*
X1855736Y485573D01*
G01X1853926Y482136D02*
X1864725Y492935D01*
G01X1855736Y485573D02*
X1854817D01*
G01X1853926Y482136D02*
X1864725Y492935D01*
G01X1853863Y483700D02*
X1852776Y482613D01*
G01X1853926Y474952D02*
Y482136D01*
G01X1852776Y482613D02*
Y475429D01*
G01X1848896Y469922D02*
X1853926Y474952D01*
G01X1852776Y475429D02*
X1847746Y470399D01*
G01X1852776Y475429D02*
X1847746Y470399D01*
G01X1848896Y469922D02*
X1853926Y474952D01*
G01X1852776Y482613D02*
Y475429D01*
G01X1853926Y474952D02*
Y482136D01*
G01X1863575Y493412D02*
X1861393Y491230D01*
G01D02*
X1860474D01*
G01X1859520Y489357D02*
X1858565Y488402D01*
G01D02*
X1857646D01*
G01X1856691Y486528D02*
X1855736Y485573D01*
G01D02*
X1854817D01*
G01X1853863Y483700D02*
X1852776Y482613D01*
G01X1853926Y482136D02*
X1864725Y492935D01*
G01X1863575Y502777D02*
Y493412D01*
G01X1864725Y492935D02*
Y503254D01*
G01X1855587Y510765D02*
X1863575Y502777D01*
G01X1864725Y503254D02*
X1856064Y511915D01*
G01X1850733Y510765D02*
X1855587D01*
G01X1856064Y511915D02*
X1850256D01*
G01X1849700Y509732D02*
X1850733Y510765D01*
G01X1850256Y511915D02*
X1848550Y510209D01*
G01X1849700Y503572D02*
Y509732D01*
G01X1848550Y510209D02*
Y504049D01*
G01X1847477Y501349D02*
X1849700Y503572D01*
G01X1848550Y504049D02*
X1847000Y502499D01*
G01X1841675Y501349D02*
X1847477D01*
G01X1847000Y502499D02*
X1841198D01*
G01X1839572Y499246D02*
X1841675Y501349D01*
G01X1840932Y469080D02*
Y469717D01*
G01X1839782Y469080D02*
Y470194D01*
G01X1840932Y469717D02*
X1842042Y470827D01*
G01X1839782Y470194D02*
X1841565Y471977D01*
G01X1842042Y470827D02*
X1845538D01*
G01X1841565Y471977D02*
X1845061D01*
G01X1845538Y470827D02*
X1850630Y475919D01*
G01X1845061Y471977D02*
X1846016Y472932D01*
G01X1845538Y470827D02*
X1850630Y475919D01*
G01X1847889Y474805D02*
X1849480Y476396D01*
G01X1850630Y475919D02*
Y483065D01*
G01X1849480Y476396D02*
Y477746D01*
G01X1850630Y475919D02*
Y483065D01*
G01X1849480Y480396D02*
Y482588D01*
G01X1850630Y483065D02*
X1849607Y484088D01*
G01X1849480Y482588D02*
X1849130Y482938D01*
G01X1849607Y484088D02*
X1844629D01*
G01X1849130Y482938D02*
X1845106D01*
G01X1839782Y469080D02*
Y470194D01*
G01X1840932Y469080D02*
Y469717D01*
G01X1839782Y470194D02*
X1841565Y471977D01*
G01X1840932Y469717D02*
X1842042Y470827D01*
G01X1841565Y471977D02*
X1845061D01*
G01X1842042Y470827D02*
X1845538D01*
G01X1845061Y471977D02*
X1846016Y472932D01*
G01X1847889Y474805D02*
X1849480Y476396D01*
G01X1845538Y470827D02*
X1850630Y475919D01*
G01X1849480Y476396D02*
Y477746D01*
G01Y480396D02*
Y482588D01*
G01X1850630Y475919D02*
Y483065D01*
G01X1849480Y482588D02*
X1849130Y482938D01*
G01X1850630Y483065D02*
X1849607Y484088D01*
G01X1849130Y482938D02*
X1845106D01*
G01X1849607Y484088D02*
X1844629D01*
G54D14*
G01X141880Y-4651D02*
X142989D01*
G01D02*
X144012Y-3628D01*
G01X141880Y-7260D02*
X145072Y-4068D01*
G01X144012Y-3628D02*
Y-1007D01*
G01Y2907D02*
Y4280D01*
G01Y8106D02*
Y10881D01*
G01X145072Y-4068D02*
Y11322D01*
G01X144012Y10881D02*
X142978Y11915D01*
G01D02*
X141880D01*
G01X145072Y11322D02*
X141880Y14514D01*
G01X140626Y18835D02*
Y21231D01*
G01X141686Y19920D02*
Y20788D01*
G01X140626Y21231D02*
X143900Y24505D01*
G01X141686Y20788D02*
X144960Y24062D01*
G01X143900Y24505D02*
Y97960D01*
G01X144960Y24062D02*
Y98403D01*
G01X141880Y-4651D02*
X142989D01*
G01D02*
X144012Y-3628D01*
G01X141880Y-7260D02*
X145072Y-4068D01*
G01X144012Y-3628D02*
Y-1007D01*
G01Y2907D02*
Y4280D01*
G01Y8106D02*
Y10881D01*
G01X145072Y-4068D02*
Y11322D01*
G01X144012Y10881D02*
X142978Y11915D01*
G01D02*
X141880D01*
G01X145072Y11322D02*
X141880Y14514D01*
G01X140626Y18835D02*
Y21231D01*
G01X141686Y19920D02*
Y20788D01*
G01X140626Y21231D02*
X143900Y24505D01*
G01X141686Y20788D02*
X144960Y24062D01*
G01X143900Y24505D02*
Y97960D01*
G01X144960Y24062D02*
Y98403D01*
G01X137599Y-5220D02*
X138115D01*
G01X137576Y-6280D02*
X138558D01*
G01X138115Y-5220D02*
X138826Y-4509D01*
G01X138558Y-6280D02*
X139886Y-4952D01*
G01X138826Y-4509D02*
Y-1220D01*
G01Y3120D02*
Y4080D01*
G01Y8220D02*
Y10753D01*
G01X139886Y-4952D02*
Y11194D01*
G01X138826Y10753D02*
X137879Y11700D01*
G01X139886Y11194D02*
X136780Y14300D01*
G01X134926Y13554D02*
Y21131D01*
G01X135986Y19620D02*
Y20688D01*
G01X134926Y21131D02*
X138800Y25005D01*
G01X135986Y20688D02*
X139860Y24562D01*
G01X138800Y25005D02*
Y78979D01*
G01X139860Y24562D02*
Y37780D01*
G01X138800Y25005D02*
Y78979D01*
G01Y25005D02*
Y78979D01*
G01Y25005D02*
Y78979D01*
G01Y25005D02*
Y78979D01*
G01X137599Y-5220D02*
X138115D01*
G01X137576Y-6280D02*
X138558D01*
G01X138115Y-5220D02*
X138826Y-4509D01*
G01X138558Y-6280D02*
X139886Y-4952D01*
G01X138826Y-4509D02*
Y-1220D01*
G01Y3120D02*
Y4080D01*
G01Y8220D02*
Y10753D01*
G01X139886Y-4952D02*
Y11194D01*
G01X138826Y10753D02*
X137879Y11700D01*
G01X139886Y11194D02*
X136780Y14300D01*
G01X134926Y13554D02*
Y21131D01*
G01X135986Y19620D02*
Y20688D01*
G01X134926Y21131D02*
X138800Y25005D01*
G01X135986Y20688D02*
X139860Y24562D01*
G01X138800Y25005D02*
Y78979D01*
G01X139860Y24562D02*
Y37780D01*
G01X138800Y25005D02*
Y78979D01*
G01Y25005D02*
Y78979D01*
G01Y25005D02*
Y78979D01*
G01Y25005D02*
Y78979D01*
G01X141880Y-7260D02*
X145072Y-4068D01*
G01X141880Y-4651D02*
X142989D01*
G01X141880Y-7260D02*
X145072Y-4068D01*
G01X142989Y-4651D02*
X144012Y-3628D01*
G01X145072Y-4068D02*
Y11322D01*
G01X144012Y-3628D02*
Y-1007D01*
G01X145072Y-4068D02*
Y11322D01*
G01X144012Y2907D02*
Y4280D01*
G01X145072Y-4068D02*
Y11322D01*
G01X144012Y8106D02*
Y10881D01*
G01X145072Y11322D02*
X141880Y14514D01*
G01X144012Y10881D02*
X142978Y11915D01*
G01X145072Y11322D02*
X141880Y14514D01*
G01X142978Y11915D02*
X141880D01*
G01X141686Y19920D02*
Y20788D01*
G01X140626Y18835D02*
Y21231D01*
G01X141686Y20788D02*
X144960Y24062D01*
G01X140626Y21231D02*
X143900Y24505D01*
G01X144960Y24062D02*
Y98403D01*
G01X143900Y24505D02*
Y97960D01*
G01X141880Y-7260D02*
X145072Y-4068D01*
G01X141880Y-4651D02*
X142989D01*
G01X141880Y-7260D02*
X145072Y-4068D01*
G01X142989Y-4651D02*
X144012Y-3628D01*
G01X145072Y-4068D02*
Y11322D01*
G01X144012Y-3628D02*
Y-1007D01*
G01X145072Y-4068D02*
Y11322D01*
G01X144012Y2907D02*
Y4280D01*
G01X145072Y-4068D02*
Y11322D01*
G01X144012Y8106D02*
Y10881D01*
G01X145072Y11322D02*
X141880Y14514D01*
G01X144012Y10881D02*
X142978Y11915D01*
G01X145072Y11322D02*
X141880Y14514D01*
G01X142978Y11915D02*
X141880D01*
G01X141686Y19920D02*
Y20788D01*
G01X140626Y18835D02*
Y21231D01*
G01X141686Y20788D02*
X144960Y24062D01*
G01X140626Y21231D02*
X143900Y24505D01*
G01X144960Y24062D02*
Y98403D01*
G01X143900Y24505D02*
Y97960D01*
G01X137576Y-6280D02*
X138558D01*
G01X137599Y-5220D02*
X138115D01*
G01X138558Y-6280D02*
X139886Y-4952D01*
G01X138115Y-5220D02*
X138826Y-4509D01*
G01X139886Y-4952D02*
Y11194D01*
G01X138826Y-4509D02*
Y-1220D01*
G01X139886Y-4952D02*
Y11194D01*
G01X138826Y3120D02*
Y4080D01*
G01X139886Y-4952D02*
Y11194D01*
G01X138826Y8220D02*
Y10753D01*
G01X139886Y11194D02*
X136780Y14300D01*
G01X138826Y10753D02*
X137879Y11700D01*
G01X135986Y19620D02*
Y20688D01*
G01X134926Y13554D02*
Y21131D01*
G01X135986Y20688D02*
X139860Y24562D01*
G01X134926Y21131D02*
X138800Y25005D01*
G01X139860Y24562D02*
Y37780D01*
G01X138800Y25005D02*
Y78979D01*
G01X137576Y-6280D02*
X138558D01*
G01X137599Y-5220D02*
X138115D01*
G01X138558Y-6280D02*
X139886Y-4952D01*
G01X138115Y-5220D02*
X138826Y-4509D01*
G01X139886Y-4952D02*
Y11194D01*
G01X138826Y-4509D02*
Y-1220D01*
G01X139886Y-4952D02*
Y11194D01*
G01X138826Y3120D02*
Y4080D01*
G01X139886Y-4952D02*
Y11194D01*
G01X138826Y8220D02*
Y10753D01*
G01X139886Y11194D02*
X136780Y14300D01*
G01X138826Y10753D02*
X137879Y11700D01*
G01X135986Y19620D02*
Y20688D01*
G01X134926Y13554D02*
Y21131D01*
G01X135986Y20688D02*
X139860Y24562D01*
G01X134926Y21131D02*
X138800Y25005D01*
G01X139860Y24562D02*
Y37780D01*
G01X138800Y25005D02*
Y78979D01*
G01X139860Y40020D02*
Y40780D01*
G01Y43020D02*
Y43780D01*
G01Y46020D02*
Y55680D01*
G01Y57920D02*
Y78536D01*
G01X138800Y78979D02*
X139712Y79891D01*
G01X139860Y78536D02*
X140772Y79448D01*
G01X139712Y79891D02*
Y82497D01*
G01X140772Y79448D02*
Y82940D01*
G01X139712Y82497D02*
X138800Y83409D01*
G01X140772Y82940D02*
X139860Y83852D01*
G01X138800Y83409D02*
Y95960D01*
G01X139860Y83852D02*
Y96403D01*
G01Y40020D02*
Y40780D01*
G01Y43020D02*
Y43780D01*
G01Y46020D02*
Y55680D01*
G01Y57920D02*
Y78536D01*
G01X138800Y78979D02*
X139712Y79891D01*
G01X139860Y78536D02*
X140772Y79448D01*
G01X139712Y79891D02*
Y82497D01*
G01X140772Y79448D02*
Y82940D01*
G01X139712Y82497D02*
X138800Y83409D01*
G01X140772Y82940D02*
X139860Y83852D01*
G01X138800Y83409D02*
Y95960D01*
G01X139860Y83852D02*
Y96403D01*
G01Y40020D02*
Y40780D01*
G01Y43020D02*
Y43780D01*
G01Y46020D02*
Y55680D01*
G01Y57920D02*
Y78536D01*
G01D02*
X140772Y79448D01*
G01X138800Y78979D02*
X139712Y79891D01*
G01X140772Y79448D02*
Y82940D01*
G01X139712Y79891D02*
Y82497D01*
G01X140772Y82940D02*
X139860Y83852D01*
G01X139712Y82497D02*
X138800Y83409D01*
G01X139860Y83852D02*
Y96403D01*
G01X138800Y83409D02*
Y95960D01*
G01X139860Y40020D02*
Y40780D01*
G01Y43020D02*
Y43780D01*
G01Y46020D02*
Y55680D01*
G01Y57920D02*
Y78536D01*
G01D02*
X140772Y79448D01*
G01X138800Y78979D02*
X139712Y79891D01*
G01X140772Y79448D02*
Y82940D01*
G01X139712Y79891D02*
Y82497D01*
G01X140772Y82940D02*
X139860Y83852D01*
G01X139712Y82497D02*
X138800Y83409D01*
G01X139860Y83852D02*
Y96403D01*
G01X138800Y83409D02*
Y95960D01*
G01X143900Y97960D02*
X139412Y102448D01*
G01X144960Y98403D02*
X140472Y102891D01*
G01X139412Y102448D02*
Y127382D01*
G01X140472Y102891D02*
Y126939D01*
G01X139412Y127382D02*
X140901Y128871D01*
G01X140472Y126939D02*
X141344Y127811D01*
G01X140901Y128871D02*
X145056D01*
G01X141344Y127811D02*
X145496D01*
G01X145056Y128871D02*
X145928Y129743D01*
G01X145496Y127811D02*
X146988Y129303D01*
G01X145928Y129743D02*
Y132139D01*
G01X146988Y129303D02*
Y132579D01*
G01X145928Y132139D02*
X144956Y133111D01*
G01X146988Y132579D02*
X145396Y134171D01*
G01X144956Y133111D02*
X141653D01*
G01X145396Y134171D02*
X142093D01*
G01X141653Y133111D02*
X139610Y135154D01*
G01X142093Y134171D02*
X140670Y135594D01*
G01X139610Y135154D02*
Y137961D01*
G01X140670Y135594D02*
Y137521D01*
G01X139610Y137961D02*
X141129Y139480D01*
G01X140670Y137521D02*
X141569Y138420D01*
G01X141129Y139480D02*
X143289D01*
G01X141569Y138420D02*
X143729D01*
G01X143289Y139480D02*
X143900Y140091D01*
G01X143729Y138420D02*
X144960Y139651D01*
G01X143900Y140091D02*
Y148332D01*
G01X144960Y139651D02*
Y147892D01*
G01X143900Y148332D02*
X158311Y162743D01*
G01X144960Y147892D02*
X159371Y162303D01*
G01X143900Y97960D02*
X139412Y102448D01*
G01X144960Y98403D02*
X140472Y102891D01*
G01X139412Y102448D02*
Y127382D01*
G01X140472Y102891D02*
Y126939D01*
G01X139412Y127382D02*
X140901Y128871D01*
G01X140472Y126939D02*
X141344Y127811D01*
G01X140901Y128871D02*
X145056D01*
G01X141344Y127811D02*
X145496D01*
G01X145056Y128871D02*
X145928Y129743D01*
G01X145496Y127811D02*
X146988Y129303D01*
G01X145928Y129743D02*
Y132139D01*
G01X146988Y129303D02*
Y132579D01*
G01X145928Y132139D02*
X144956Y133111D01*
G01X146988Y132579D02*
X145396Y134171D01*
G01X144956Y133111D02*
X141653D01*
G01X145396Y134171D02*
X142093D01*
G01X141653Y133111D02*
X139610Y135154D01*
G01X142093Y134171D02*
X140670Y135594D01*
G01X139610Y135154D02*
Y137961D01*
G01X140670Y135594D02*
Y137521D01*
G01X139610Y137961D02*
X141129Y139480D01*
G01X140670Y137521D02*
X141569Y138420D01*
G01X141129Y139480D02*
X143289D01*
G01X141569Y138420D02*
X143729D01*
G01X143289Y139480D02*
X143900Y140091D01*
G01X143729Y138420D02*
X144960Y139651D01*
G01X143900Y140091D02*
Y148332D01*
G01X144960Y139651D02*
Y147892D01*
G01X143900Y148332D02*
X158311Y162743D01*
G01X144960Y147892D02*
X159371Y162303D01*
G01X138800Y95960D02*
X135612Y99148D01*
G01X139860Y96403D02*
X136672Y99591D01*
G01X135612Y99148D02*
Y129088D01*
G01X136672Y99591D02*
Y110189D01*
G01X135612Y99148D02*
Y129088D01*
G01X136672Y112089D02*
Y113436D01*
G01X135612Y99148D02*
Y129088D01*
G01X136672Y115336D02*
Y117825D01*
G01X135612Y99148D02*
Y129088D01*
G01X136672Y119725D02*
Y122718D01*
G01X135612Y99148D02*
Y129088D01*
G01X136672Y124618D02*
Y128648D01*
G01X135612Y129088D02*
X136957Y130433D01*
G01X136672Y128648D02*
X138017Y129993D01*
G01X136957Y130433D02*
Y132435D01*
G01X138017Y129993D02*
Y132875D01*
G01X136957Y132435D02*
X135612Y133780D01*
G01X138017Y132875D02*
X136672Y134220D01*
G01X135612Y133780D02*
Y141747D01*
G01X136672Y134220D02*
Y141307D01*
G01X135612Y141747D02*
X137104Y143239D01*
G01X136672Y141307D02*
X137544Y142179D01*
G01X137104Y143239D02*
X138303D01*
G01X137544Y142179D02*
X138743D01*
G01X138303Y143239D02*
X139423Y144359D01*
G01X138743Y142179D02*
X140487Y143923D01*
G01X139423Y144359D02*
Y146231D01*
G01X140487Y143923D02*
Y146667D01*
G01X139423Y146231D02*
X137306Y148348D01*
G01X140487Y146667D02*
X138366Y148788D01*
G01X137306Y148348D02*
Y152804D01*
G01X138366Y148788D02*
Y152364D01*
G01X137306Y152804D02*
X138434Y153932D01*
G01X138366Y152364D02*
X138874Y152872D01*
G01X138434Y153932D02*
X145066D01*
G01X138874Y152872D02*
X145506D01*
G01X145066Y153932D02*
X147008Y155874D01*
G01X145506Y152872D02*
X148068Y155434D01*
G01X147008Y155874D02*
Y160868D01*
G01X148068Y155434D02*
Y160428D01*
G01X138800Y95960D02*
X135612Y99148D01*
G01X139860Y96403D02*
X136672Y99591D01*
G01X135612Y99148D02*
Y129088D01*
G01X136672Y99591D02*
Y110189D01*
G01X135612Y99148D02*
Y129088D01*
G01X136672Y112089D02*
Y113436D01*
G01X135612Y99148D02*
Y129088D01*
G01X136672Y115336D02*
Y117825D01*
G01X135612Y99148D02*
Y129088D01*
G01X136672Y119725D02*
Y122718D01*
G01X135612Y99148D02*
Y129088D01*
G01X136672Y124618D02*
Y128648D01*
G01X135612Y129088D02*
X136957Y130433D01*
G01X136672Y128648D02*
X138017Y129993D01*
G01X136957Y130433D02*
Y132435D01*
G01X138017Y129993D02*
Y132875D01*
G01X136957Y132435D02*
X135612Y133780D01*
G01X138017Y132875D02*
X136672Y134220D01*
G01X135612Y133780D02*
Y141747D01*
G01X136672Y134220D02*
Y141307D01*
G01X135612Y141747D02*
X137104Y143239D01*
G01X136672Y141307D02*
X137544Y142179D01*
G01X137104Y143239D02*
X138303D01*
G01X137544Y142179D02*
X138743D01*
G01X138303Y143239D02*
X139423Y144359D01*
G01X138743Y142179D02*
X140487Y143923D01*
G01X139423Y144359D02*
Y146231D01*
G01X140487Y143923D02*
Y146667D01*
G01X139423Y146231D02*
X137306Y148348D01*
G01X140487Y146667D02*
X138366Y148788D01*
G01X137306Y148348D02*
Y152804D01*
G01X138366Y148788D02*
Y152364D01*
G01X137306Y152804D02*
X138434Y153932D01*
G01X138366Y152364D02*
X138874Y152872D01*
G01X138434Y153932D02*
X145066D01*
G01X138874Y152872D02*
X145506D01*
G01X145066Y153932D02*
X147008Y155874D01*
G01X145506Y152872D02*
X148068Y155434D01*
G01X147008Y155874D02*
Y160868D01*
G01X148068Y155434D02*
Y160428D01*
G01X144960Y98403D02*
X140472Y102891D01*
G01X143900Y97960D02*
X139412Y102448D01*
G01X140472Y102891D02*
Y126939D01*
G01X139412Y102448D02*
Y127382D01*
G01X140472Y126939D02*
X141344Y127811D01*
G01X139412Y127382D02*
X140901Y128871D01*
G01X141344Y127811D02*
X145496D01*
G01X140901Y128871D02*
X145056D01*
G01X145496Y127811D02*
X146988Y129303D01*
G01X145056Y128871D02*
X145928Y129743D01*
G01X146988Y129303D02*
Y132579D01*
G01X145928Y129743D02*
Y132139D01*
G01X146988Y132579D02*
X145396Y134171D01*
G01X145928Y132139D02*
X144956Y133111D01*
G01X145396Y134171D02*
X142093D01*
G01X144956Y133111D02*
X141653D01*
G01X142093Y134171D02*
X140670Y135594D01*
G01X141653Y133111D02*
X139610Y135154D01*
G01X140670Y135594D02*
Y137521D01*
G01X139610Y135154D02*
Y137961D01*
G01X140670Y137521D02*
X141569Y138420D01*
G01X139610Y137961D02*
X141129Y139480D01*
G01X141569Y138420D02*
X143729D01*
G01X141129Y139480D02*
X143289D01*
G01X143729Y138420D02*
X144960Y139651D01*
G01X143289Y139480D02*
X143900Y140091D01*
G01X144960Y139651D02*
Y147892D01*
G01X143900Y140091D02*
Y148332D01*
G01X144960Y147892D02*
X159371Y162303D01*
G01X143900Y148332D02*
X158311Y162743D01*
G01X144960Y98403D02*
X140472Y102891D01*
G01X143900Y97960D02*
X139412Y102448D01*
G01X140472Y102891D02*
Y126939D01*
G01X139412Y102448D02*
Y127382D01*
G01X140472Y126939D02*
X141344Y127811D01*
G01X139412Y127382D02*
X140901Y128871D01*
G01X141344Y127811D02*
X145496D01*
G01X140901Y128871D02*
X145056D01*
G01X145496Y127811D02*
X146988Y129303D01*
G01X145056Y128871D02*
X145928Y129743D01*
G01X146988Y129303D02*
Y132579D01*
G01X145928Y129743D02*
Y132139D01*
G01X146988Y132579D02*
X145396Y134171D01*
G01X145928Y132139D02*
X144956Y133111D01*
G01X145396Y134171D02*
X142093D01*
G01X144956Y133111D02*
X141653D01*
G01X142093Y134171D02*
X140670Y135594D01*
G01X141653Y133111D02*
X139610Y135154D01*
G01X140670Y135594D02*
Y137521D01*
G01X139610Y135154D02*
Y137961D01*
G01X140670Y137521D02*
X141569Y138420D01*
G01X139610Y137961D02*
X141129Y139480D01*
G01X141569Y138420D02*
X143729D01*
G01X141129Y139480D02*
X143289D01*
G01X143729Y138420D02*
X144960Y139651D01*
G01X143289Y139480D02*
X143900Y140091D01*
G01X144960Y139651D02*
Y147892D01*
G01X143900Y140091D02*
Y148332D01*
G01X144960Y147892D02*
X159371Y162303D01*
G01X143900Y148332D02*
X158311Y162743D01*
G01X139860Y96403D02*
X136672Y99591D01*
G01X138800Y95960D02*
X135612Y99148D01*
G01X136672Y99591D02*
Y110189D01*
G01Y112089D02*
Y113436D01*
G01Y115336D02*
Y117825D01*
G01Y119725D02*
Y122718D01*
G01Y124618D02*
Y128648D01*
G01X135612Y99148D02*
Y129088D01*
G01X136672Y128648D02*
X138017Y129993D01*
G01X135612Y129088D02*
X136957Y130433D01*
G01X138017Y129993D02*
Y132875D01*
G01X136957Y130433D02*
Y132435D01*
G01X138017Y132875D02*
X136672Y134220D01*
G01X136957Y132435D02*
X135612Y133780D01*
G01X136672Y134220D02*
Y141307D01*
G01X135612Y133780D02*
Y141747D01*
G01X136672Y141307D02*
X137544Y142179D01*
G01X135612Y141747D02*
X137104Y143239D01*
G01X137544Y142179D02*
X138743D01*
G01X137104Y143239D02*
X138303D01*
G01X138743Y142179D02*
X140487Y143923D01*
G01X138303Y143239D02*
X139423Y144359D01*
G01X140487Y143923D02*
Y146667D01*
G01X139423Y144359D02*
Y146231D01*
G01X140487Y146667D02*
X138366Y148788D01*
G01X139423Y146231D02*
X137306Y148348D01*
G01X138366Y148788D02*
Y152364D01*
G01X137306Y148348D02*
Y152804D01*
G01X138366Y152364D02*
X138874Y152872D01*
G01X137306Y152804D02*
X138434Y153932D01*
G01X138874Y152872D02*
X145506D01*
G01X138434Y153932D02*
X145066D01*
G01X145506Y152872D02*
X148068Y155434D01*
G01X145066Y153932D02*
X147008Y155874D01*
G01X148068Y155434D02*
Y160428D01*
G01X147008Y155874D02*
Y160868D01*
G01X139860Y96403D02*
X136672Y99591D01*
G01X138800Y95960D02*
X135612Y99148D01*
G01X136672Y99591D02*
Y110189D01*
G01Y112089D02*
Y113436D01*
G01Y115336D02*
Y117825D01*
G01Y119725D02*
Y122718D01*
G01Y124618D02*
Y128648D01*
G01X135612Y99148D02*
Y129088D01*
G01X136672Y128648D02*
X138017Y129993D01*
G01X135612Y129088D02*
X136957Y130433D01*
G01X138017Y129993D02*
Y132875D01*
G01X136957Y130433D02*
Y132435D01*
G01X138017Y132875D02*
X136672Y134220D01*
G01X136957Y132435D02*
X135612Y133780D01*
G01X136672Y134220D02*
Y141307D01*
G01X135612Y133780D02*
Y141747D01*
G01X136672Y141307D02*
X137544Y142179D01*
G01X135612Y141747D02*
X137104Y143239D01*
G01X137544Y142179D02*
X138743D01*
G01X137104Y143239D02*
X138303D01*
G01X138743Y142179D02*
X140487Y143923D01*
G01X138303Y143239D02*
X139423Y144359D01*
G01X140487Y143923D02*
Y146667D01*
G01X139423Y144359D02*
Y146231D01*
G01X140487Y146667D02*
X138366Y148788D01*
G01X139423Y146231D02*
X137306Y148348D01*
G01X138366Y148788D02*
Y152364D01*
G01X137306Y148348D02*
Y152804D01*
G01X138366Y152364D02*
X138874Y152872D01*
G01X137306Y152804D02*
X138434Y153932D01*
G01X138874Y152872D02*
X145506D01*
G01X138434Y153932D02*
X145066D01*
G01X145506Y152872D02*
X148068Y155434D01*
G01X145066Y153932D02*
X147008Y155874D01*
G01X148068Y155434D02*
Y160428D01*
G01X147008Y155874D02*
Y160868D01*
G01X158311Y162743D02*
Y168891D01*
G01X159371Y162303D02*
Y168451D01*
G01X158311Y168891D02*
X241960Y252540D01*
G01X159371Y168451D02*
X232693Y241773D01*
G01X158311Y168891D02*
X241960Y252540D01*
G01X158311Y168891D02*
X241960Y252540D01*
G01X158311Y168891D02*
X241960Y252540D01*
G01X158311Y168891D02*
X241960Y252540D01*
G01X158311Y162743D02*
Y168891D01*
G01X159371Y162303D02*
Y168451D01*
G01X158311Y168891D02*
X241960Y252540D01*
G01X159371Y168451D02*
X232693Y241773D01*
G01X158311Y168891D02*
X241960Y252540D01*
G01X158311Y168891D02*
X241960Y252540D01*
G01X158311Y168891D02*
X241960Y252540D01*
G01X158311Y168891D02*
X241960Y252540D01*
G01X147008Y160868D02*
X148626Y162486D01*
G01X148068Y160428D02*
X149066Y161426D01*
G01X148626Y162486D02*
X152977D01*
G01X149066Y161426D02*
X153417D01*
G01X152977Y162486D02*
X154516Y164025D01*
G01X153417Y161426D02*
X155576Y163585D01*
G01X154516Y164025D02*
Y170538D01*
G01X155576Y163585D02*
Y170098D01*
G01X154516Y170538D02*
X240418Y256440D01*
G01X155576Y170098D02*
X230069Y244591D01*
G01X154516Y170538D02*
X240418Y256440D01*
G01X154516Y170538D02*
X240418Y256440D01*
G01X154516Y170538D02*
X240418Y256440D01*
G01X154516Y170538D02*
X240418Y256440D01*
G01X154516Y170538D02*
X240418Y256440D01*
G01X147008Y160868D02*
X148626Y162486D01*
G01X148068Y160428D02*
X149066Y161426D01*
G01X148626Y162486D02*
X152977D01*
G01X149066Y161426D02*
X153417D01*
G01X152977Y162486D02*
X154516Y164025D01*
G01X153417Y161426D02*
X155576Y163585D01*
G01X154516Y164025D02*
Y170538D01*
G01X155576Y163585D02*
Y170098D01*
G01X154516Y170538D02*
X240418Y256440D01*
G01X155576Y170098D02*
X230069Y244591D01*
G01X154516Y170538D02*
X240418Y256440D01*
G01X154516Y170538D02*
X240418Y256440D01*
G01X154516Y170538D02*
X240418Y256440D01*
G01X154516Y170538D02*
X240418Y256440D01*
G01X154516Y170538D02*
X240418Y256440D01*
G01X159371Y162303D02*
Y168451D01*
G01X158311Y162743D02*
Y168891D01*
G01X159371Y168451D02*
X232693Y241773D01*
G01X158311Y168891D02*
X241960Y252540D01*
G01X159371Y162303D02*
Y168451D01*
G01X158311Y162743D02*
Y168891D01*
G01X159371Y168451D02*
X232693Y241773D01*
G01X158311Y168891D02*
X241960Y252540D01*
G01X148068Y160428D02*
X149066Y161426D01*
G01X147008Y160868D02*
X148626Y162486D01*
G01X149066Y161426D02*
X153417D01*
G01X148626Y162486D02*
X152977D01*
G01X153417Y161426D02*
X155576Y163585D01*
G01X152977Y162486D02*
X154516Y164025D01*
G01X155576Y163585D02*
Y170098D01*
G01X154516Y164025D02*
Y170538D01*
G01X155576Y170098D02*
X230069Y244591D01*
G01X154516Y170538D02*
X240418Y256440D01*
G01X148068Y160428D02*
X149066Y161426D01*
G01X147008Y160868D02*
X148626Y162486D01*
G01X149066Y161426D02*
X153417D01*
G01X148626Y162486D02*
X152977D01*
G01X153417Y161426D02*
X155576Y163585D01*
G01X152977Y162486D02*
X154516Y164025D01*
G01X155576Y163585D02*
Y170098D01*
G01X154516Y164025D02*
Y170538D01*
G01X155576Y170098D02*
X230069Y244591D01*
G01X154516Y170538D02*
X240418Y256440D01*
G01X177792Y410900D02*
X162892Y425800D01*
G01X177352Y409840D02*
X161832Y425360D01*
G01X162892Y425800D02*
Y427800D01*
G01X161832Y425360D02*
Y427360D01*
G01X162892Y427800D02*
X148672Y442020D01*
G01X161832Y427360D02*
X147612Y441580D01*
G01X148672Y442020D02*
Y468520D01*
G01X147612Y441580D02*
Y468080D01*
G01X143050Y465110D02*
X143712Y464448D01*
G01D02*
Y461321D01*
G01X144772Y464891D02*
Y460881D01*
G01X143712Y461321D02*
X142843Y460452D01*
G01X144772Y460881D02*
X143283Y459392D01*
G01X142843Y460452D02*
X139872D01*
G01X143283Y459392D02*
X140312D01*
G01X139872Y460452D02*
X138752Y459332D01*
G01X140312Y459392D02*
X139812Y458892D01*
G01X138752Y459332D02*
Y456012D01*
G01X139812Y458892D02*
Y456452D01*
G01X138752Y456012D02*
X139872Y454892D01*
G01X139812Y456452D02*
X140312Y455952D01*
G01X139872Y454892D02*
X142843D01*
G01X140312Y455952D02*
X143283D01*
G01X142843Y454892D02*
X143712Y454023D01*
G01X143283Y455952D02*
X144772Y454463D01*
G01X143712Y454023D02*
Y441280D01*
G01X144772Y454463D02*
Y441720D01*
G01X143712Y441280D02*
X158832Y426160D01*
G01X144772Y441720D02*
X159892Y426600D01*
G01X158832Y426160D02*
Y424160D01*
G01X159892Y426600D02*
Y424600D01*
G01X158832Y424160D02*
X176752Y406240D01*
G01X159892Y424600D02*
X177192Y407300D01*
G01X177352Y409840D02*
X161832Y425360D01*
G01X177792Y410900D02*
X162892Y425800D01*
G01X161832Y425360D02*
Y427360D01*
G01X162892Y425800D02*
Y427800D01*
G01X161832Y427360D02*
X147612Y441580D01*
G01X162892Y427800D02*
X148672Y442020D01*
G01X147612Y441580D02*
Y468080D01*
G01X148672Y442020D02*
Y468520D01*
G01X143050Y465110D02*
X143712Y464448D01*
G01X144772Y464891D02*
Y460881D01*
G01X143712Y464448D02*
Y461321D01*
G01X144772Y460881D02*
X143283Y459392D01*
G01X143712Y461321D02*
X142843Y460452D01*
G01X143283Y459392D02*
X140312D01*
G01X142843Y460452D02*
X139872D01*
G01X140312Y459392D02*
X139812Y458892D01*
G01X139872Y460452D02*
X138752Y459332D01*
G01X139812Y458892D02*
Y456452D01*
G01X138752Y459332D02*
Y456012D01*
G01X139812Y456452D02*
X140312Y455952D01*
G01X138752Y456012D02*
X139872Y454892D01*
G01X140312Y455952D02*
X143283D01*
G01X139872Y454892D02*
X142843D01*
G01X143283Y455952D02*
X144772Y454463D01*
G01X142843Y454892D02*
X143712Y454023D01*
G01X144772Y454463D02*
Y441720D01*
G01X143712Y454023D02*
Y441280D01*
G01X144772Y441720D02*
X159892Y426600D01*
G01X143712Y441280D02*
X158832Y426160D01*
G01X159892Y426600D02*
Y424600D01*
G01X158832Y426160D02*
Y424160D01*
G01X159892Y424600D02*
X177192Y407300D01*
G01X158832Y424160D02*
X176752Y406240D01*
G01X177792Y410900D02*
X162892Y425800D01*
G01X177352Y409840D02*
X161832Y425360D01*
G01X162892Y425800D02*
Y427800D01*
G01X161832Y425360D02*
Y427360D01*
G01X162892Y427800D02*
X148672Y442020D01*
G01X161832Y427360D02*
X147612Y441580D01*
G01X148672Y442020D02*
Y468520D01*
G01X147612Y441580D02*
Y468080D01*
G01X143050Y465110D02*
X143712Y464448D01*
G01D02*
Y461321D01*
G01X144772Y464891D02*
Y460881D01*
G01X143712Y461321D02*
X142843Y460452D01*
G01X144772Y460881D02*
X143283Y459392D01*
G01X142843Y460452D02*
X139872D01*
G01X143283Y459392D02*
X140312D01*
G01X139872Y460452D02*
X138752Y459332D01*
G01X140312Y459392D02*
X139812Y458892D01*
G01X138752Y459332D02*
Y456012D01*
G01X139812Y458892D02*
Y456452D01*
G01X138752Y456012D02*
X139872Y454892D01*
G01X139812Y456452D02*
X140312Y455952D01*
G01X139872Y454892D02*
X142843D01*
G01X140312Y455952D02*
X143283D01*
G01X142843Y454892D02*
X143712Y454023D01*
G01X143283Y455952D02*
X144772Y454463D01*
G01X143712Y454023D02*
Y441280D01*
G01X144772Y454463D02*
Y441720D01*
G01X143712Y441280D02*
X158832Y426160D01*
G01X144772Y441720D02*
X159892Y426600D01*
G01X158832Y426160D02*
Y424160D01*
G01X159892Y426600D02*
Y424600D01*
G01X158832Y424160D02*
X176752Y406240D01*
G01X159892Y424600D02*
X177192Y407300D01*
G01X177352Y409840D02*
X161832Y425360D01*
G01X177792Y410900D02*
X162892Y425800D01*
G01X161832Y425360D02*
Y427360D01*
G01X162892Y425800D02*
Y427800D01*
G01X161832Y427360D02*
X147612Y441580D01*
G01X162892Y427800D02*
X148672Y442020D01*
G01X147612Y441580D02*
Y468080D01*
G01X148672Y442020D02*
Y468520D01*
G01X143050Y465110D02*
X143712Y464448D01*
G01X144772Y464891D02*
Y460881D01*
G01X143712Y464448D02*
Y461321D01*
G01X144772Y460881D02*
X143283Y459392D01*
G01X143712Y461321D02*
X142843Y460452D01*
G01X143283Y459392D02*
X140312D01*
G01X142843Y460452D02*
X139872D01*
G01X140312Y459392D02*
X139812Y458892D01*
G01X139872Y460452D02*
X138752Y459332D01*
G01X139812Y458892D02*
Y456452D01*
G01X138752Y459332D02*
Y456012D01*
G01X139812Y456452D02*
X140312Y455952D01*
G01X138752Y456012D02*
X139872Y454892D01*
G01X140312Y455952D02*
X143283D01*
G01X139872Y454892D02*
X142843D01*
G01X143283Y455952D02*
X144772Y454463D01*
G01X142843Y454892D02*
X143712Y454023D01*
G01X144772Y454463D02*
Y441720D01*
G01X143712Y454023D02*
Y441280D01*
G01X144772Y441720D02*
X159892Y426600D01*
G01X143712Y441280D02*
X158832Y426160D01*
G01X159892Y426600D02*
Y424600D01*
G01X158832Y426160D02*
Y424160D01*
G01X159892Y424600D02*
X177192Y407300D01*
G01X158832Y424160D02*
X176752Y406240D01*
G01X148672Y468520D02*
X147183Y470009D01*
G01X147612Y468080D02*
X146743Y468949D01*
G01X147183Y470009D02*
X144218D01*
G01X146743Y468949D02*
X143778D01*
G01X144218Y470009D02*
X143316Y470911D01*
G01X143778Y468949D02*
X142256Y470471D01*
G01X143316Y470911D02*
Y472613D01*
G01X142256Y470471D02*
Y473053D01*
G01X143316Y472613D02*
X144152Y473449D01*
G01X142256Y473053D02*
X143712Y474509D01*
G01X144152Y473449D02*
X147180D01*
G01X143712Y474509D02*
X146740D01*
G01X147180Y473449D02*
X148672Y474941D01*
G01X146740Y474509D02*
X147612Y475381D01*
G01X148672Y474941D02*
Y477517D01*
G01X147612Y475381D02*
Y477077D01*
G01X148672Y477517D02*
X147180Y479009D01*
G01X147612Y477077D02*
X146740Y477949D01*
G01X147180Y479009D02*
X143400D01*
G01X146740Y477949D02*
X142960D01*
G01X143400Y479009D02*
X142531Y479878D01*
G01X142960Y477949D02*
X141471Y479438D01*
G01X142531Y479878D02*
Y481580D01*
G01X141471Y479438D02*
Y482020D01*
G01X142531Y481580D02*
X143400Y482449D01*
G01X141471Y482020D02*
X142960Y483509D01*
G01X143400Y482449D02*
X147180D01*
G01X142960Y483509D02*
X146740D01*
G01X147180Y482449D02*
X148672Y483941D01*
G01X146740Y483509D02*
X147612Y484381D01*
G01X148672Y483941D02*
Y486520D01*
G01X147612Y484381D02*
Y486077D01*
G01X148672Y486520D02*
X147183Y488009D01*
G01X147612Y486077D02*
X146740Y486949D01*
G01X147183Y488009D02*
X143044D01*
G01X146740Y486949D02*
X142601D01*
G01X143044Y488009D02*
X142172Y488881D01*
G01X142601Y486949D02*
X141112Y488438D01*
G01X142172Y488881D02*
Y490580D01*
G01X141112Y488438D02*
Y491020D01*
G01X142172Y490580D02*
X143041Y491449D01*
G01X141112Y491020D02*
X142601Y492509D01*
G01X143041Y491449D02*
X147000D01*
G01X142601Y492509D02*
X146560D01*
G01X147000Y491449D02*
X148492Y492941D01*
G01X146560Y492509D02*
X147432Y493381D01*
G01X148492Y492941D02*
Y495628D01*
G01X147432Y493381D02*
Y495188D01*
G01X148492Y495628D02*
X144960Y499160D01*
G01X147432Y495188D02*
X143900Y498720D01*
G01X144960Y499160D02*
Y588070D01*
G01X143900Y498720D02*
Y538169D01*
G01X144960Y499160D02*
Y588070D01*
G01Y499160D02*
Y588070D01*
G01Y499160D02*
Y588070D01*
G01Y499160D02*
Y588070D01*
G01Y499160D02*
Y588070D01*
G01Y499160D02*
Y588070D01*
G01Y499160D02*
Y588070D01*
G01Y499160D02*
Y588070D01*
G01Y499160D02*
Y588070D01*
G01X138800Y587261D02*
Y499080D01*
G01Y587261D02*
Y499080D01*
G01Y587261D02*
Y499080D01*
G01X139860Y579170D02*
Y498637D01*
G01X138800Y499080D02*
X137312Y497592D01*
G01X139860Y498637D02*
X138372Y497149D01*
G01X137312Y497592D02*
Y466709D01*
G01X138372Y497149D02*
Y467152D01*
G01X137312Y466709D02*
X138911Y465110D01*
G01X138372Y467152D02*
X139354Y466170D01*
G01X138911Y465110D02*
X143050D01*
G01X139354Y466170D02*
X143493D01*
G01D02*
X144772Y464891D01*
G01X147612Y468080D02*
X146743Y468949D01*
G01X148672Y468520D02*
X147183Y470009D01*
G01X146743Y468949D02*
X143778D01*
G01X147183Y470009D02*
X144218D01*
G01X143778Y468949D02*
X142256Y470471D01*
G01X144218Y470009D02*
X143316Y470911D01*
G01X142256Y470471D02*
Y473053D01*
G01X143316Y470911D02*
Y472613D01*
G01X142256Y473053D02*
X143712Y474509D01*
G01X143316Y472613D02*
X144152Y473449D01*
G01X143712Y474509D02*
X146740D01*
G01X144152Y473449D02*
X147180D01*
G01X146740Y474509D02*
X147612Y475381D01*
G01X147180Y473449D02*
X148672Y474941D01*
G01X147612Y475381D02*
Y477077D01*
G01X148672Y474941D02*
Y477517D01*
G01X147612Y477077D02*
X146740Y477949D01*
G01X148672Y477517D02*
X147180Y479009D01*
G01X146740Y477949D02*
X142960D01*
G01X147180Y479009D02*
X143400D01*
G01X142960Y477949D02*
X141471Y479438D01*
G01X143400Y479009D02*
X142531Y479878D01*
G01X141471Y479438D02*
Y482020D01*
G01X142531Y479878D02*
Y481580D01*
G01X141471Y482020D02*
X142960Y483509D01*
G01X142531Y481580D02*
X143400Y482449D01*
G01X142960Y483509D02*
X146740D01*
G01X143400Y482449D02*
X147180D01*
G01X146740Y483509D02*
X147612Y484381D01*
G01X147180Y482449D02*
X148672Y483941D01*
G01X147612Y484381D02*
Y486077D01*
G01X148672Y483941D02*
Y486520D01*
G01X147612Y486077D02*
X146740Y486949D01*
G01X148672Y486520D02*
X147183Y488009D01*
G01X146740Y486949D02*
X142601D01*
G01X147183Y488009D02*
X143044D01*
G01X142601Y486949D02*
X141112Y488438D01*
G01X143044Y488009D02*
X142172Y488881D01*
G01X141112Y488438D02*
Y491020D01*
G01X142172Y488881D02*
Y490580D01*
G01X141112Y491020D02*
X142601Y492509D01*
G01X142172Y490580D02*
X143041Y491449D01*
G01X142601Y492509D02*
X146560D01*
G01X143041Y491449D02*
X147000D01*
G01X146560Y492509D02*
X147432Y493381D01*
G01X147000Y491449D02*
X148492Y492941D01*
G01X147432Y493381D02*
Y495188D01*
G01X148492Y492941D02*
Y495628D01*
G01X147432Y495188D02*
X143900Y498720D01*
G01X148492Y495628D02*
X144960Y499160D01*
G01X143900Y498720D02*
Y538169D01*
G01X144960Y499160D02*
Y588070D01*
G01X139860Y579170D02*
Y498637D01*
G01X138800Y587261D02*
Y499080D01*
G01X139860Y498637D02*
X138372Y497149D01*
G01X138800Y499080D02*
X137312Y497592D01*
G01X138372Y497149D02*
Y467152D01*
G01X137312Y497592D02*
Y466709D01*
G01X138372Y467152D02*
X139354Y466170D01*
G01X137312Y466709D02*
X138911Y465110D01*
G01X139354Y466170D02*
X143493D01*
G01X138911Y465110D02*
X143050D01*
G01X143493Y466170D02*
X144772Y464891D01*
G01X148672Y468520D02*
X147183Y470009D01*
G01X147612Y468080D02*
X146743Y468949D01*
G01X147183Y470009D02*
X144218D01*
G01X146743Y468949D02*
X143778D01*
G01X144218Y470009D02*
X143316Y470911D01*
G01X143778Y468949D02*
X142256Y470471D01*
G01X143316Y470911D02*
Y472613D01*
G01X142256Y470471D02*
Y473053D01*
G01X143316Y472613D02*
X144152Y473449D01*
G01X142256Y473053D02*
X143712Y474509D01*
G01X144152Y473449D02*
X147180D01*
G01X143712Y474509D02*
X146740D01*
G01X147180Y473449D02*
X148672Y474941D01*
G01X146740Y474509D02*
X147612Y475381D01*
G01X148672Y474941D02*
Y477517D01*
G01X147612Y475381D02*
Y477077D01*
G01X148672Y477517D02*
X147180Y479009D01*
G01X147612Y477077D02*
X146740Y477949D01*
G01X147180Y479009D02*
X143400D01*
G01X146740Y477949D02*
X142960D01*
G01X143400Y479009D02*
X142531Y479878D01*
G01X142960Y477949D02*
X141471Y479438D01*
G01X142531Y479878D02*
Y481580D01*
G01X141471Y479438D02*
Y482020D01*
G01X142531Y481580D02*
X143400Y482449D01*
G01X141471Y482020D02*
X142960Y483509D01*
G01X143400Y482449D02*
X147180D01*
G01X142960Y483509D02*
X146740D01*
G01X147180Y482449D02*
X148672Y483941D01*
G01X146740Y483509D02*
X147612Y484381D01*
G01X148672Y483941D02*
Y486520D01*
G01X147612Y484381D02*
Y486077D01*
G01X148672Y486520D02*
X147183Y488009D01*
G01X147612Y486077D02*
X146740Y486949D01*
G01X147183Y488009D02*
X143044D01*
G01X146740Y486949D02*
X142601D01*
G01X143044Y488009D02*
X142172Y488881D01*
G01X142601Y486949D02*
X141112Y488438D01*
G01X142172Y488881D02*
Y490580D01*
G01X141112Y488438D02*
Y491020D01*
G01X142172Y490580D02*
X143041Y491449D01*
G01X141112Y491020D02*
X142601Y492509D01*
G01X143041Y491449D02*
X147000D01*
G01X142601Y492509D02*
X146560D01*
G01X147000Y491449D02*
X148492Y492941D01*
G01X146560Y492509D02*
X147432Y493381D01*
G01X148492Y492941D02*
Y495628D01*
G01X147432Y493381D02*
Y495188D01*
G01X148492Y495628D02*
X144960Y499160D01*
G01X147432Y495188D02*
X143900Y498720D01*
G01X144960Y499160D02*
Y588070D01*
G01X143900Y498720D02*
Y538169D01*
G01X144960Y499160D02*
Y588070D01*
G01Y499160D02*
Y588070D01*
G01Y499160D02*
Y588070D01*
G01Y499160D02*
Y588070D01*
G01Y499160D02*
Y588070D01*
G01Y499160D02*
Y588070D01*
G01Y499160D02*
Y588070D01*
G01Y499160D02*
Y588070D01*
G01Y499160D02*
Y588070D01*
G01X138800Y587261D02*
Y499080D01*
G01Y587261D02*
Y499080D01*
G01Y587261D02*
Y499080D01*
G01X139860Y579170D02*
Y498637D01*
G01X138800Y499080D02*
X137312Y497592D01*
G01X139860Y498637D02*
X138372Y497149D01*
G01X137312Y497592D02*
Y466709D01*
G01X138372Y497149D02*
Y467152D01*
G01X137312Y466709D02*
X138911Y465110D01*
G01X138372Y467152D02*
X139354Y466170D01*
G01X138911Y465110D02*
X143050D01*
G01X139354Y466170D02*
X143493D01*
G01D02*
X144772Y464891D01*
G01X147612Y468080D02*
X146743Y468949D01*
G01X148672Y468520D02*
X147183Y470009D01*
G01X146743Y468949D02*
X143778D01*
G01X147183Y470009D02*
X144218D01*
G01X143778Y468949D02*
X142256Y470471D01*
G01X144218Y470009D02*
X143316Y470911D01*
G01X142256Y470471D02*
Y473053D01*
G01X143316Y470911D02*
Y472613D01*
G01X142256Y473053D02*
X143712Y474509D01*
G01X143316Y472613D02*
X144152Y473449D01*
G01X143712Y474509D02*
X146740D01*
G01X144152Y473449D02*
X147180D01*
G01X146740Y474509D02*
X147612Y475381D01*
G01X147180Y473449D02*
X148672Y474941D01*
G01X147612Y475381D02*
Y477077D01*
G01X148672Y474941D02*
Y477517D01*
G01X147612Y477077D02*
X146740Y477949D01*
G01X148672Y477517D02*
X147180Y479009D01*
G01X146740Y477949D02*
X142960D01*
G01X147180Y479009D02*
X143400D01*
G01X142960Y477949D02*
X141471Y479438D01*
G01X143400Y479009D02*
X142531Y479878D01*
G01X141471Y479438D02*
Y482020D01*
G01X142531Y479878D02*
Y481580D01*
G01X141471Y482020D02*
X142960Y483509D01*
G01X142531Y481580D02*
X143400Y482449D01*
G01X142960Y483509D02*
X146740D01*
G01X143400Y482449D02*
X147180D01*
G01X146740Y483509D02*
X147612Y484381D01*
G01X147180Y482449D02*
X148672Y483941D01*
G01X147612Y484381D02*
Y486077D01*
G01X148672Y483941D02*
Y486520D01*
G01X147612Y486077D02*
X146740Y486949D01*
G01X148672Y486520D02*
X147183Y488009D01*
G01X146740Y486949D02*
X142601D01*
G01X147183Y488009D02*
X143044D01*
G01X142601Y486949D02*
X141112Y488438D01*
G01X143044Y488009D02*
X142172Y488881D01*
G01X141112Y488438D02*
Y491020D01*
G01X142172Y488881D02*
Y490580D01*
G01X141112Y491020D02*
X142601Y492509D01*
G01X142172Y490580D02*
X143041Y491449D01*
G01X142601Y492509D02*
X146560D01*
G01X143041Y491449D02*
X147000D01*
G01X146560Y492509D02*
X147432Y493381D01*
G01X147000Y491449D02*
X148492Y492941D01*
G01X147432Y493381D02*
Y495188D01*
G01X148492Y492941D02*
Y495628D01*
G01X147432Y495188D02*
X143900Y498720D01*
G01X148492Y495628D02*
X144960Y499160D01*
G01X143900Y498720D02*
Y538169D01*
G01X144960Y499160D02*
Y588070D01*
G01X139860Y579170D02*
Y498637D01*
G01X138800Y587261D02*
Y499080D01*
G01X139860Y498637D02*
X138372Y497149D01*
G01X138800Y499080D02*
X137312Y497592D01*
G01X138372Y497149D02*
Y467152D01*
G01X137312Y497592D02*
Y466709D01*
G01X138372Y467152D02*
X139354Y466170D01*
G01X137312Y466709D02*
X138911Y465110D01*
G01X139354Y466170D02*
X143493D01*
G01X138911Y465110D02*
X143050D01*
G01X143493Y466170D02*
X144772Y464891D01*
G01X143900Y540115D02*
Y541377D01*
G01Y543387D02*
Y544502D01*
G01Y546742D02*
Y557139D01*
G01Y559379D02*
Y560379D01*
G01Y562619D02*
Y563619D01*
G01Y565859D02*
Y576356D01*
G01Y578596D02*
Y579596D01*
G01Y581836D02*
Y582836D01*
G01Y585076D02*
Y587459D01*
G01X139860Y587872D02*
Y584650D01*
G01Y582410D02*
Y581410D01*
G01X143900Y540115D02*
Y541377D01*
G01Y543387D02*
Y544502D01*
G01Y546742D02*
Y557139D01*
G01Y559379D02*
Y560379D01*
G01Y562619D02*
Y563619D01*
G01Y565859D02*
Y576356D01*
G01Y578596D02*
Y579596D01*
G01Y581836D02*
Y582836D01*
G01Y585076D02*
Y587459D01*
G01X139860Y587872D02*
Y584650D01*
G01Y582410D02*
Y581410D01*
G01X143900Y540115D02*
Y541377D01*
G01Y543387D02*
Y544502D01*
G01Y546742D02*
Y557139D01*
G01Y559379D02*
Y560379D01*
G01Y562619D02*
Y563619D01*
G01Y565859D02*
Y576356D01*
G01Y578596D02*
Y579596D01*
G01Y581836D02*
Y582836D01*
G01Y585076D02*
Y587459D01*
G01X139860Y587872D02*
Y584650D01*
G01Y582410D02*
Y581410D01*
G01X143900Y540115D02*
Y541377D01*
G01Y543387D02*
Y544502D01*
G01Y546742D02*
Y557139D01*
G01Y559379D02*
Y560379D01*
G01Y562619D02*
Y563619D01*
G01Y565859D02*
Y576356D01*
G01Y578596D02*
Y579596D01*
G01Y581836D02*
Y582836D01*
G01Y585076D02*
Y587459D01*
G01X139860Y587872D02*
Y584650D01*
G01Y582410D02*
Y581410D01*
G01X141076Y595500D02*
X140405Y596171D01*
G01X140175Y594900D02*
X139345Y595730D01*
G01X140405Y596171D02*
Y597448D01*
G01Y600938D02*
Y601829D01*
G01X139345Y595730D02*
Y602270D01*
G01X140405Y601829D02*
X141176Y602600D01*
G01X139345Y602270D02*
X140175Y603100D01*
G01X134792Y590000D02*
Y608011D01*
G01X135852Y595890D02*
Y597260D01*
G01X134792Y590000D02*
Y608011D01*
G01X135852Y600940D02*
Y602360D01*
G01X140175Y594900D02*
X139345Y595730D01*
G01X141076Y595500D02*
X140405Y596171D01*
G01X139345Y595730D02*
Y602270D01*
G01X140405Y596171D02*
Y597448D01*
G01X139345Y595730D02*
Y602270D01*
G01X140405Y600938D02*
Y601829D01*
G01X139345Y602270D02*
X140175Y603100D01*
G01X140405Y601829D02*
X141176Y602600D01*
G01X135852Y595890D02*
Y597260D01*
G01Y600940D02*
Y602360D01*
G01X134792Y590000D02*
Y608011D01*
G01X141076Y595500D02*
X140405Y596171D01*
G01X140175Y594900D02*
X139345Y595730D01*
G01X140405Y596171D02*
Y597448D01*
G01Y600938D02*
Y601829D01*
G01X139345Y595730D02*
Y602270D01*
G01X140405Y601829D02*
X141176Y602600D01*
G01X139345Y602270D02*
X140175Y603100D01*
G01X134792Y590000D02*
Y608011D01*
G01X135852Y595890D02*
Y597260D01*
G01X134792Y590000D02*
Y608011D01*
G01X135852Y600940D02*
Y602360D01*
G01X140175Y594900D02*
X139345Y595730D01*
G01X141076Y595500D02*
X140405Y596171D01*
G01X139345Y595730D02*
Y602270D01*
G01X140405Y596171D02*
Y597448D01*
G01X139345Y595730D02*
Y602270D01*
G01X140405Y600938D02*
Y601829D01*
G01X139345Y602270D02*
X140175Y603100D01*
G01X140405Y601829D02*
X141176Y602600D01*
G01X135852Y595890D02*
Y597260D01*
G01Y600940D02*
Y602360D01*
G01X134792Y590000D02*
Y608011D01*
G01X174410Y-5220D02*
X174926D01*
G01X174387Y-6280D02*
X175369D01*
G01X174926Y-5220D02*
X175637Y-4509D01*
G01X175369Y-6280D02*
X176697Y-4952D01*
G01X175637Y-4509D02*
Y-1220D01*
G01Y3120D02*
Y4080D01*
G01Y8220D02*
Y10753D01*
G01X176697Y-4952D02*
Y11194D01*
G01X175637Y10753D02*
X174690Y11700D01*
G01X176697Y11194D02*
X173591Y14300D01*
G01X171737Y13554D02*
Y21131D01*
G01X172797Y19620D02*
Y20688D01*
G01X171737Y21131D02*
X175611Y25005D01*
G01X172797Y20688D02*
X177171Y25062D01*
G01X175611Y25005D02*
Y101210D01*
G01X176671Y27122D02*
Y37180D01*
G01X175611Y25005D02*
Y101210D01*
G01Y25005D02*
Y101210D01*
G01Y25005D02*
Y101210D01*
G01X174410Y-5220D02*
X174926D01*
G01X174387Y-6280D02*
X175369D01*
G01X174926Y-5220D02*
X175637Y-4509D01*
G01X175369Y-6280D02*
X176697Y-4952D01*
G01X175637Y-4509D02*
Y-1220D01*
G01Y3120D02*
Y4080D01*
G01Y8220D02*
Y10753D01*
G01X176697Y-4952D02*
Y11194D01*
G01X175637Y10753D02*
X174690Y11700D01*
G01X176697Y11194D02*
X173591Y14300D01*
G01X171737Y13554D02*
Y21131D01*
G01X172797Y19620D02*
Y20688D01*
G01X171737Y21131D02*
X175611Y25005D01*
G01X172797Y20688D02*
X177171Y25062D01*
G01X175611Y25005D02*
Y101210D01*
G01X176671Y27122D02*
Y37180D01*
G01X175611Y25005D02*
Y101210D01*
G01Y25005D02*
Y101210D01*
G01Y25005D02*
Y101210D01*
G01X212422Y97753D02*
Y25005D01*
G01Y97753D02*
Y25005D01*
G01Y97753D02*
Y25005D01*
G01Y97753D02*
Y25005D01*
G01Y97753D02*
Y25005D01*
G01X213482Y36780D02*
Y24562D01*
G01X212422Y25005D02*
X208548Y21131D01*
G01X213482Y24562D02*
X209608Y20688D01*
G01X208548Y21131D02*
Y13554D01*
G01X209608Y20688D02*
Y19620D01*
G01X211501Y11700D02*
X212448Y10753D01*
G01X210402Y14300D02*
X213508Y11194D01*
G01X212448Y10753D02*
Y8220D01*
G01Y4080D02*
Y3120D01*
G01Y-1220D02*
Y-4509D01*
G01X213508Y11194D02*
Y-4952D01*
G01X212448Y-4509D02*
X211737Y-5220D01*
G01X213508Y-4952D02*
X212180Y-6280D01*
G01X211737Y-5220D02*
X211221D01*
G01X212180Y-6280D02*
X211198D01*
G01X212422Y97753D02*
Y25005D01*
G01Y97753D02*
Y25005D01*
G01Y97753D02*
Y25005D01*
G01Y97753D02*
Y25005D01*
G01Y97753D02*
Y25005D01*
G01X213482Y36780D02*
Y24562D01*
G01X212422Y25005D02*
X208548Y21131D01*
G01X213482Y24562D02*
X209608Y20688D01*
G01X208548Y21131D02*
Y13554D01*
G01X209608Y20688D02*
Y19620D01*
G01X211501Y11700D02*
X212448Y10753D01*
G01X210402Y14300D02*
X213508Y11194D01*
G01X212448Y10753D02*
Y8220D01*
G01Y4080D02*
Y3120D01*
G01Y-1220D02*
Y-4509D01*
G01X213508Y11194D02*
Y-4952D01*
G01X212448Y-4509D02*
X211737Y-5220D01*
G01X213508Y-4952D02*
X212180Y-6280D01*
G01X211737Y-5220D02*
X211221D01*
G01X212180Y-6280D02*
X211198D01*
G01X179800Y-4651D02*
X180823Y-3628D01*
G01X178691Y-7260D02*
X181883Y-4068D01*
G01X180823Y-3628D02*
Y-1007D01*
G01Y2907D02*
Y4280D01*
G01Y8106D02*
Y10881D01*
G01X181883Y-4068D02*
Y11322D01*
G01X180823Y10881D02*
X179789Y11915D01*
G01X181883Y11322D02*
X178691Y14514D01*
G01X177437Y18745D02*
Y21231D01*
G01X178497Y19920D02*
Y20788D01*
G01X177437Y21231D02*
X180711Y24505D01*
G01X178497Y20788D02*
X179471Y21762D01*
G01X180711Y24505D02*
Y102012D01*
G01X181771Y26134D02*
Y102452D01*
G01X179800Y-4651D02*
X180823Y-3628D01*
G01X178691Y-7260D02*
X181883Y-4068D01*
G01X180823Y-3628D02*
Y-1007D01*
G01Y2907D02*
Y4280D01*
G01Y8106D02*
Y10881D01*
G01X181883Y-4068D02*
Y11322D01*
G01X180823Y10881D02*
X179789Y11915D01*
G01X181883Y11322D02*
X178691Y14514D01*
G01X177437Y18745D02*
Y21231D01*
G01X178497Y19920D02*
Y20788D01*
G01X177437Y21231D02*
X180711Y24505D01*
G01X178497Y20788D02*
X179471Y21762D01*
G01X180711Y24505D02*
Y102012D01*
G01X181771Y26134D02*
Y102452D01*
G01X215502Y-4651D02*
X216611D01*
G01D02*
X217634Y-3628D01*
G01X215502Y-7260D02*
X218694Y-4068D01*
G01X217634Y-3628D02*
Y-1007D01*
G01Y2907D02*
Y4280D01*
G01Y8106D02*
Y10881D01*
G01X218694Y-4068D02*
Y11322D01*
G01X217634Y10881D02*
X216600Y11915D01*
G01D02*
X215502D01*
G01X218694Y11322D02*
X215502Y14514D01*
G01X214248Y18755D02*
Y21231D01*
G01X215308Y19920D02*
Y20788D01*
G01X214248Y21231D02*
X217522Y24505D01*
G01X215308Y20788D02*
X216282Y21762D01*
G01X217522Y24505D02*
Y132337D01*
G01X218582Y26134D02*
Y131897D01*
G01X215502Y-4651D02*
X216611D01*
G01D02*
X217634Y-3628D01*
G01X215502Y-7260D02*
X218694Y-4068D01*
G01X217634Y-3628D02*
Y-1007D01*
G01Y2907D02*
Y4280D01*
G01Y8106D02*
Y10881D01*
G01X218694Y-4068D02*
Y11322D01*
G01X217634Y10881D02*
X216600Y11915D01*
G01D02*
X215502D01*
G01X218694Y11322D02*
X215502Y14514D01*
G01X214248Y18755D02*
Y21231D01*
G01X215308Y19920D02*
Y20788D01*
G01X214248Y21231D02*
X217522Y24505D01*
G01X215308Y20788D02*
X216282Y21762D01*
G01X217522Y24505D02*
Y132337D01*
G01X218582Y26134D02*
Y131897D01*
G01X174387Y-6280D02*
X175369D01*
G01X174410Y-5220D02*
X174926D01*
G01X175369Y-6280D02*
X176697Y-4952D01*
G01X174926Y-5220D02*
X175637Y-4509D01*
G01X176697Y-4952D02*
Y11194D01*
G01X175637Y-4509D02*
Y-1220D01*
G01X176697Y-4952D02*
Y11194D01*
G01X175637Y3120D02*
Y4080D01*
G01X176697Y-4952D02*
Y11194D01*
G01X175637Y8220D02*
Y10753D01*
G01X176697Y11194D02*
X173591Y14300D01*
G01X175637Y10753D02*
X174690Y11700D01*
G01X172797Y19620D02*
Y20688D01*
G01X171737Y13554D02*
Y21131D01*
G01X172797Y20688D02*
X177171Y25062D01*
G01X171737Y21131D02*
X175611Y25005D01*
G01X176671Y27122D02*
Y37180D01*
G01X175611Y25005D02*
Y101210D01*
G01X174387Y-6280D02*
X175369D01*
G01X174410Y-5220D02*
X174926D01*
G01X175369Y-6280D02*
X176697Y-4952D01*
G01X174926Y-5220D02*
X175637Y-4509D01*
G01X176697Y-4952D02*
Y11194D01*
G01X175637Y-4509D02*
Y-1220D01*
G01X176697Y-4952D02*
Y11194D01*
G01X175637Y3120D02*
Y4080D01*
G01X176697Y-4952D02*
Y11194D01*
G01X175637Y8220D02*
Y10753D01*
G01X176697Y11194D02*
X173591Y14300D01*
G01X175637Y10753D02*
X174690Y11700D01*
G01X172797Y19620D02*
Y20688D01*
G01X171737Y13554D02*
Y21131D01*
G01X172797Y20688D02*
X177171Y25062D01*
G01X171737Y21131D02*
X175611Y25005D01*
G01X176671Y27122D02*
Y37180D01*
G01X175611Y25005D02*
Y101210D01*
G01X213482Y36780D02*
Y24562D01*
G01X212422Y97753D02*
Y25005D01*
G01X213482Y24562D02*
X209608Y20688D01*
G01X212422Y25005D02*
X208548Y21131D01*
G01X209608Y20688D02*
Y19620D01*
G01X208548Y21131D02*
Y13554D01*
G01X210402Y14300D02*
X213508Y11194D01*
G01X211501Y11700D02*
X212448Y10753D01*
G01X213508Y11194D02*
Y-4952D01*
G01X212448Y10753D02*
Y8220D01*
G01X213508Y11194D02*
Y-4952D01*
G01X212448Y4080D02*
Y3120D01*
G01X213508Y11194D02*
Y-4952D01*
G01X212448Y-1220D02*
Y-4509D01*
G01X213508Y-4952D02*
X212180Y-6280D01*
G01X212448Y-4509D02*
X211737Y-5220D01*
G01X212180Y-6280D02*
X211198D01*
G01X211737Y-5220D02*
X211221D01*
G01X213482Y36780D02*
Y24562D01*
G01X212422Y97753D02*
Y25005D01*
G01X213482Y24562D02*
X209608Y20688D01*
G01X212422Y25005D02*
X208548Y21131D01*
G01X209608Y20688D02*
Y19620D01*
G01X208548Y21131D02*
Y13554D01*
G01X210402Y14300D02*
X213508Y11194D01*
G01X211501Y11700D02*
X212448Y10753D01*
G01X213508Y11194D02*
Y-4952D01*
G01X212448Y10753D02*
Y8220D01*
G01X213508Y11194D02*
Y-4952D01*
G01X212448Y4080D02*
Y3120D01*
G01X213508Y11194D02*
Y-4952D01*
G01X212448Y-1220D02*
Y-4509D01*
G01X213508Y-4952D02*
X212180Y-6280D01*
G01X212448Y-4509D02*
X211737Y-5220D01*
G01X212180Y-6280D02*
X211198D01*
G01X211737Y-5220D02*
X211221D01*
G01X178691Y-7260D02*
X181883Y-4068D01*
G01X179800Y-4651D02*
X180823Y-3628D01*
G01X181883Y-4068D02*
Y11322D01*
G01X180823Y-3628D02*
Y-1007D01*
G01X181883Y-4068D02*
Y11322D01*
G01X180823Y2907D02*
Y4280D01*
G01X181883Y-4068D02*
Y11322D01*
G01X180823Y8106D02*
Y10881D01*
G01X181883Y11322D02*
X178691Y14514D01*
G01X180823Y10881D02*
X179789Y11915D01*
G01X178497Y19920D02*
Y20788D01*
G01X177437Y18745D02*
Y21231D01*
G01X178497Y20788D02*
X179471Y21762D01*
G01X177437Y21231D02*
X180711Y24505D01*
G01X181771Y26134D02*
Y102452D01*
G01X180711Y24505D02*
Y102012D01*
G01X178691Y-7260D02*
X181883Y-4068D01*
G01X179800Y-4651D02*
X180823Y-3628D01*
G01X181883Y-4068D02*
Y11322D01*
G01X180823Y-3628D02*
Y-1007D01*
G01X181883Y-4068D02*
Y11322D01*
G01X180823Y2907D02*
Y4280D01*
G01X181883Y-4068D02*
Y11322D01*
G01X180823Y8106D02*
Y10881D01*
G01X181883Y11322D02*
X178691Y14514D01*
G01X180823Y10881D02*
X179789Y11915D01*
G01X178497Y19920D02*
Y20788D01*
G01X177437Y18745D02*
Y21231D01*
G01X178497Y20788D02*
X179471Y21762D01*
G01X177437Y21231D02*
X180711Y24505D01*
G01X181771Y26134D02*
Y102452D01*
G01X180711Y24505D02*
Y102012D01*
G01X215502Y-7260D02*
X218694Y-4068D01*
G01X215502Y-4651D02*
X216611D01*
G01X215502Y-7260D02*
X218694Y-4068D01*
G01X216611Y-4651D02*
X217634Y-3628D01*
G01X218694Y-4068D02*
Y11322D01*
G01X217634Y-3628D02*
Y-1007D01*
G01X218694Y-4068D02*
Y11322D01*
G01X217634Y2907D02*
Y4280D01*
G01X218694Y-4068D02*
Y11322D01*
G01X217634Y8106D02*
Y10881D01*
G01X218694Y11322D02*
X215502Y14514D01*
G01X217634Y10881D02*
X216600Y11915D01*
G01X218694Y11322D02*
X215502Y14514D01*
G01X216600Y11915D02*
X215502D01*
G01X215308Y19920D02*
Y20788D01*
G01X214248Y18755D02*
Y21231D01*
G01X215308Y20788D02*
X216282Y21762D01*
G01X214248Y21231D02*
X217522Y24505D01*
G01X218582Y26134D02*
Y131897D01*
G01X217522Y24505D02*
Y132337D01*
G01X215502Y-7260D02*
X218694Y-4068D01*
G01X215502Y-4651D02*
X216611D01*
G01X215502Y-7260D02*
X218694Y-4068D01*
G01X216611Y-4651D02*
X217634Y-3628D01*
G01X218694Y-4068D02*
Y11322D01*
G01X217634Y-3628D02*
Y-1007D01*
G01X218694Y-4068D02*
Y11322D01*
G01X217634Y2907D02*
Y4280D01*
G01X218694Y-4068D02*
Y11322D01*
G01X217634Y8106D02*
Y10881D01*
G01X218694Y11322D02*
X215502Y14514D01*
G01X217634Y10881D02*
X216600Y11915D01*
G01X218694Y11322D02*
X215502Y14514D01*
G01X216600Y11915D02*
X215502D01*
G01X215308Y19920D02*
Y20788D01*
G01X214248Y18755D02*
Y21231D01*
G01X215308Y20788D02*
X216282Y21762D01*
G01X214248Y21231D02*
X217522Y24505D01*
G01X218582Y26134D02*
Y131897D01*
G01X217522Y24505D02*
Y132337D01*
G01X176671Y39420D02*
Y40180D01*
G01Y42420D02*
Y43180D01*
G01Y45420D02*
Y101653D01*
G01Y39420D02*
Y40180D01*
G01Y42420D02*
Y43180D01*
G01Y45420D02*
Y101653D01*
G01X213482Y98193D02*
Y58220D01*
G01Y55980D02*
Y45020D01*
G01Y42780D02*
Y42020D01*
G01Y39780D02*
Y39020D01*
G01Y98193D02*
Y58220D01*
G01Y55980D02*
Y45020D01*
G01Y42780D02*
Y42020D01*
G01Y39780D02*
Y39020D01*
G01X176671Y39420D02*
Y40180D01*
G01Y42420D02*
Y43180D01*
G01Y45420D02*
Y101653D01*
G01Y39420D02*
Y40180D01*
G01Y42420D02*
Y43180D01*
G01Y45420D02*
Y101653D01*
G01X213482Y98193D02*
Y58220D01*
G01Y55980D02*
Y45020D01*
G01Y42780D02*
Y42020D01*
G01Y39780D02*
Y39020D01*
G01Y98193D02*
Y58220D01*
G01Y55980D02*
Y45020D01*
G01Y42780D02*
Y42020D01*
G01Y39780D02*
Y39020D01*
G01X175611Y101210D02*
X172412Y104409D01*
G01X176671Y101653D02*
X173472Y104852D01*
G01X172412Y104409D02*
Y133359D01*
G01X173472Y104852D02*
Y132916D01*
G01X172412Y133359D02*
X173901Y134848D01*
G01X173472Y132916D02*
X174344Y133788D01*
G01X173901Y134848D02*
X175400D01*
G01X174344Y133788D02*
X175840D01*
G01X175400Y134848D02*
X175900Y135348D01*
G01X175840Y133788D02*
X176960Y134908D01*
G01X175900Y135348D02*
Y138588D01*
G01X176960Y134908D02*
Y139028D01*
G01X175900Y138588D02*
X175400Y139088D01*
G01X176960Y139028D02*
X175840Y140148D01*
G01X175400Y139088D02*
X173704D01*
G01D02*
X172312Y140480D01*
G01X175840Y140148D02*
X174144D01*
G01X173704Y139088D02*
X172312Y140480D01*
G01X174144Y140148D02*
X173372Y140920D01*
G01X172312Y140480D02*
Y142588D01*
G01X173372Y140920D02*
Y142148D01*
G01X172312Y142588D02*
X190984Y161260D01*
G01X173372Y142148D02*
X191424Y160200D01*
G01X175611Y101210D02*
X172412Y104409D01*
G01X176671Y101653D02*
X173472Y104852D01*
G01X172412Y104409D02*
Y133359D01*
G01X173472Y104852D02*
Y132916D01*
G01X172412Y133359D02*
X173901Y134848D01*
G01X173472Y132916D02*
X174344Y133788D01*
G01X173901Y134848D02*
X175400D01*
G01X174344Y133788D02*
X175840D01*
G01X175400Y134848D02*
X175900Y135348D01*
G01X175840Y133788D02*
X176960Y134908D01*
G01X175900Y135348D02*
Y138588D01*
G01X176960Y134908D02*
Y139028D01*
G01X175900Y138588D02*
X175400Y139088D01*
G01X176960Y139028D02*
X175840Y140148D01*
G01X175400Y139088D02*
X173704D01*
G01D02*
X172312Y140480D01*
G01X175840Y140148D02*
X174144D01*
G01X173704Y139088D02*
X172312Y140480D01*
G01X174144Y140148D02*
X173372Y140920D01*
G01X172312Y140480D02*
Y142588D01*
G01X173372Y140920D02*
Y142148D01*
G01X172312Y142588D02*
X190984Y161260D01*
G01X173372Y142148D02*
X191424Y160200D01*
G01X261930Y182230D02*
X213712Y134012D01*
G01X261930Y182230D02*
X213712Y134012D01*
G01X261930Y182230D02*
X213712Y134012D01*
G01X261930Y182230D02*
X213712Y134012D01*
G01X261930Y182230D02*
X213712Y134012D01*
G01X261930Y182230D02*
X213712Y134012D01*
G01X261930Y182230D02*
X213712Y134012D01*
G01X261930Y182230D02*
X213712Y134012D01*
G01X261930Y182230D02*
X213712Y134012D01*
G01X261930Y182230D02*
X213712Y134012D01*
G01X261930Y182230D02*
X213712Y134012D01*
G01X261930Y182230D02*
X213712Y134012D01*
G01X261930Y182230D02*
X213712Y134012D01*
G01X261930Y182230D02*
X213712Y134012D01*
G01X261930Y182230D02*
X213712Y134012D01*
G01X261930Y182230D02*
X213712Y134012D01*
G01X261930Y182230D02*
X213712Y134012D01*
G01X261930Y182230D02*
X213712Y134012D01*
G01X261930Y182230D02*
X213712Y134012D01*
G01X243769Y162569D02*
X214772Y133572D01*
G01X213712Y134012D02*
Y106634D01*
G01X214772Y133572D02*
Y106194D01*
G01X213712Y106634D02*
X212840Y105762D01*
G01X214772Y106194D02*
X213280Y104702D01*
G01X212840Y105762D02*
X212209D01*
G01D02*
X210012Y103565D01*
G01X213280Y104702D02*
X212649D01*
G01X212209Y105762D02*
X210012Y103565D01*
G01X212649Y104702D02*
X211072Y103125D01*
G01X210012Y103565D02*
Y100163D01*
G01X211072Y103125D02*
Y100603D01*
G01X210012Y100163D02*
X212422Y97753D01*
G01X211072Y100603D02*
X213482Y98193D01*
G01X261930Y182230D02*
X213712Y134012D01*
G01X261930Y182230D02*
X213712Y134012D01*
G01X261930Y182230D02*
X213712Y134012D01*
G01X261930Y182230D02*
X213712Y134012D01*
G01X261930Y182230D02*
X213712Y134012D01*
G01X261930Y182230D02*
X213712Y134012D01*
G01X261930Y182230D02*
X213712Y134012D01*
G01X261930Y182230D02*
X213712Y134012D01*
G01X261930Y182230D02*
X213712Y134012D01*
G01X261930Y182230D02*
X213712Y134012D01*
G01X261930Y182230D02*
X213712Y134012D01*
G01X261930Y182230D02*
X213712Y134012D01*
G01X261930Y182230D02*
X213712Y134012D01*
G01X261930Y182230D02*
X213712Y134012D01*
G01X261930Y182230D02*
X213712Y134012D01*
G01X261930Y182230D02*
X213712Y134012D01*
G01X261930Y182230D02*
X213712Y134012D01*
G01X261930Y182230D02*
X213712Y134012D01*
G01X261930Y182230D02*
X213712Y134012D01*
G01X243769Y162569D02*
X214772Y133572D01*
G01X213712Y134012D02*
Y106634D01*
G01X214772Y133572D02*
Y106194D01*
G01X213712Y106634D02*
X212840Y105762D01*
G01X214772Y106194D02*
X213280Y104702D01*
G01X212840Y105762D02*
X212209D01*
G01D02*
X210012Y103565D01*
G01X213280Y104702D02*
X212649D01*
G01X212209Y105762D02*
X210012Y103565D01*
G01X212649Y104702D02*
X211072Y103125D01*
G01X210012Y103565D02*
Y100163D01*
G01X211072Y103125D02*
Y100603D01*
G01X210012Y100163D02*
X212422Y97753D01*
G01X211072Y100603D02*
X213482Y98193D01*
G01X180711Y102012D02*
X176212Y106511D01*
G01X181771Y102452D02*
X177272Y106951D01*
G01X176212Y106511D02*
Y119885D01*
G01X177272Y106951D02*
Y119442D01*
G01X176212Y119885D02*
X177701Y121374D01*
G01X177272Y119442D02*
X178144Y120314D01*
G01X177701Y121374D02*
X178943D01*
G01X178144Y120314D02*
X179383D01*
G01X177701Y121374D02*
X178943D01*
G01D02*
X179912Y122343D01*
G01X179383Y120314D02*
X180972Y121903D01*
G01X179912Y122343D02*
Y124785D01*
G01X180972Y121903D02*
Y125225D01*
G01X179912Y124785D02*
X179083Y125614D01*
G01X180972Y125225D02*
X179523Y126674D01*
G01X179083Y125614D02*
X177904D01*
G01D02*
X176412Y127106D01*
G01X179523Y126674D02*
X178344D01*
G01X177904Y125614D02*
X176412Y127106D01*
G01X178344Y126674D02*
X177472Y127546D01*
G01X176412Y127106D02*
Y130159D01*
G01X177472Y127546D02*
Y129719D01*
G01X176412Y130159D02*
X180212Y133959D01*
G01X177472Y129719D02*
X181272Y133519D01*
G01X180212Y133959D02*
Y143719D01*
G01X181272Y133519D02*
Y143279D01*
G01X180212Y143719D02*
X191953Y155460D01*
G01X181272Y143279D02*
X192393Y154400D01*
G01X191953Y155460D02*
X196253D01*
G01X192393Y154400D02*
X196693D01*
G01X196253Y155460D02*
X200194Y159401D01*
G01X196693Y154400D02*
X201254Y158961D01*
G01X180711Y102012D02*
X176212Y106511D01*
G01X181771Y102452D02*
X177272Y106951D01*
G01X176212Y106511D02*
Y119885D01*
G01X177272Y106951D02*
Y119442D01*
G01X176212Y119885D02*
X177701Y121374D01*
G01X177272Y119442D02*
X178144Y120314D01*
G01X177701Y121374D02*
X178943D01*
G01X178144Y120314D02*
X179383D01*
G01X177701Y121374D02*
X178943D01*
G01D02*
X179912Y122343D01*
G01X179383Y120314D02*
X180972Y121903D01*
G01X179912Y122343D02*
Y124785D01*
G01X180972Y121903D02*
Y125225D01*
G01X179912Y124785D02*
X179083Y125614D01*
G01X180972Y125225D02*
X179523Y126674D01*
G01X179083Y125614D02*
X177904D01*
G01D02*
X176412Y127106D01*
G01X179523Y126674D02*
X178344D01*
G01X177904Y125614D02*
X176412Y127106D01*
G01X178344Y126674D02*
X177472Y127546D01*
G01X176412Y127106D02*
Y130159D01*
G01X177472Y127546D02*
Y129719D01*
G01X176412Y130159D02*
X180212Y133959D01*
G01X177472Y129719D02*
X181272Y133519D01*
G01X180212Y133959D02*
Y143719D01*
G01X181272Y133519D02*
Y143279D01*
G01X180212Y143719D02*
X191953Y155460D01*
G01X181272Y143279D02*
X192393Y154400D01*
G01X191953Y155460D02*
X196253D01*
G01X192393Y154400D02*
X196693D01*
G01X196253Y155460D02*
X200194Y159401D01*
G01X196693Y154400D02*
X201254Y158961D01*
G01X217522Y132337D02*
X265464Y180279D01*
G01X218582Y131897D02*
X266524Y179839D01*
G01X217522Y132337D02*
X265464Y180279D01*
G01X218582Y131897D02*
X266524Y179839D01*
G01X176671Y101653D02*
X173472Y104852D01*
G01X175611Y101210D02*
X172412Y104409D01*
G01X173472Y104852D02*
Y132916D01*
G01X172412Y104409D02*
Y133359D01*
G01X173472Y132916D02*
X174344Y133788D01*
G01X172412Y133359D02*
X173901Y134848D01*
G01X174344Y133788D02*
X175840D01*
G01X173901Y134848D02*
X175400D01*
G01X175840Y133788D02*
X176960Y134908D01*
G01X175400Y134848D02*
X175900Y135348D01*
G01X176960Y134908D02*
Y139028D01*
G01X175900Y135348D02*
Y138588D01*
G01X176960Y139028D02*
X175840Y140148D01*
G01X175900Y138588D02*
X175400Y139088D01*
G01X175840Y140148D02*
X174144D01*
G01X175400Y139088D02*
X173704D01*
G01X175840Y140148D02*
X174144D01*
G01D02*
X173372Y140920D01*
G01X173704Y139088D02*
X172312Y140480D01*
G01X173372Y140920D02*
Y142148D01*
G01X172312Y140480D02*
Y142588D01*
G01X173372Y142148D02*
X191424Y160200D01*
G01X172312Y142588D02*
X190984Y161260D01*
G01X176671Y101653D02*
X173472Y104852D01*
G01X175611Y101210D02*
X172412Y104409D01*
G01X173472Y104852D02*
Y132916D01*
G01X172412Y104409D02*
Y133359D01*
G01X173472Y132916D02*
X174344Y133788D01*
G01X172412Y133359D02*
X173901Y134848D01*
G01X174344Y133788D02*
X175840D01*
G01X173901Y134848D02*
X175400D01*
G01X175840Y133788D02*
X176960Y134908D01*
G01X175400Y134848D02*
X175900Y135348D01*
G01X176960Y134908D02*
Y139028D01*
G01X175900Y135348D02*
Y138588D01*
G01X176960Y139028D02*
X175840Y140148D01*
G01X175900Y138588D02*
X175400Y139088D01*
G01X175840Y140148D02*
X174144D01*
G01X175400Y139088D02*
X173704D01*
G01X175840Y140148D02*
X174144D01*
G01D02*
X173372Y140920D01*
G01X173704Y139088D02*
X172312Y140480D01*
G01X173372Y140920D02*
Y142148D01*
G01X172312Y140480D02*
Y142588D01*
G01X173372Y142148D02*
X191424Y160200D01*
G01X172312Y142588D02*
X190984Y161260D01*
G01X243769Y162569D02*
X214772Y133572D01*
G01X261930Y182230D02*
X213712Y134012D01*
G01X214772Y133572D02*
Y106194D01*
G01X213712Y134012D02*
Y106634D01*
G01X214772Y106194D02*
X213280Y104702D01*
G01X213712Y106634D02*
X212840Y105762D01*
G01X213280Y104702D02*
X212649D01*
G01X212840Y105762D02*
X212209D01*
G01X213280Y104702D02*
X212649D01*
G01D02*
X211072Y103125D01*
G01X212209Y105762D02*
X210012Y103565D01*
G01X211072Y103125D02*
Y100603D01*
G01X210012Y103565D02*
Y100163D01*
G01X211072Y100603D02*
X213482Y98193D01*
G01X210012Y100163D02*
X212422Y97753D01*
G01X243769Y162569D02*
X214772Y133572D01*
G01X261930Y182230D02*
X213712Y134012D01*
G01X214772Y133572D02*
Y106194D01*
G01X213712Y134012D02*
Y106634D01*
G01X214772Y106194D02*
X213280Y104702D01*
G01X213712Y106634D02*
X212840Y105762D01*
G01X213280Y104702D02*
X212649D01*
G01X212840Y105762D02*
X212209D01*
G01X213280Y104702D02*
X212649D01*
G01D02*
X211072Y103125D01*
G01X212209Y105762D02*
X210012Y103565D01*
G01X211072Y103125D02*
Y100603D01*
G01X210012Y103565D02*
Y100163D01*
G01X211072Y100603D02*
X213482Y98193D01*
G01X210012Y100163D02*
X212422Y97753D01*
G01X181771Y102452D02*
X177272Y106951D01*
G01X180711Y102012D02*
X176212Y106511D01*
G01X177272Y106951D02*
Y119442D01*
G01X176212Y106511D02*
Y119885D01*
G01X177272Y119442D02*
X178144Y120314D01*
G01X176212Y119885D02*
X177701Y121374D01*
G01X178144Y120314D02*
X179383D01*
G01D02*
X180972Y121903D01*
G01X177701Y121374D02*
X178943D01*
G01X179383Y120314D02*
X180972Y121903D01*
G01X178943Y121374D02*
X179912Y122343D01*
G01X180972Y121903D02*
Y125225D01*
G01X179912Y122343D02*
Y124785D01*
G01X180972Y125225D02*
X179523Y126674D01*
G01X179912Y124785D02*
X179083Y125614D01*
G01X179523Y126674D02*
X178344D01*
G01X179083Y125614D02*
X177904D01*
G01X179523Y126674D02*
X178344D01*
G01D02*
X177472Y127546D01*
G01X177904Y125614D02*
X176412Y127106D01*
G01X177472Y127546D02*
Y129719D01*
G01X176412Y127106D02*
Y130159D01*
G01X177472Y129719D02*
X181272Y133519D01*
G01X176412Y130159D02*
X180212Y133959D01*
G01X181272Y133519D02*
Y143279D01*
G01X180212Y133959D02*
Y143719D01*
G01X181272Y143279D02*
X192393Y154400D01*
G01X180212Y143719D02*
X191953Y155460D01*
G01X192393Y154400D02*
X196693D01*
G01X191953Y155460D02*
X196253D01*
G01X196693Y154400D02*
X201254Y158961D01*
G01X196253Y155460D02*
X200194Y159401D01*
G01X181771Y102452D02*
X177272Y106951D01*
G01X180711Y102012D02*
X176212Y106511D01*
G01X177272Y106951D02*
Y119442D01*
G01X176212Y106511D02*
Y119885D01*
G01X177272Y119442D02*
X178144Y120314D01*
G01X176212Y119885D02*
X177701Y121374D01*
G01X178144Y120314D02*
X179383D01*
G01D02*
X180972Y121903D01*
G01X177701Y121374D02*
X178943D01*
G01X179383Y120314D02*
X180972Y121903D01*
G01X178943Y121374D02*
X179912Y122343D01*
G01X180972Y121903D02*
Y125225D01*
G01X179912Y122343D02*
Y124785D01*
G01X180972Y125225D02*
X179523Y126674D01*
G01X179912Y124785D02*
X179083Y125614D01*
G01X179523Y126674D02*
X178344D01*
G01X179083Y125614D02*
X177904D01*
G01X179523Y126674D02*
X178344D01*
G01D02*
X177472Y127546D01*
G01X177904Y125614D02*
X176412Y127106D01*
G01X177472Y127546D02*
Y129719D01*
G01X176412Y127106D02*
Y130159D01*
G01X177472Y129719D02*
X181272Y133519D01*
G01X176412Y130159D02*
X180212Y133959D01*
G01X181272Y133519D02*
Y143279D01*
G01X180212Y133959D02*
Y143719D01*
G01X181272Y143279D02*
X192393Y154400D01*
G01X180212Y143719D02*
X191953Y155460D01*
G01X192393Y154400D02*
X196693D01*
G01X191953Y155460D02*
X196253D01*
G01X196693Y154400D02*
X201254Y158961D01*
G01X196253Y155460D02*
X200194Y159401D01*
G01X218582Y131897D02*
X266524Y179839D01*
G01X217522Y132337D02*
X265464Y180279D01*
G01X218582Y131897D02*
X266524Y179839D01*
G01X217522Y132337D02*
X265464Y180279D01*
G01X190984Y161260D02*
X194780D01*
G01X191424Y160200D02*
X195220D01*
G01X194780Y161260D02*
X204196Y170676D01*
G01X195220Y160200D02*
X205256Y170236D01*
G01X204196Y170676D02*
Y174472D01*
G01X205256Y170236D02*
Y174032D01*
G01X204196Y174472D02*
X254964Y225240D01*
G01X205256Y174032D02*
X216585Y185361D01*
G01X204196Y174472D02*
X254964Y225240D01*
G01X217930Y186706D02*
X218803Y187579D01*
G01X204196Y174472D02*
X254964Y225240D01*
G01X220148Y188924D02*
X221204Y189980D01*
G01X204196Y174472D02*
X254964Y225240D01*
G01X222548Y191324D02*
X223489Y192265D01*
G01X204196Y174472D02*
X254964Y225240D01*
G01X224834Y193610D02*
X225661Y194437D01*
G01X204196Y174472D02*
X254964Y225240D01*
G01X227006Y195782D02*
X228062Y196838D01*
G01X204196Y174472D02*
X254964Y225240D01*
G01X229406Y198182D02*
X230737Y199513D01*
G01X204196Y174472D02*
X254964Y225240D01*
G01X204196Y174472D02*
X254964Y225240D01*
G01X204196Y174472D02*
X254964Y225240D01*
G01X204196Y174472D02*
X254964Y225240D01*
G01X204196Y174472D02*
X254964Y225240D01*
G01X204196Y174472D02*
X254964Y225240D01*
G01X204196Y174472D02*
X254964Y225240D01*
G01X204196Y174472D02*
X254964Y225240D01*
G01X204196Y174472D02*
X254964Y225240D01*
G01X204196Y174472D02*
X254964Y225240D01*
G01X204196Y174472D02*
X254964Y225240D01*
G01X190984Y161260D02*
X194780D01*
G01X191424Y160200D02*
X195220D01*
G01X194780Y161260D02*
X204196Y170676D01*
G01X195220Y160200D02*
X205256Y170236D01*
G01X204196Y170676D02*
Y174472D01*
G01X205256Y170236D02*
Y174032D01*
G01X204196Y174472D02*
X254964Y225240D01*
G01X205256Y174032D02*
X216585Y185361D01*
G01X204196Y174472D02*
X254964Y225240D01*
G01X217930Y186706D02*
X218803Y187579D01*
G01X204196Y174472D02*
X254964Y225240D01*
G01X220148Y188924D02*
X221204Y189980D01*
G01X204196Y174472D02*
X254964Y225240D01*
G01X222548Y191324D02*
X223489Y192265D01*
G01X204196Y174472D02*
X254964Y225240D01*
G01X224834Y193610D02*
X225661Y194437D01*
G01X204196Y174472D02*
X254964Y225240D01*
G01X227006Y195782D02*
X228062Y196838D01*
G01X204196Y174472D02*
X254964Y225240D01*
G01X229406Y198182D02*
X230737Y199513D01*
G01X204196Y174472D02*
X254964Y225240D01*
G01X204196Y174472D02*
X254964Y225240D01*
G01X204196Y174472D02*
X254964Y225240D01*
G01X204196Y174472D02*
X254964Y225240D01*
G01X204196Y174472D02*
X254964Y225240D01*
G01X204196Y174472D02*
X254964Y225240D01*
G01X204196Y174472D02*
X254964Y225240D01*
G01X204196Y174472D02*
X254964Y225240D01*
G01X204196Y174472D02*
X254964Y225240D01*
G01X204196Y174472D02*
X254964Y225240D01*
G01X204196Y174472D02*
X254964Y225240D01*
G01X200194Y159401D02*
Y160961D01*
G01X201254Y158961D02*
Y160521D01*
G01X200194Y160961D02*
X210710Y171477D01*
G01X201254Y160521D02*
X211770Y171037D01*
G01X210710Y171477D02*
Y175386D01*
G01X211770Y171037D02*
Y174946D01*
G01X210710Y175386D02*
X256552Y221228D01*
G01X211770Y174946D02*
X241733Y204909D01*
G01X210710Y175386D02*
X256552Y221228D01*
G01X210710Y175386D02*
X256552Y221228D01*
G01X210710Y175386D02*
X256552Y221228D01*
G01X210710Y175386D02*
X256552Y221228D01*
G01X210710Y175386D02*
X256552Y221228D01*
G01X200194Y159401D02*
Y160961D01*
G01X201254Y158961D02*
Y160521D01*
G01X200194Y160961D02*
X210710Y171477D01*
G01X201254Y160521D02*
X211770Y171037D01*
G01X210710Y171477D02*
Y175386D01*
G01X211770Y171037D02*
Y174946D01*
G01X210710Y175386D02*
X256552Y221228D01*
G01X211770Y174946D02*
X241733Y204909D01*
G01X210710Y175386D02*
X256552Y221228D01*
G01X210710Y175386D02*
X256552Y221228D01*
G01X210710Y175386D02*
X256552Y221228D01*
G01X210710Y175386D02*
X256552Y221228D01*
G01X210710Y175386D02*
X256552Y221228D01*
G01X191424Y160200D02*
X195220D01*
G01X190984Y161260D02*
X194780D01*
G01X195220Y160200D02*
X205256Y170236D01*
G01X194780Y161260D02*
X204196Y170676D01*
G01X205256Y170236D02*
Y174032D01*
G01X204196Y170676D02*
Y174472D01*
G01X205256Y174032D02*
X216585Y185361D01*
G01X217930Y186706D02*
X218803Y187579D01*
G01X220148Y188924D02*
X221204Y189980D01*
G01X222548Y191324D02*
X223489Y192265D01*
G01X224834Y193610D02*
X225661Y194437D01*
G01X227006Y195782D02*
X228062Y196838D01*
G01X229406Y198182D02*
X230737Y199513D01*
G01X204196Y174472D02*
X254964Y225240D01*
G01X191424Y160200D02*
X195220D01*
G01X190984Y161260D02*
X194780D01*
G01X195220Y160200D02*
X205256Y170236D01*
G01X194780Y161260D02*
X204196Y170676D01*
G01X205256Y170236D02*
Y174032D01*
G01X204196Y170676D02*
Y174472D01*
G01X205256Y174032D02*
X216585Y185361D01*
G01X217930Y186706D02*
X218803Y187579D01*
G01X220148Y188924D02*
X221204Y189980D01*
G01X222548Y191324D02*
X223489Y192265D01*
G01X224834Y193610D02*
X225661Y194437D01*
G01X227006Y195782D02*
X228062Y196838D01*
G01X229406Y198182D02*
X230737Y199513D01*
G01X204196Y174472D02*
X254964Y225240D01*
G01X201254Y158961D02*
Y160521D01*
G01X200194Y159401D02*
Y160961D01*
G01X201254Y160521D02*
X211770Y171037D01*
G01X200194Y160961D02*
X210710Y171477D01*
G01X211770Y171037D02*
Y174946D01*
G01X210710Y171477D02*
Y175386D01*
G01X211770Y174946D02*
X241733Y204909D01*
G01X210710Y175386D02*
X256552Y221228D01*
G01X201254Y158961D02*
Y160521D01*
G01X200194Y159401D02*
Y160961D01*
G01X201254Y160521D02*
X211770Y171037D01*
G01X200194Y160961D02*
X210710Y171477D01*
G01X211770Y171037D02*
Y174946D01*
G01X210710Y171477D02*
Y175386D01*
G01X211770Y174946D02*
X241733Y204909D01*
G01X210710Y175386D02*
X256552Y221228D01*
G01X231413Y245935D02*
X232120Y246642D01*
G01X231413Y245935D02*
X232120Y246642D01*
G01X231413Y245935D02*
X232120Y246642D01*
G01X231413Y245935D02*
X232120Y246642D01*
G01X247356Y352736D02*
X211752Y388340D01*
G01X246916Y351676D02*
X210692Y387900D01*
G01X211752Y388340D02*
Y393231D01*
G01X210692Y387900D02*
Y392791D01*
G01X211752Y393231D02*
X194083Y410900D01*
G01X210692Y392791D02*
X193643Y409840D01*
G01X191829Y406240D02*
X207232Y390837D01*
G01X192269Y407300D02*
X208292Y391277D01*
G01X207232Y390837D02*
Y386930D01*
G01X208292Y391277D02*
Y387370D01*
G01X207232Y386930D02*
X246383Y347779D01*
G01X208292Y387370D02*
X246823Y348839D01*
G01X246916Y351676D02*
X210692Y387900D01*
G01X247356Y352736D02*
X211752Y388340D01*
G01X210692Y387900D02*
Y392791D01*
G01X211752Y388340D02*
Y393231D01*
G01X210692Y392791D02*
X193643Y409840D01*
G01X211752Y393231D02*
X194083Y410900D01*
G01X192269Y407300D02*
X208292Y391277D01*
G01X191829Y406240D02*
X207232Y390837D01*
G01X208292Y391277D02*
Y387370D01*
G01X207232Y390837D02*
Y386930D01*
G01X208292Y387370D02*
X246823Y348839D01*
G01X207232Y386930D02*
X246383Y347779D01*
G01X247356Y352736D02*
X211752Y388340D01*
G01X246916Y351676D02*
X210692Y387900D01*
G01X211752Y388340D02*
Y393231D01*
G01X210692Y387900D02*
Y392791D01*
G01X211752Y393231D02*
X194083Y410900D01*
G01X210692Y392791D02*
X193643Y409840D01*
G01X191829Y406240D02*
X207232Y390837D01*
G01X192269Y407300D02*
X208292Y391277D01*
G01X207232Y390837D02*
Y386930D01*
G01X208292Y391277D02*
Y387370D01*
G01X207232Y386930D02*
X246383Y347779D01*
G01X208292Y387370D02*
X246823Y348839D01*
G01X246916Y351676D02*
X210692Y387900D01*
G01X247356Y352736D02*
X211752Y388340D01*
G01X210692Y387900D02*
Y392791D01*
G01X211752Y388340D02*
Y393231D01*
G01X210692Y392791D02*
X193643Y409840D01*
G01X211752Y393231D02*
X194083Y410900D01*
G01X192269Y407300D02*
X208292Y391277D01*
G01X191829Y406240D02*
X207232Y390837D01*
G01X208292Y391277D02*
Y387370D01*
G01X207232Y390837D02*
Y386930D01*
G01X208292Y387370D02*
X246823Y348839D01*
G01X207232Y386930D02*
X246383Y347779D01*
G01X194083Y410900D02*
X177792D01*
G01X193643Y409840D02*
X177352D01*
G01X176752Y406240D02*
X191829D01*
G01X177192Y407300D02*
X192269D01*
G01X193643Y409840D02*
X177352D01*
G01X194083Y410900D02*
X177792D01*
G01X177192Y407300D02*
X192269D01*
G01X176752Y406240D02*
X191829D01*
G01X194083Y410900D02*
X177792D01*
G01X193643Y409840D02*
X177352D01*
G01X176752Y406240D02*
X191829D01*
G01X177192Y407300D02*
X192269D01*
G01X193643Y409840D02*
X177352D01*
G01X194083Y410900D02*
X177792D01*
G01X177192Y407300D02*
X192269D01*
G01X176752Y406240D02*
X191829D01*
G01X241732Y398431D02*
X175613Y464550D01*
G01X242792Y398871D02*
X176671Y464992D01*
G01X175611Y464550D02*
Y487759D01*
G01X267892Y422632D02*
X216614Y473910D01*
G01X268952Y423072D02*
X217672Y474352D01*
G01X184272Y469249D02*
Y463322D01*
G01X183212Y468806D02*
Y462879D01*
G01X184272Y463322D02*
X185417Y462177D01*
G01D02*
X187174D01*
G01X183212Y462879D02*
X184974Y461117D01*
G01X185417Y462177D02*
X187174D01*
G01X184974Y461117D02*
X187614D01*
G01X185417Y462177D02*
X187174D01*
G01D02*
X189505Y464508D01*
G01X187614Y461117D02*
X189945Y463448D01*
G01X187174Y462177D02*
X189505Y464508D01*
G01D02*
X191614D01*
G01X189945Y463448D02*
X191174D01*
G01X191614Y464508D02*
X193440Y462682D01*
G01X191174Y463448D02*
X192380Y462242D01*
G01X193440Y462682D02*
Y460574D01*
G01X192380Y462242D02*
Y461013D01*
G01X193440Y460574D02*
X190579Y457712D01*
G01X192380Y461013D02*
X189519Y458151D01*
G01X190579Y457712D02*
Y456484D01*
G01X189519Y458151D02*
Y456041D01*
G01X190579Y456484D02*
X191784Y455279D01*
G01X189519Y456041D02*
X191341Y454219D01*
G01X191784Y455279D02*
X193010D01*
G01X191341Y454219D02*
X193453D01*
G01X193010Y455279D02*
X195871Y458141D01*
G01X193453Y454219D02*
X196314Y457081D01*
G01X195871Y458141D02*
X197981D01*
G01X196314Y457081D02*
X197538D01*
G01X197981Y458141D02*
X199807Y456315D01*
G01X197538Y457081D02*
X198747Y455872D01*
G01X199807Y456315D02*
Y454207D01*
G01X198747Y455872D02*
Y454646D01*
G01X199807Y454207D02*
X196946Y451345D01*
G01X198747Y454646D02*
X195886Y451784D01*
G01X196946Y451345D02*
Y450117D01*
G01X195886Y451784D02*
Y449675D01*
G01X196946Y450117D02*
X246792Y400271D01*
G01X195888Y449675D02*
X245732Y399831D01*
G01X242792Y398871D02*
X176671Y464992D01*
G01X241732Y398431D02*
X175613Y464550D01*
G01X175611D02*
Y487759D01*
G01X268952Y423072D02*
X217672Y474352D01*
G01X267892Y422632D02*
X216614Y473910D01*
G01X183212Y468806D02*
Y462879D01*
G01X184272Y469249D02*
Y463322D01*
G01X183212Y462879D02*
X184974Y461117D01*
G01X184272Y463322D02*
X185417Y462177D01*
G01X183212Y462879D02*
X184974Y461117D01*
G01D02*
X187614D01*
G01D02*
X189945Y463448D01*
G01X185417Y462177D02*
X187174D01*
G01X187614Y461117D02*
X189945Y463448D01*
G01D02*
X191174D01*
G01X187174Y462177D02*
X189505Y464508D01*
G01X189945Y463448D02*
X191174D01*
G01X189505Y464508D02*
X191614D01*
G01X191174Y463448D02*
X192380Y462242D01*
G01X191614Y464508D02*
X193440Y462682D01*
G01X192380Y462242D02*
Y461013D01*
G01X193440Y462682D02*
Y460574D01*
G01X192380Y461013D02*
X189519Y458151D01*
G01X193440Y460574D02*
X190579Y457712D01*
G01X189519Y458151D02*
Y456041D01*
G01X190579Y457712D02*
Y456484D01*
G01X189519Y456041D02*
X191341Y454219D01*
G01X190579Y456484D02*
X191784Y455279D01*
G01X191341Y454219D02*
X193453D01*
G01X191784Y455279D02*
X193010D01*
G01X193453Y454219D02*
X196314Y457081D01*
G01X193010Y455279D02*
X195871Y458141D01*
G01X196314Y457081D02*
X197538D01*
G01X195871Y458141D02*
X197981D01*
G01X197538Y457081D02*
X198747Y455872D01*
G01X197981Y458141D02*
X199807Y456315D01*
G01X198747Y455872D02*
Y454646D01*
G01X199807Y456315D02*
Y454207D01*
G01X198747Y454646D02*
X195886Y451784D01*
G01X199807Y454207D02*
X196946Y451345D01*
G01X195886Y451784D02*
Y449675D01*
G01X196946Y451345D02*
Y450117D01*
G01X195888Y449675D02*
X245732Y399831D01*
G01X196946Y450117D02*
X246792Y400271D01*
G01X241732Y398431D02*
X175613Y464550D01*
G01X242792Y398871D02*
X176671Y464992D01*
G01X175611Y464550D02*
Y487759D01*
G01X267892Y422632D02*
X216614Y473910D01*
G01X268952Y423072D02*
X217672Y474352D01*
G01X184272Y469249D02*
Y463322D01*
G01X183212Y468806D02*
Y462879D01*
G01X184272Y463322D02*
X185417Y462177D01*
G01D02*
X187174D01*
G01X183212Y462879D02*
X184974Y461117D01*
G01X185417Y462177D02*
X187174D01*
G01X184974Y461117D02*
X187614D01*
G01X185417Y462177D02*
X187174D01*
G01D02*
X189505Y464508D01*
G01X187614Y461117D02*
X189945Y463448D01*
G01X187174Y462177D02*
X189505Y464508D01*
G01D02*
X191614D01*
G01X189945Y463448D02*
X191174D01*
G01X191614Y464508D02*
X193440Y462682D01*
G01X191174Y463448D02*
X192380Y462242D01*
G01X193440Y462682D02*
Y460574D01*
G01X192380Y462242D02*
Y461013D01*
G01X193440Y460574D02*
X190579Y457712D01*
G01X192380Y461013D02*
X189519Y458151D01*
G01X190579Y457712D02*
Y456484D01*
G01X189519Y458151D02*
Y456041D01*
G01X190579Y456484D02*
X191784Y455279D01*
G01X189519Y456041D02*
X191341Y454219D01*
G01X191784Y455279D02*
X193010D01*
G01X191341Y454219D02*
X193453D01*
G01X193010Y455279D02*
X195871Y458141D01*
G01X193453Y454219D02*
X196314Y457081D01*
G01X195871Y458141D02*
X197981D01*
G01X196314Y457081D02*
X197538D01*
G01X197981Y458141D02*
X199807Y456315D01*
G01X197538Y457081D02*
X198747Y455872D01*
G01X199807Y456315D02*
Y454207D01*
G01X198747Y455872D02*
Y454646D01*
G01X199807Y454207D02*
X196946Y451345D01*
G01X198747Y454646D02*
X195886Y451784D01*
G01X196946Y451345D02*
Y450117D01*
G01X195886Y451784D02*
Y449675D01*
G01X196946Y450117D02*
X246792Y400271D01*
G01X195888Y449675D02*
X245732Y399831D01*
G01X242792Y398871D02*
X176671Y464992D01*
G01X241732Y398431D02*
X175613Y464550D01*
G01X175611D02*
Y487759D01*
G01X268952Y423072D02*
X217672Y474352D01*
G01X267892Y422632D02*
X216614Y473910D01*
G01X183212Y468806D02*
Y462879D01*
G01X184272Y469249D02*
Y463322D01*
G01X183212Y462879D02*
X184974Y461117D01*
G01X184272Y463322D02*
X185417Y462177D01*
G01X183212Y462879D02*
X184974Y461117D01*
G01D02*
X187614D01*
G01D02*
X189945Y463448D01*
G01X185417Y462177D02*
X187174D01*
G01X187614Y461117D02*
X189945Y463448D01*
G01D02*
X191174D01*
G01X187174Y462177D02*
X189505Y464508D01*
G01X189945Y463448D02*
X191174D01*
G01X189505Y464508D02*
X191614D01*
G01X191174Y463448D02*
X192380Y462242D01*
G01X191614Y464508D02*
X193440Y462682D01*
G01X192380Y462242D02*
Y461013D01*
G01X193440Y462682D02*
Y460574D01*
G01X192380Y461013D02*
X189519Y458151D01*
G01X193440Y460574D02*
X190579Y457712D01*
G01X189519Y458151D02*
Y456041D01*
G01X190579Y457712D02*
Y456484D01*
G01X189519Y456041D02*
X191341Y454219D01*
G01X190579Y456484D02*
X191784Y455279D01*
G01X191341Y454219D02*
X193453D01*
G01X191784Y455279D02*
X193010D01*
G01X193453Y454219D02*
X196314Y457081D01*
G01X193010Y455279D02*
X195871Y458141D01*
G01X196314Y457081D02*
X197538D01*
G01X195871Y458141D02*
X197981D01*
G01X197538Y457081D02*
X198747Y455872D01*
G01X197981Y458141D02*
X199807Y456315D01*
G01X198747Y455872D02*
Y454646D01*
G01X199807Y456315D02*
Y454207D01*
G01X198747Y454646D02*
X195886Y451784D01*
G01X199807Y454207D02*
X196946Y451345D01*
G01X195886Y451784D02*
Y449675D01*
G01X196946Y451345D02*
Y450117D01*
G01X195888Y449675D02*
X245732Y399831D01*
G01X196946Y450117D02*
X246792Y400271D01*
G01X176671Y464992D02*
Y487319D01*
G01X175611Y487759D02*
X177103Y489251D01*
G01X176671Y487319D02*
X177543Y488191D01*
G01X177103Y489251D02*
X178882D01*
G01X177543Y488191D02*
X179325D01*
G01X178882Y489251D02*
X179754Y490123D01*
G01X179325Y488191D02*
X180814Y489680D01*
G01X179754Y490123D02*
Y491822D01*
G01X180814Y489680D02*
Y492262D01*
G01X179754Y491822D02*
X178885Y492691D01*
G01X180814Y492262D02*
X179325Y493751D01*
G01X178885Y492691D02*
X177103D01*
G01X179325Y493751D02*
X177543D01*
G01X177103Y492691D02*
X175611Y494183D01*
G01X177543Y493751D02*
X176671Y494623D01*
G01X175611Y494183D02*
Y496759D01*
G01X176671Y494623D02*
Y496319D01*
G01X175611Y496759D02*
X177103Y498251D01*
G01X176671Y496319D02*
X177543Y497191D01*
G01X177103Y498251D02*
X178921D01*
G01X177543Y497191D02*
X179361D01*
G01X177103Y498251D02*
X178921D01*
G01D02*
X179838Y499168D01*
G01X179361Y497191D02*
X180898Y498728D01*
G01X179838Y499168D02*
Y500870D01*
G01X180898Y498728D02*
Y501310D01*
G01X179838Y500870D02*
X179017Y501691D01*
G01X180898Y501310D02*
X179457Y502751D01*
G01X179017Y501691D02*
X177103D01*
G01X179457Y502751D02*
X177543D01*
G01X177103Y501691D02*
X175611Y503183D01*
G01X177543Y502751D02*
X176671Y503623D01*
G01X175611Y503183D02*
Y587409D01*
G01X176671Y503623D02*
Y579416D01*
G01X175611Y503183D02*
Y587409D01*
G01Y503183D02*
Y587409D01*
G01X216612Y473910D02*
Y495509D01*
G01X217672Y474352D02*
Y495952D01*
G01X216612Y495509D02*
X212422Y499699D01*
G01X217672Y495952D02*
X213482Y500142D01*
G01X212422Y499699D02*
Y587409D01*
G01X213482Y500142D02*
Y587849D01*
G01X181771Y588035D02*
Y508052D01*
G01Y588035D02*
Y508052D01*
G01Y588035D02*
Y508052D01*
G01X180711Y578633D02*
Y507609D01*
G01X181771Y508052D02*
X184272Y505551D01*
G01X180711Y507609D02*
X183212Y505108D01*
G01X184272Y505551D02*
Y484667D01*
G01X183212Y505108D02*
Y485110D01*
G01X184272Y484667D02*
X182783Y483178D01*
G01X183212Y485110D02*
X182340Y484238D01*
G01X182783Y483178D02*
X182144D01*
G01X182340Y484238D02*
X181701D01*
G01X182144Y483178D02*
X181272Y482306D01*
G01X181701Y484238D02*
X180212Y482749D01*
G01X181272Y482306D02*
Y480610D01*
G01X180212Y482749D02*
Y480167D01*
G01X181272Y480610D02*
X182144Y479738D01*
G01X180212Y480167D02*
X181701Y478678D01*
G01X182144Y479738D02*
X182783D01*
G01X181701Y478678D02*
X182340D01*
G01X182783Y479738D02*
X184272Y478249D01*
G01X182340Y478678D02*
X183212Y477806D01*
G01X184272Y478249D02*
Y475667D01*
G01X183212Y477806D02*
Y476110D01*
G01X184272Y475667D02*
X182783Y474178D01*
G01X183212Y476110D02*
X182340Y475238D01*
G01X182783Y474178D02*
X182144D01*
G01X182340Y475238D02*
X181701D01*
G01X182144Y474178D02*
X181372Y473406D01*
G01X181701Y475238D02*
X180312Y473849D01*
G01X181372Y473406D02*
Y471510D01*
G01X180312Y473849D02*
Y471067D01*
G01X181372Y471510D02*
X182144Y470738D01*
G01X180312Y471067D02*
X181701Y469678D01*
G01X182144Y470738D02*
X182783D01*
G01X181701Y469678D02*
X182340D01*
G01X182783Y470738D02*
X184272Y469249D01*
G01X182340Y469678D02*
X183212Y468806D01*
G01X176671Y464992D02*
Y487319D01*
G01D02*
X177543Y488191D01*
G01X175611Y487759D02*
X177103Y489251D01*
G01X177543Y488191D02*
X179325D01*
G01X177103Y489251D02*
X178882D01*
G01X179325Y488191D02*
X180814Y489680D01*
G01X178882Y489251D02*
X179754Y490123D01*
G01X180814Y489680D02*
Y492262D01*
G01X179754Y490123D02*
Y491822D01*
G01X180814Y492262D02*
X179325Y493751D01*
G01X179754Y491822D02*
X178885Y492691D01*
G01X179325Y493751D02*
X177543D01*
G01X178885Y492691D02*
X177103D01*
G01X177543Y493751D02*
X176671Y494623D01*
G01X177103Y492691D02*
X175611Y494183D01*
G01X176671Y494623D02*
Y496319D01*
G01X175611Y494183D02*
Y496759D01*
G01X176671Y496319D02*
X177543Y497191D01*
G01X175611Y496759D02*
X177103Y498251D01*
G01X177543Y497191D02*
X179361D01*
G01D02*
X180898Y498728D01*
G01X177103Y498251D02*
X178921D01*
G01X179361Y497191D02*
X180898Y498728D01*
G01X178921Y498251D02*
X179838Y499168D01*
G01X180898Y498728D02*
Y501310D01*
G01X179838Y499168D02*
Y500870D01*
G01X180898Y501310D02*
X179457Y502751D01*
G01X179838Y500870D02*
X179017Y501691D01*
G01X179457Y502751D02*
X177543D01*
G01X179017Y501691D02*
X177103D01*
G01X177543Y502751D02*
X176671Y503623D01*
G01X177103Y501691D02*
X175611Y503183D01*
G01X176671Y503623D02*
Y579416D01*
G01X175611Y503183D02*
Y587409D01*
G01X217672Y474352D02*
Y495952D01*
G01X216612Y473910D02*
Y495509D01*
G01X217672Y495952D02*
X213482Y500142D01*
G01X216612Y495509D02*
X212422Y499699D01*
G01X213482Y500142D02*
Y587849D01*
G01X212422Y499699D02*
Y587409D01*
G01X180711Y578633D02*
Y507609D01*
G01X181771Y588035D02*
Y508052D01*
G01X180711Y507609D02*
X183212Y505108D01*
G01X181771Y508052D02*
X184272Y505551D01*
G01X183212Y505108D02*
Y485110D01*
G01X184272Y505551D02*
Y484667D01*
G01X183212Y485110D02*
X182340Y484238D01*
G01X184272Y484667D02*
X182783Y483178D01*
G01X182340Y484238D02*
X181701D01*
G01X182783Y483178D02*
X182144D01*
G01X181701Y484238D02*
X180212Y482749D01*
G01X182144Y483178D02*
X181272Y482306D01*
G01X180212Y482749D02*
Y480167D01*
G01X181272Y482306D02*
Y480610D01*
G01X180212Y480167D02*
X181701Y478678D01*
G01X181272Y480610D02*
X182144Y479738D01*
G01X181701Y478678D02*
X182340D01*
G01X182144Y479738D02*
X182783D01*
G01X182340Y478678D02*
X183212Y477806D01*
G01X182783Y479738D02*
X184272Y478249D01*
G01X183212Y477806D02*
Y476110D01*
G01X184272Y478249D02*
Y475667D01*
G01X183212Y476110D02*
X182340Y475238D01*
G01X184272Y475667D02*
X182783Y474178D01*
G01X182340Y475238D02*
X181701D01*
G01X182783Y474178D02*
X182144D01*
G01X181701Y475238D02*
X180312Y473849D01*
G01X182144Y474178D02*
X181372Y473406D01*
G01X180312Y473849D02*
Y471067D01*
G01X181372Y473406D02*
Y471510D01*
G01X180312Y471067D02*
X181701Y469678D01*
G01X181372Y471510D02*
X182144Y470738D01*
G01X181701Y469678D02*
X182340D01*
G01X182144Y470738D02*
X182783D01*
G01X182340Y469678D02*
X183212Y468806D01*
G01X182783Y470738D02*
X184272Y469249D01*
G01X233938Y466786D02*
X230878D01*
G01X233495Y465726D02*
X230438D01*
G01X230878Y466786D02*
X229535Y468129D01*
G01X230438Y465726D02*
X228475Y467689D01*
G01X229535Y468129D02*
Y470554D01*
G01X228475Y467689D02*
Y470114D01*
G01X229535Y470554D02*
X226936Y473153D01*
G01X228475Y470114D02*
X226496Y472093D01*
G01X226936Y473153D02*
X225508D01*
G01X226496Y472093D02*
X225068D01*
G01X226936Y473153D02*
X225508D01*
G01D02*
X223168Y475493D01*
G01X225068Y472093D02*
X222108Y475053D01*
G01X223168Y475493D02*
Y477553D01*
G01X222108Y475053D02*
Y477113D01*
G01X223168Y477553D02*
X221472Y479249D01*
G01X222108Y477113D02*
X220412Y478809D01*
G01X221472Y479249D02*
Y497652D01*
G01X220412Y478809D02*
Y497209D01*
G01X221472Y497652D02*
X218646Y500478D01*
G01X220412Y497209D02*
X217586Y500035D01*
G01X218646Y500478D02*
Y587986D01*
G01X217586Y500035D02*
Y522200D01*
G01X218646Y500478D02*
Y587986D01*
G01X217586Y524440D02*
Y525776D01*
G01X218646Y500478D02*
Y587986D01*
G01Y500478D02*
Y587986D01*
G01Y500478D02*
Y587986D01*
G01Y500478D02*
Y587986D01*
G01Y500478D02*
Y587986D01*
G01Y500478D02*
Y587986D01*
G01Y500478D02*
Y587986D01*
G01Y500478D02*
Y587986D01*
G01Y500478D02*
Y587986D01*
G01Y500478D02*
Y587986D01*
G01X233495Y465726D02*
X230438D01*
G01X233938Y466786D02*
X230878D01*
G01X230438Y465726D02*
X228475Y467689D01*
G01X230878Y466786D02*
X229535Y468129D01*
G01X228475Y467689D02*
Y470114D01*
G01X229535Y468129D02*
Y470554D01*
G01X228475Y470114D02*
X226496Y472093D01*
G01X229535Y470554D02*
X226936Y473153D01*
G01X226496Y472093D02*
X225068D01*
G01D02*
X222108Y475053D01*
G01X226936Y473153D02*
X225508D01*
G01X225068Y472093D02*
X222108Y475053D01*
G01X225508Y473153D02*
X223168Y475493D01*
G01X222108Y475053D02*
Y477113D01*
G01X223168Y475493D02*
Y477553D01*
G01X222108Y477113D02*
X220412Y478809D01*
G01X223168Y477553D02*
X221472Y479249D01*
G01X220412Y478809D02*
Y497209D01*
G01X221472Y479249D02*
Y497652D01*
G01X220412Y497209D02*
X217586Y500035D01*
G01X221472Y497652D02*
X218646Y500478D01*
G01X217586Y500035D02*
Y522200D01*
G01Y524440D02*
Y525776D01*
G01X218646Y500478D02*
Y587986D01*
G01X176671Y464992D02*
Y487319D01*
G01X175611Y487759D02*
X177103Y489251D01*
G01X176671Y487319D02*
X177543Y488191D01*
G01X177103Y489251D02*
X178882D01*
G01X177543Y488191D02*
X179325D01*
G01X178882Y489251D02*
X179754Y490123D01*
G01X179325Y488191D02*
X180814Y489680D01*
G01X179754Y490123D02*
Y491822D01*
G01X180814Y489680D02*
Y492262D01*
G01X179754Y491822D02*
X178885Y492691D01*
G01X180814Y492262D02*
X179325Y493751D01*
G01X178885Y492691D02*
X177103D01*
G01X179325Y493751D02*
X177543D01*
G01X177103Y492691D02*
X175611Y494183D01*
G01X177543Y493751D02*
X176671Y494623D01*
G01X175611Y494183D02*
Y496759D01*
G01X176671Y494623D02*
Y496319D01*
G01X175611Y496759D02*
X177103Y498251D01*
G01X176671Y496319D02*
X177543Y497191D01*
G01X177103Y498251D02*
X178921D01*
G01X177543Y497191D02*
X179361D01*
G01X177103Y498251D02*
X178921D01*
G01D02*
X179838Y499168D01*
G01X179361Y497191D02*
X180898Y498728D01*
G01X179838Y499168D02*
Y500870D01*
G01X180898Y498728D02*
Y501310D01*
G01X179838Y500870D02*
X179017Y501691D01*
G01X180898Y501310D02*
X179457Y502751D01*
G01X179017Y501691D02*
X177103D01*
G01X179457Y502751D02*
X177543D01*
G01X177103Y501691D02*
X175611Y503183D01*
G01X177543Y502751D02*
X176671Y503623D01*
G01X175611Y503183D02*
Y587409D01*
G01X176671Y503623D02*
Y579416D01*
G01X175611Y503183D02*
Y587409D01*
G01Y503183D02*
Y587409D01*
G01X216612Y473910D02*
Y495509D01*
G01X217672Y474352D02*
Y495952D01*
G01X216612Y495509D02*
X212422Y499699D01*
G01X217672Y495952D02*
X213482Y500142D01*
G01X212422Y499699D02*
Y587409D01*
G01X213482Y500142D02*
Y587849D01*
G01X181771Y588035D02*
Y508052D01*
G01Y588035D02*
Y508052D01*
G01Y588035D02*
Y508052D01*
G01X180711Y578633D02*
Y507609D01*
G01X181771Y508052D02*
X184272Y505551D01*
G01X180711Y507609D02*
X183212Y505108D01*
G01X184272Y505551D02*
Y484667D01*
G01X183212Y505108D02*
Y485110D01*
G01X184272Y484667D02*
X182783Y483178D01*
G01X183212Y485110D02*
X182340Y484238D01*
G01X182783Y483178D02*
X182144D01*
G01X182340Y484238D02*
X181701D01*
G01X182144Y483178D02*
X181272Y482306D01*
G01X181701Y484238D02*
X180212Y482749D01*
G01X181272Y482306D02*
Y480610D01*
G01X180212Y482749D02*
Y480167D01*
G01X181272Y480610D02*
X182144Y479738D01*
G01X180212Y480167D02*
X181701Y478678D01*
G01X182144Y479738D02*
X182783D01*
G01X181701Y478678D02*
X182340D01*
G01X182783Y479738D02*
X184272Y478249D01*
G01X182340Y478678D02*
X183212Y477806D01*
G01X184272Y478249D02*
Y475667D01*
G01X183212Y477806D02*
Y476110D01*
G01X184272Y475667D02*
X182783Y474178D01*
G01X183212Y476110D02*
X182340Y475238D01*
G01X182783Y474178D02*
X182144D01*
G01X182340Y475238D02*
X181701D01*
G01X182144Y474178D02*
X181372Y473406D01*
G01X181701Y475238D02*
X180312Y473849D01*
G01X181372Y473406D02*
Y471510D01*
G01X180312Y473849D02*
Y471067D01*
G01X181372Y471510D02*
X182144Y470738D01*
G01X180312Y471067D02*
X181701Y469678D01*
G01X182144Y470738D02*
X182783D01*
G01X181701Y469678D02*
X182340D01*
G01X182783Y470738D02*
X184272Y469249D01*
G01X182340Y469678D02*
X183212Y468806D01*
G01X233938Y466786D02*
X230878D01*
G01X233495Y465726D02*
X230438D01*
G01X230878Y466786D02*
X229535Y468129D01*
G01X230438Y465726D02*
X228475Y467689D01*
G01X229535Y468129D02*
Y470554D01*
G01X228475Y467689D02*
Y470114D01*
G01X229535Y470554D02*
X226936Y473153D01*
G01X228475Y470114D02*
X226496Y472093D01*
G01X226936Y473153D02*
X225508D01*
G01X226496Y472093D02*
X225068D01*
G01X226936Y473153D02*
X225508D01*
G01D02*
X223168Y475493D01*
G01X225068Y472093D02*
X222108Y475053D01*
G01X223168Y475493D02*
Y477553D01*
G01X222108Y475053D02*
Y477113D01*
G01X223168Y477553D02*
X221472Y479249D01*
G01X222108Y477113D02*
X220412Y478809D01*
G01X221472Y479249D02*
Y497652D01*
G01X220412Y478809D02*
Y497209D01*
G01X221472Y497652D02*
X218646Y500478D01*
G01X220412Y497209D02*
X217586Y500035D01*
G01X218646Y500478D02*
Y587986D01*
G01X217586Y500035D02*
Y522200D01*
G01X218646Y500478D02*
Y587986D01*
G01X217586Y524440D02*
Y525776D01*
G01X218646Y500478D02*
Y587986D01*
G01Y500478D02*
Y587986D01*
G01Y500478D02*
Y587986D01*
G01Y500478D02*
Y587986D01*
G01Y500478D02*
Y587986D01*
G01Y500478D02*
Y587986D01*
G01Y500478D02*
Y587986D01*
G01Y500478D02*
Y587986D01*
G01Y500478D02*
Y587986D01*
G01Y500478D02*
Y587986D01*
G01X176671Y464992D02*
Y487319D01*
G01D02*
X177543Y488191D01*
G01X175611Y487759D02*
X177103Y489251D01*
G01X177543Y488191D02*
X179325D01*
G01X177103Y489251D02*
X178882D01*
G01X179325Y488191D02*
X180814Y489680D01*
G01X178882Y489251D02*
X179754Y490123D01*
G01X180814Y489680D02*
Y492262D01*
G01X179754Y490123D02*
Y491822D01*
G01X180814Y492262D02*
X179325Y493751D01*
G01X179754Y491822D02*
X178885Y492691D01*
G01X179325Y493751D02*
X177543D01*
G01X178885Y492691D02*
X177103D01*
G01X177543Y493751D02*
X176671Y494623D01*
G01X177103Y492691D02*
X175611Y494183D01*
G01X176671Y494623D02*
Y496319D01*
G01X175611Y494183D02*
Y496759D01*
G01X176671Y496319D02*
X177543Y497191D01*
G01X175611Y496759D02*
X177103Y498251D01*
G01X177543Y497191D02*
X179361D01*
G01D02*
X180898Y498728D01*
G01X177103Y498251D02*
X178921D01*
G01X179361Y497191D02*
X180898Y498728D01*
G01X178921Y498251D02*
X179838Y499168D01*
G01X180898Y498728D02*
Y501310D01*
G01X179838Y499168D02*
Y500870D01*
G01X180898Y501310D02*
X179457Y502751D01*
G01X179838Y500870D02*
X179017Y501691D01*
G01X179457Y502751D02*
X177543D01*
G01X179017Y501691D02*
X177103D01*
G01X177543Y502751D02*
X176671Y503623D01*
G01X177103Y501691D02*
X175611Y503183D01*
G01X176671Y503623D02*
Y579416D01*
G01X175611Y503183D02*
Y587409D01*
G01X217672Y474352D02*
Y495952D01*
G01X216612Y473910D02*
Y495509D01*
G01X217672Y495952D02*
X213482Y500142D01*
G01X216612Y495509D02*
X212422Y499699D01*
G01X213482Y500142D02*
Y587849D01*
G01X212422Y499699D02*
Y587409D01*
G01X180711Y578633D02*
Y507609D01*
G01X181771Y588035D02*
Y508052D01*
G01X180711Y507609D02*
X183212Y505108D01*
G01X181771Y508052D02*
X184272Y505551D01*
G01X183212Y505108D02*
Y485110D01*
G01X184272Y505551D02*
Y484667D01*
G01X183212Y485110D02*
X182340Y484238D01*
G01X184272Y484667D02*
X182783Y483178D01*
G01X182340Y484238D02*
X181701D01*
G01X182783Y483178D02*
X182144D01*
G01X181701Y484238D02*
X180212Y482749D01*
G01X182144Y483178D02*
X181272Y482306D01*
G01X180212Y482749D02*
Y480167D01*
G01X181272Y482306D02*
Y480610D01*
G01X180212Y480167D02*
X181701Y478678D01*
G01X181272Y480610D02*
X182144Y479738D01*
G01X181701Y478678D02*
X182340D01*
G01X182144Y479738D02*
X182783D01*
G01X182340Y478678D02*
X183212Y477806D01*
G01X182783Y479738D02*
X184272Y478249D01*
G01X183212Y477806D02*
Y476110D01*
G01X184272Y478249D02*
Y475667D01*
G01X183212Y476110D02*
X182340Y475238D01*
G01X184272Y475667D02*
X182783Y474178D01*
G01X182340Y475238D02*
X181701D01*
G01X182783Y474178D02*
X182144D01*
G01X181701Y475238D02*
X180312Y473849D01*
G01X182144Y474178D02*
X181372Y473406D01*
G01X180312Y473849D02*
Y471067D01*
G01X181372Y473406D02*
Y471510D01*
G01X180312Y471067D02*
X181701Y469678D01*
G01X181372Y471510D02*
X182144Y470738D01*
G01X181701Y469678D02*
X182340D01*
G01X182144Y470738D02*
X182783D01*
G01X182340Y469678D02*
X183212Y468806D01*
G01X182783Y470738D02*
X184272Y469249D01*
G01X233495Y465726D02*
X230438D01*
G01X233938Y466786D02*
X230878D01*
G01X230438Y465726D02*
X228475Y467689D01*
G01X230878Y466786D02*
X229535Y468129D01*
G01X228475Y467689D02*
Y470114D01*
G01X229535Y468129D02*
Y470554D01*
G01X228475Y470114D02*
X226496Y472093D01*
G01X229535Y470554D02*
X226936Y473153D01*
G01X226496Y472093D02*
X225068D01*
G01D02*
X222108Y475053D01*
G01X226936Y473153D02*
X225508D01*
G01X225068Y472093D02*
X222108Y475053D01*
G01X225508Y473153D02*
X223168Y475493D01*
G01X222108Y475053D02*
Y477113D01*
G01X223168Y475493D02*
Y477553D01*
G01X222108Y477113D02*
X220412Y478809D01*
G01X223168Y477553D02*
X221472Y479249D01*
G01X220412Y478809D02*
Y497209D01*
G01X221472Y479249D02*
Y497652D01*
G01X220412Y497209D02*
X217586Y500035D01*
G01X221472Y497652D02*
X218646Y500478D01*
G01X217586Y500035D02*
Y522200D01*
G01Y524440D02*
Y525776D01*
G01X218646Y500478D02*
Y587986D01*
G01X176671Y581656D02*
Y582656D01*
G01Y584896D02*
Y587849D01*
G01X175611Y587409D02*
X174720Y588300D01*
G01X176671Y587849D02*
X173620Y590900D01*
G01X212422Y587409D02*
X211531Y588300D01*
G01X213482Y587849D02*
X210431Y590900D01*
G01X178692Y591114D02*
X181771Y588035D01*
G01X179792Y588514D02*
X180711Y587595D01*
G01D02*
Y583946D01*
G01Y581874D02*
Y580707D01*
G01X176671Y581656D02*
Y582656D01*
G01Y584896D02*
Y587849D01*
G01D02*
X173620Y590900D01*
G01X175611Y587409D02*
X174720Y588300D01*
G01X213482Y587849D02*
X210431Y590900D01*
G01X212422Y587409D02*
X211531Y588300D01*
G01X179792Y588514D02*
X180711Y587595D01*
G01X178692Y591114D02*
X181771Y588035D01*
G01X180711Y587595D02*
Y583946D01*
G01Y581874D02*
Y580707D01*
G01X217586Y528016D02*
Y538181D01*
G01Y540421D02*
Y541421D01*
G01Y543661D02*
Y544661D01*
G01Y546901D02*
Y556844D01*
G01Y559084D02*
Y560084D01*
G01Y562324D02*
Y563324D01*
G01Y565564D02*
Y575812D01*
G01Y578052D02*
Y579052D01*
G01Y581292D02*
Y582292D01*
G01Y584532D02*
Y587375D01*
G01Y528016D02*
Y538181D01*
G01Y540421D02*
Y541421D01*
G01Y543661D02*
Y544661D01*
G01Y546901D02*
Y556844D01*
G01Y559084D02*
Y560084D01*
G01Y562324D02*
Y563324D01*
G01Y565564D02*
Y575812D01*
G01Y578052D02*
Y579052D01*
G01Y581292D02*
Y582292D01*
G01Y584532D02*
Y587375D01*
G01X176671Y581656D02*
Y582656D01*
G01Y584896D02*
Y587849D01*
G01X175611Y587409D02*
X174720Y588300D01*
G01X176671Y587849D02*
X173620Y590900D01*
G01X212422Y587409D02*
X211531Y588300D01*
G01X213482Y587849D02*
X210431Y590900D01*
G01X178692Y591114D02*
X181771Y588035D01*
G01X179792Y588514D02*
X180711Y587595D01*
G01D02*
Y583946D01*
G01Y581874D02*
Y580707D01*
G01X217586Y528016D02*
Y538181D01*
G01Y540421D02*
Y541421D01*
G01Y543661D02*
Y544661D01*
G01Y546901D02*
Y556844D01*
G01Y559084D02*
Y560084D01*
G01Y562324D02*
Y563324D01*
G01Y565564D02*
Y575812D01*
G01Y578052D02*
Y579052D01*
G01Y581292D02*
Y582292D01*
G01Y584532D02*
Y587375D01*
G01X176671Y581656D02*
Y582656D01*
G01Y584896D02*
Y587849D01*
G01D02*
X173620Y590900D01*
G01X175611Y587409D02*
X174720Y588300D01*
G01X213482Y587849D02*
X210431Y590900D01*
G01X212422Y587409D02*
X211531Y588300D01*
G01X179792Y588514D02*
X180711Y587595D01*
G01X178692Y591114D02*
X181771Y588035D01*
G01X180711Y587595D02*
Y583946D01*
G01Y581874D02*
Y580707D01*
G01X217586Y528016D02*
Y538181D01*
G01Y540421D02*
Y541421D01*
G01Y543661D02*
Y544661D01*
G01Y546901D02*
Y556844D01*
G01Y559084D02*
Y560084D01*
G01Y562324D02*
Y563324D01*
G01Y565564D02*
Y575812D01*
G01Y578052D02*
Y579052D01*
G01Y581292D02*
Y582292D01*
G01Y584532D02*
Y587375D01*
G01X171603Y590000D02*
Y608011D01*
G01X172663Y595890D02*
Y597260D01*
G01X171603Y590000D02*
Y608011D01*
G01X172663Y600940D02*
Y602360D01*
G01X208414Y590000D02*
Y608011D01*
G01X209474Y595890D02*
Y597260D01*
G01X208414Y590000D02*
Y608011D01*
G01X209474Y600940D02*
Y602360D01*
G01X177887Y595500D02*
X177216Y596171D01*
G01X176986Y594900D02*
X176156Y595730D01*
G01X177216Y596171D02*
Y597448D01*
G01Y600938D02*
Y601829D01*
G01X176156Y595730D02*
Y602270D01*
G01X177216Y601829D02*
X177987Y602600D01*
G01X176156Y602270D02*
X176986Y603100D01*
G01X172663Y595890D02*
Y597260D01*
G01Y600940D02*
Y602360D01*
G01X171603Y590000D02*
Y608011D01*
G01X209474Y595890D02*
Y597260D01*
G01Y600940D02*
Y602360D01*
G01X208414Y590000D02*
Y608011D01*
G01X176986Y594900D02*
X176156Y595730D01*
G01X177887Y595500D02*
X177216Y596171D01*
G01X176156Y595730D02*
Y602270D01*
G01X177216Y596171D02*
Y597448D01*
G01X176156Y595730D02*
Y602270D01*
G01X177216Y600938D02*
Y601829D01*
G01X176156Y602270D02*
X176986Y603100D01*
G01X177216Y601829D02*
X177987Y602600D01*
G01X214698Y595500D02*
X214027Y596171D01*
G01X213797Y594900D02*
X212967Y595730D01*
G01X214027Y596171D02*
Y597448D01*
G01Y600938D02*
Y601829D01*
G01X212967Y595730D02*
Y602270D01*
G01X214027Y601829D02*
X214798Y602600D01*
G01X212967Y602270D02*
X213797Y603100D01*
G01Y594900D02*
X212967Y595730D01*
G01X214698Y595500D02*
X214027Y596171D01*
G01X212967Y595730D02*
Y602270D01*
G01X214027Y596171D02*
Y597448D01*
G01X212967Y595730D02*
Y602270D01*
G01X214027Y600938D02*
Y601829D01*
G01X212967Y602270D02*
X213797Y603100D01*
G01X214027Y601829D02*
X214798Y602600D01*
G01X171603Y590000D02*
Y608011D01*
G01X172663Y595890D02*
Y597260D01*
G01X171603Y590000D02*
Y608011D01*
G01X172663Y600940D02*
Y602360D01*
G01X208414Y590000D02*
Y608011D01*
G01X209474Y595890D02*
Y597260D01*
G01X208414Y590000D02*
Y608011D01*
G01X209474Y600940D02*
Y602360D01*
G01X177887Y595500D02*
X177216Y596171D01*
G01X176986Y594900D02*
X176156Y595730D01*
G01X177216Y596171D02*
Y597448D01*
G01Y600938D02*
Y601829D01*
G01X176156Y595730D02*
Y602270D01*
G01X177216Y601829D02*
X177987Y602600D01*
G01X176156Y602270D02*
X176986Y603100D01*
G01X214698Y595500D02*
X214027Y596171D01*
G01X213797Y594900D02*
X212967Y595730D01*
G01X214027Y596171D02*
Y597448D01*
G01Y600938D02*
Y601829D01*
G01X212967Y595730D02*
Y602270D01*
G01X214027Y601829D02*
X214798Y602600D01*
G01X212967Y602270D02*
X213797Y603100D01*
G01X172663Y595890D02*
Y597260D01*
G01Y600940D02*
Y602360D01*
G01X171603Y590000D02*
Y608011D01*
G01X209474Y595890D02*
Y597260D01*
G01Y600940D02*
Y602360D01*
G01X208414Y590000D02*
Y608011D01*
G01X176986Y594900D02*
X176156Y595730D01*
G01X177887Y595500D02*
X177216Y596171D01*
G01X176156Y595730D02*
Y602270D01*
G01X177216Y596171D02*
Y597448D01*
G01X176156Y595730D02*
Y602270D01*
G01X177216Y600938D02*
Y601829D01*
G01X176156Y602270D02*
X176986Y603100D01*
G01X177216Y601829D02*
X177987Y602600D01*
G01X213797Y594900D02*
X212967Y595730D01*
G01X214698Y595500D02*
X214027Y596171D01*
G01X212967Y595730D02*
Y602270D01*
G01X214027Y596171D02*
Y597448D01*
G01X212967Y595730D02*
Y602270D01*
G01X214027Y600938D02*
Y601829D01*
G01X212967Y602270D02*
X213797Y603100D01*
G01X214027Y601829D02*
X214798Y602600D01*
G01X286070Y33291D02*
X285359Y32580D01*
G01D02*
X284843D01*
G01X287130Y32848D02*
X285802Y31520D01*
G01X285359Y32580D02*
X284843D01*
G01X285802Y31520D02*
X284820D01*
G01X287130Y32848D02*
X285802Y31520D01*
G01X286070Y33291D02*
X285359Y32580D01*
G01X287130Y32848D02*
X285802Y31520D01*
G01D02*
X284820D01*
G01X285359Y32580D02*
X284843D01*
G01X292316Y33732D02*
X289124Y30540D01*
G01X248032Y-5220D02*
X248548D01*
G01X248009Y-6280D02*
X248991D01*
G01X248032Y-5220D02*
X248548D01*
G01D02*
X249259Y-4509D01*
G01X248991Y-6280D02*
X250319Y-4952D01*
G01X249259Y-4509D02*
Y-1220D01*
G01Y3120D02*
Y4080D01*
G01Y8220D02*
Y10753D01*
G01X250319Y-4952D02*
Y11194D01*
G01X249259Y10753D02*
X248312Y11700D01*
G01X250319Y11194D02*
X247213Y14300D01*
G01X245359Y13554D02*
Y21531D01*
G01X246419Y19620D02*
Y21088D01*
G01X245359Y21531D02*
X249233Y25405D01*
G01X246419Y21088D02*
X250293Y24962D01*
G01X249233Y25405D02*
Y115009D01*
G01X250293Y24962D02*
Y36780D01*
G01X249233Y25405D02*
Y115009D01*
G01Y25405D02*
Y115009D01*
G01Y25405D02*
Y115009D01*
G01Y25405D02*
Y115009D01*
G01X248032Y-5220D02*
X248548D01*
G01X248009Y-6280D02*
X248991D01*
G01X248032Y-5220D02*
X248548D01*
G01D02*
X249259Y-4509D01*
G01X248991Y-6280D02*
X250319Y-4952D01*
G01X249259Y-4509D02*
Y-1220D01*
G01Y3120D02*
Y4080D01*
G01Y8220D02*
Y10753D01*
G01X250319Y-4952D02*
Y11194D01*
G01X249259Y10753D02*
X248312Y11700D01*
G01X250319Y11194D02*
X247213Y14300D01*
G01X245359Y13554D02*
Y21531D01*
G01X246419Y19620D02*
Y21088D01*
G01X245359Y21531D02*
X249233Y25405D01*
G01X246419Y21088D02*
X250293Y24962D01*
G01X249233Y25405D02*
Y115009D01*
G01X250293Y24962D02*
Y36780D01*
G01X249233Y25405D02*
Y115009D01*
G01Y25405D02*
Y115009D01*
G01Y25405D02*
Y115009D01*
G01Y25405D02*
Y115009D01*
G01X284843Y-5220D02*
X285359D01*
G01X284820Y-6280D02*
X285802D01*
G01X284843Y-5220D02*
X285359D01*
G01D02*
X286070Y-4509D01*
G01X285802Y-6280D02*
X287130Y-4952D01*
G01X286070Y-4509D02*
Y-1220D01*
G01Y3120D02*
Y4080D01*
G01Y8220D02*
Y10753D01*
G01X287130Y-4952D02*
Y11194D01*
G01X286070Y10753D02*
X285123Y11700D01*
G01D02*
X284024D01*
G01X287130Y11194D02*
X284024Y14300D01*
G01X252313Y-4651D02*
X253422D01*
G01D02*
X254445Y-3628D01*
G01X252313Y-7260D02*
X255505Y-4068D01*
G01X254445Y-3628D02*
Y-1007D01*
G01Y2907D02*
Y4280D01*
G01Y8106D02*
Y10881D01*
G01X255505Y-4068D02*
Y11322D01*
G01X254445Y10881D02*
X253411Y11915D01*
G01D02*
X252313D01*
G01X255505Y11322D02*
X252313Y14514D01*
G01X251059Y18567D02*
Y21231D01*
G01X252119Y19920D02*
Y20788D01*
G01X251059Y21231D02*
X254333Y24505D01*
G01X252119Y20788D02*
X253093Y21762D01*
G01X251059Y21231D02*
X254333Y24505D01*
G01X254677Y23346D02*
X255393Y24062D01*
G01X254333Y24505D02*
Y114709D01*
G01X255393Y24062D02*
Y32500D01*
G01X254333Y24505D02*
Y114709D01*
G01Y24505D02*
Y114709D01*
G01Y24505D02*
Y114709D01*
G01X252313Y-4651D02*
X253422D01*
G01D02*
X254445Y-3628D01*
G01X252313Y-7260D02*
X255505Y-4068D01*
G01X254445Y-3628D02*
Y-1007D01*
G01Y2907D02*
Y4280D01*
G01Y8106D02*
Y10881D01*
G01X255505Y-4068D02*
Y11322D01*
G01X254445Y10881D02*
X253411Y11915D01*
G01D02*
X252313D01*
G01X255505Y11322D02*
X252313Y14514D01*
G01X251059Y18567D02*
Y21231D01*
G01X252119Y19920D02*
Y20788D01*
G01X251059Y21231D02*
X254333Y24505D01*
G01X252119Y20788D02*
X253093Y21762D01*
G01X251059Y21231D02*
X254333Y24505D01*
G01X254677Y23346D02*
X255393Y24062D01*
G01X254333Y24505D02*
Y114709D01*
G01X255393Y24062D02*
Y32500D01*
G01X254333Y24505D02*
Y114709D01*
G01Y24505D02*
Y114709D01*
G01Y24505D02*
Y114709D01*
G01X289124Y-4651D02*
X290233D01*
G01D02*
X291256Y-3628D01*
G01X289124Y-7260D02*
X292316Y-4068D01*
G01X291256Y-3628D02*
Y-1007D01*
G01Y2907D02*
Y4280D01*
G01Y8106D02*
Y10881D01*
G01X292316Y-4068D02*
Y11322D01*
G01X291256Y10881D02*
X290222Y11915D01*
G01D02*
X289124D01*
G01X292316Y11322D02*
X289124Y14514D01*
G01X248009Y-6280D02*
X248991D01*
G01D02*
X250319Y-4952D01*
G01X248032Y-5220D02*
X248548D01*
G01X248991Y-6280D02*
X250319Y-4952D01*
G01X248548Y-5220D02*
X249259Y-4509D01*
G01X250319Y-4952D02*
Y11194D01*
G01X249259Y-4509D02*
Y-1220D01*
G01X250319Y-4952D02*
Y11194D01*
G01X249259Y3120D02*
Y4080D01*
G01X250319Y-4952D02*
Y11194D01*
G01X249259Y8220D02*
Y10753D01*
G01X250319Y11194D02*
X247213Y14300D01*
G01X249259Y10753D02*
X248312Y11700D01*
G01X246419Y19620D02*
Y21088D01*
G01X245359Y13554D02*
Y21531D01*
G01X246419Y21088D02*
X250293Y24962D01*
G01X245359Y21531D02*
X249233Y25405D01*
G01X250293Y24962D02*
Y36780D01*
G01X249233Y25405D02*
Y115009D01*
G01X248009Y-6280D02*
X248991D01*
G01D02*
X250319Y-4952D01*
G01X248032Y-5220D02*
X248548D01*
G01X248991Y-6280D02*
X250319Y-4952D01*
G01X248548Y-5220D02*
X249259Y-4509D01*
G01X250319Y-4952D02*
Y11194D01*
G01X249259Y-4509D02*
Y-1220D01*
G01X250319Y-4952D02*
Y11194D01*
G01X249259Y3120D02*
Y4080D01*
G01X250319Y-4952D02*
Y11194D01*
G01X249259Y8220D02*
Y10753D01*
G01X250319Y11194D02*
X247213Y14300D01*
G01X249259Y10753D02*
X248312Y11700D01*
G01X246419Y19620D02*
Y21088D01*
G01X245359Y13554D02*
Y21531D01*
G01X246419Y21088D02*
X250293Y24962D01*
G01X245359Y21531D02*
X249233Y25405D01*
G01X250293Y24962D02*
Y36780D01*
G01X249233Y25405D02*
Y115009D01*
G01X284820Y-6280D02*
X285802D01*
G01D02*
X287130Y-4952D01*
G01X284843Y-5220D02*
X285359D01*
G01X285802Y-6280D02*
X287130Y-4952D01*
G01X285359Y-5220D02*
X286070Y-4509D01*
G01X287130Y-4952D02*
Y11194D01*
G01X286070Y-4509D02*
Y-1220D01*
G01X287130Y-4952D02*
Y11194D01*
G01X286070Y3120D02*
Y4080D01*
G01X287130Y-4952D02*
Y11194D01*
G01X286070Y8220D02*
Y10753D01*
G01X287130Y11194D02*
X284024Y14300D01*
G01X286070Y10753D02*
X285123Y11700D01*
G01X287130Y11194D02*
X284024Y14300D01*
G01X285123Y11700D02*
X284024D01*
G01X252313Y-7260D02*
X255505Y-4068D01*
G01X252313Y-4651D02*
X253422D01*
G01X252313Y-7260D02*
X255505Y-4068D01*
G01X253422Y-4651D02*
X254445Y-3628D01*
G01X255505Y-4068D02*
Y11322D01*
G01X254445Y-3628D02*
Y-1007D01*
G01X255505Y-4068D02*
Y11322D01*
G01X254445Y2907D02*
Y4280D01*
G01X255505Y-4068D02*
Y11322D01*
G01X254445Y8106D02*
Y10881D01*
G01X255505Y11322D02*
X252313Y14514D01*
G01X254445Y10881D02*
X253411Y11915D01*
G01X255505Y11322D02*
X252313Y14514D01*
G01X253411Y11915D02*
X252313D01*
G01X252119Y19920D02*
Y20788D01*
G01X251059Y18567D02*
Y21231D01*
G01X252119Y20788D02*
X253093Y21762D01*
G01X254677Y23346D02*
X255393Y24062D01*
G01X251059Y21231D02*
X254333Y24505D01*
G01X255393Y24062D02*
Y32500D01*
G01X254333Y24505D02*
Y114709D01*
G01X252313Y-7260D02*
X255505Y-4068D01*
G01X252313Y-4651D02*
X253422D01*
G01X252313Y-7260D02*
X255505Y-4068D01*
G01X253422Y-4651D02*
X254445Y-3628D01*
G01X255505Y-4068D02*
Y11322D01*
G01X254445Y-3628D02*
Y-1007D01*
G01X255505Y-4068D02*
Y11322D01*
G01X254445Y2907D02*
Y4280D01*
G01X255505Y-4068D02*
Y11322D01*
G01X254445Y8106D02*
Y10881D01*
G01X255505Y11322D02*
X252313Y14514D01*
G01X254445Y10881D02*
X253411Y11915D01*
G01X255505Y11322D02*
X252313Y14514D01*
G01X253411Y11915D02*
X252313D01*
G01X252119Y19920D02*
Y20788D01*
G01X251059Y18567D02*
Y21231D01*
G01X252119Y20788D02*
X253093Y21762D01*
G01X254677Y23346D02*
X255393Y24062D01*
G01X251059Y21231D02*
X254333Y24505D01*
G01X255393Y24062D02*
Y32500D01*
G01X254333Y24505D02*
Y114709D01*
G01X289124Y-7260D02*
X292316Y-4068D01*
G01X289124Y-4651D02*
X290233D01*
G01X289124Y-7260D02*
X292316Y-4068D01*
G01X290233Y-4651D02*
X291256Y-3628D01*
G01X292316Y-4068D02*
Y11322D01*
G01X291256Y-3628D02*
Y-1007D01*
G01X292316Y-4068D02*
Y11322D01*
G01X291256Y2907D02*
Y4280D01*
G01X292316Y-4068D02*
Y11322D01*
G01X291256Y8106D02*
Y10881D01*
G01X292316Y11322D02*
X289124Y14514D01*
G01X291256Y10881D02*
X290222Y11915D01*
G01X292316Y11322D02*
X289124Y14514D01*
G01X290222Y11915D02*
X289124D01*
G01X286070Y33291D02*
X285359Y32580D01*
G01D02*
X284843D01*
G01X287130Y32848D02*
X285802Y31520D01*
G01X285359Y32580D02*
X284843D01*
G01X285802Y31520D02*
X284820D01*
G01X292316Y33732D02*
X289124Y30540D01*
G01X292316Y33732D02*
X289124Y30540D01*
G01X292316Y33732D02*
X289124Y30540D01*
G01X292316Y33732D02*
X289124Y30540D01*
G01X287130Y32848D02*
X285802Y31520D01*
G01X286070Y33291D02*
X285359Y32580D01*
G01X287130Y32848D02*
X285802Y31520D01*
G01D02*
X284820D01*
G01X285359Y32580D02*
X284843D01*
G01X292316Y33732D02*
X289124Y30540D01*
G01X285981Y105934D02*
Y62190D01*
G01X287041Y107497D02*
Y61747D01*
G01X285981Y62190D02*
X283981Y60190D01*
G01X287041Y61747D02*
X285041Y59747D01*
G01X283981Y60190D02*
Y57320D01*
G01X285041Y59747D02*
Y56451D01*
G01X284024Y49500D02*
X285123D01*
G01D02*
X286070Y48553D01*
G01X284024Y52100D02*
X287130Y48994D01*
G01X286070Y48553D02*
Y46020D01*
G01Y41880D02*
Y40920D01*
G01Y36580D02*
Y33291D01*
G01X287130Y48994D02*
Y32848D01*
G01X287041Y107497D02*
Y61747D01*
G01X285981Y105934D02*
Y62190D01*
G01X287041Y61747D02*
X285041Y59747D01*
G01X285981Y62190D02*
X283981Y60190D01*
G01X285041Y59747D02*
Y56451D01*
G01X283981Y60190D02*
Y57320D01*
G01X284024Y52100D02*
X287130Y48994D01*
G01X284024Y49500D02*
X285123D01*
G01X284024Y52100D02*
X287130Y48994D01*
G01X285123Y49500D02*
X286070Y48553D01*
G01X287130Y48994D02*
Y32848D01*
G01X286070Y48553D02*
Y46020D01*
G01X287130Y48994D02*
Y32848D01*
G01X286070Y41880D02*
Y40920D01*
G01X287130Y48994D02*
Y32848D01*
G01X286070Y36580D02*
Y33291D01*
G01X291081Y105698D02*
Y60092D01*
G01X292141Y107247D02*
Y59649D01*
G01X291081Y60092D02*
X289181Y58192D01*
G01X292141Y59649D02*
X290241Y57749D01*
G01X289181Y58192D02*
Y57520D01*
G01X290241Y57749D02*
Y56620D01*
G01X289124Y49715D02*
X290222D01*
G01D02*
X291256Y48681D01*
G01X289124Y52314D02*
X292316Y49122D01*
G01X291256Y48681D02*
Y45906D01*
G01Y42080D02*
Y40707D01*
G01Y36793D02*
Y34172D01*
G01X292316Y49122D02*
Y33732D01*
G01X291256Y34172D02*
X290233Y33149D01*
G01D02*
X289124D01*
G01X250293Y39020D02*
Y39780D01*
G01Y42020D02*
Y42780D01*
G01Y45020D02*
Y55880D01*
G01Y58120D02*
Y114569D01*
G01Y39020D02*
Y39780D01*
G01Y42020D02*
Y42780D01*
G01Y45020D02*
Y55880D01*
G01Y58120D02*
Y114569D01*
G01X255393Y34500D02*
Y36980D01*
G01Y39220D02*
Y39980D01*
G01Y42220D02*
Y114269D01*
G01Y34500D02*
Y36980D01*
G01Y39220D02*
Y39980D01*
G01Y42220D02*
Y114269D01*
G01X250293Y39020D02*
Y39780D01*
G01Y42020D02*
Y42780D01*
G01Y45020D02*
Y55880D01*
G01Y58120D02*
Y114569D01*
G01Y39020D02*
Y39780D01*
G01Y42020D02*
Y42780D01*
G01Y45020D02*
Y55880D01*
G01Y58120D02*
Y114569D01*
G01X255393Y34500D02*
Y36980D01*
G01Y39220D02*
Y39980D01*
G01Y42220D02*
Y114269D01*
G01Y34500D02*
Y36980D01*
G01Y39220D02*
Y39980D01*
G01Y42220D02*
Y114269D01*
G01X285981Y105934D02*
Y62190D01*
G01X287041Y107497D02*
Y61747D01*
G01X285981Y62190D02*
X283981Y60190D01*
G01X287041Y61747D02*
X285041Y59747D01*
G01X283981Y60190D02*
Y57320D01*
G01X285041Y59747D02*
Y56451D01*
G01X284024Y49500D02*
X285123D01*
G01D02*
X286070Y48553D01*
G01X284024Y52100D02*
X287130Y48994D01*
G01X286070Y48553D02*
Y46020D01*
G01Y41880D02*
Y40920D01*
G01Y36580D02*
Y33291D01*
G01X287130Y48994D02*
Y32848D01*
G01X289124Y52314D02*
X292316Y49122D01*
G01X289124Y49715D02*
X290222D01*
G01X289124Y52314D02*
X292316Y49122D01*
G01X290222Y49715D02*
X291256Y48681D01*
G01X292316Y49122D02*
Y33732D01*
G01X291256Y48681D02*
Y45906D01*
G01X292316Y49122D02*
Y33732D01*
G01X291256Y42080D02*
Y40707D01*
G01X292316Y49122D02*
Y33732D01*
G01X291256Y36793D02*
Y34172D01*
G01D02*
X290233Y33149D01*
G01D02*
X289124D01*
G01X292141Y107247D02*
Y59649D01*
G01X291081Y105698D02*
Y60092D01*
G01X292141Y59649D02*
X290241Y57749D01*
G01X291081Y60092D02*
X289181Y58192D01*
G01X290241Y57749D02*
Y56620D01*
G01X289181Y58192D02*
Y57520D01*
G01X289124Y52314D02*
X292316Y49122D01*
G01X289124Y49715D02*
X290222D01*
G01X289124Y52314D02*
X292316Y49122D01*
G01X290222Y49715D02*
X291256Y48681D01*
G01X292316Y49122D02*
Y33732D01*
G01X291256Y48681D02*
Y45906D01*
G01X292316Y49122D02*
Y33732D01*
G01X291256Y42080D02*
Y40707D01*
G01X292316Y49122D02*
Y33732D01*
G01X291256Y36793D02*
Y34172D01*
G01D02*
X290233Y33149D01*
G01D02*
X289124D01*
G01X292141Y107247D02*
Y59649D01*
G01X291081Y105698D02*
Y60092D01*
G01X292141Y59649D02*
X290241Y57749D01*
G01X291081Y60092D02*
X289181Y58192D01*
G01X290241Y57749D02*
Y56620D01*
G01X289181Y58192D02*
Y57520D01*
G01X287041Y107497D02*
Y61747D01*
G01X285981Y105934D02*
Y62190D01*
G01X287041Y61747D02*
X285041Y59747D01*
G01X285981Y62190D02*
X283981Y60190D01*
G01X285041Y59747D02*
Y56451D01*
G01X283981Y60190D02*
Y57320D01*
G01X284024Y52100D02*
X287130Y48994D01*
G01X284024Y49500D02*
X285123D01*
G01X284024Y52100D02*
X287130Y48994D01*
G01X285123Y49500D02*
X286070Y48553D01*
G01X287130Y48994D02*
Y32848D01*
G01X286070Y48553D02*
Y46020D01*
G01X287130Y48994D02*
Y32848D01*
G01X286070Y41880D02*
Y40920D01*
G01X287130Y48994D02*
Y32848D01*
G01X286070Y36580D02*
Y33291D01*
G01X291081Y105698D02*
Y60092D01*
G01X292141Y107247D02*
Y59649D01*
G01X291081Y60092D02*
X289181Y58192D01*
G01X292141Y59649D02*
X290241Y57749D01*
G01X289181Y58192D02*
Y57520D01*
G01X290241Y57749D02*
Y56620D01*
G01X289124Y49715D02*
X290222D01*
G01D02*
X291256Y48681D01*
G01X289124Y52314D02*
X292316Y49122D01*
G01X291256Y48681D02*
Y45906D01*
G01Y42080D02*
Y40707D01*
G01Y36793D02*
Y34172D01*
G01X292316Y49122D02*
Y33732D01*
G01X291256Y34172D02*
X290233Y33149D01*
G01D02*
X289124D01*
G01X249233Y115009D02*
X256474Y122250D01*
G01X250293Y114569D02*
X257534Y121810D01*
G01X256474Y122250D02*
Y123482D01*
G01X257534Y121810D02*
Y123922D01*
G01X256474Y123482D02*
X254057Y125899D01*
G01X257534Y123922D02*
X255117Y126339D01*
G01X254057Y125899D02*
Y127819D01*
G01X255117Y126339D02*
Y127379D01*
G01X254057Y127819D02*
X256577Y130339D01*
G01X255117Y127379D02*
X257017Y129279D01*
G01X256577Y130339D02*
X258617D01*
G01X257017Y129279D02*
X258177D01*
G01X258617Y130339D02*
X260974Y127982D01*
G01D02*
X262206D01*
G01X258177Y129279D02*
X260534Y126922D01*
G01X260974Y127982D02*
X262206D01*
G01X260534Y126922D02*
X262646D01*
G01X262206Y127982D02*
X272803Y138579D01*
G01X262646Y126922D02*
X273863Y138139D01*
G01X272803Y138579D02*
Y147904D01*
G01X273863Y138139D02*
Y147464D01*
G01X272803Y147904D02*
X313592Y188693D01*
G01X273863Y147464D02*
X297559Y171160D01*
G01X272803Y147904D02*
X313592Y188693D01*
G01X272803Y147904D02*
X313592Y188693D01*
G01X272803Y147904D02*
X313592Y188693D01*
G01X272803Y147904D02*
X313592Y188693D01*
G01X272803Y147904D02*
X313592Y188693D01*
G01X272803Y147904D02*
X313592Y188693D01*
G01X272803Y147904D02*
X313592Y188693D01*
G01X272803Y147904D02*
X313592Y188693D01*
G01X249233Y115009D02*
X256474Y122250D01*
G01X250293Y114569D02*
X257534Y121810D01*
G01X256474Y122250D02*
Y123482D01*
G01X257534Y121810D02*
Y123922D01*
G01X256474Y123482D02*
X254057Y125899D01*
G01X257534Y123922D02*
X255117Y126339D01*
G01X254057Y125899D02*
Y127819D01*
G01X255117Y126339D02*
Y127379D01*
G01X254057Y127819D02*
X256577Y130339D01*
G01X255117Y127379D02*
X257017Y129279D01*
G01X256577Y130339D02*
X258617D01*
G01X257017Y129279D02*
X258177D01*
G01X258617Y130339D02*
X260974Y127982D01*
G01D02*
X262206D01*
G01X258177Y129279D02*
X260534Y126922D01*
G01X260974Y127982D02*
X262206D01*
G01X260534Y126922D02*
X262646D01*
G01X262206Y127982D02*
X272803Y138579D01*
G01X262646Y126922D02*
X273863Y138139D01*
G01X272803Y138579D02*
Y147904D01*
G01X273863Y138139D02*
Y147464D01*
G01X272803Y147904D02*
X313592Y188693D01*
G01X273863Y147464D02*
X297559Y171160D01*
G01X272803Y147904D02*
X313592Y188693D01*
G01X272803Y147904D02*
X313592Y188693D01*
G01X272803Y147904D02*
X313592Y188693D01*
G01X272803Y147904D02*
X313592Y188693D01*
G01X272803Y147904D02*
X313592Y188693D01*
G01X272803Y147904D02*
X313592Y188693D01*
G01X272803Y147904D02*
X313592Y188693D01*
G01X272803Y147904D02*
X313592Y188693D01*
G01X254333Y114709D02*
X277375Y137751D01*
G01X255393Y114269D02*
X278435Y137311D01*
G01X277375Y137751D02*
Y147058D01*
G01X278435Y137311D02*
Y146618D01*
G01X277375Y147058D02*
X317685Y187368D01*
G01X278435Y146618D02*
X323382Y191565D01*
G01X254333Y114709D02*
X277375Y137751D01*
G01X255393Y114269D02*
X278435Y137311D01*
G01X277375Y137751D02*
Y147058D01*
G01X278435Y137311D02*
Y146618D01*
G01X277375Y147058D02*
X317685Y187368D01*
G01X278435Y146618D02*
X323382Y191565D01*
G01X250293Y114569D02*
X257534Y121810D01*
G01X249233Y115009D02*
X256474Y122250D01*
G01X257534Y121810D02*
Y123922D01*
G01X256474Y122250D02*
Y123482D01*
G01X257534Y123922D02*
X255117Y126339D01*
G01X256474Y123482D02*
X254057Y125899D01*
G01X255117Y126339D02*
Y127379D01*
G01X254057Y125899D02*
Y127819D01*
G01X255117Y127379D02*
X257017Y129279D01*
G01X254057Y127819D02*
X256577Y130339D01*
G01X257017Y129279D02*
X258177D01*
G01X256577Y130339D02*
X258617D01*
G01X258177Y129279D02*
X260534Y126922D01*
G01X258617Y130339D02*
X260974Y127982D01*
G01X258177Y129279D02*
X260534Y126922D01*
G01D02*
X262646D01*
G01X260974Y127982D02*
X262206D01*
G01X262646Y126922D02*
X273863Y138139D01*
G01X262206Y127982D02*
X272803Y138579D01*
G01X273863Y138139D02*
Y147464D01*
G01X272803Y138579D02*
Y147904D01*
G01X273863Y147464D02*
X297559Y171160D01*
G01X272803Y147904D02*
X313592Y188693D01*
G01X250293Y114569D02*
X257534Y121810D01*
G01X249233Y115009D02*
X256474Y122250D01*
G01X257534Y121810D02*
Y123922D01*
G01X256474Y122250D02*
Y123482D01*
G01X257534Y123922D02*
X255117Y126339D01*
G01X256474Y123482D02*
X254057Y125899D01*
G01X255117Y126339D02*
Y127379D01*
G01X254057Y125899D02*
Y127819D01*
G01X255117Y127379D02*
X257017Y129279D01*
G01X254057Y127819D02*
X256577Y130339D01*
G01X257017Y129279D02*
X258177D01*
G01X256577Y130339D02*
X258617D01*
G01X258177Y129279D02*
X260534Y126922D01*
G01X258617Y130339D02*
X260974Y127982D01*
G01X258177Y129279D02*
X260534Y126922D01*
G01D02*
X262646D01*
G01X260974Y127982D02*
X262206D01*
G01X262646Y126922D02*
X273863Y138139D01*
G01X262206Y127982D02*
X272803Y138579D01*
G01X273863Y138139D02*
Y147464D01*
G01X272803Y138579D02*
Y147904D01*
G01X273863Y147464D02*
X297559Y171160D01*
G01X272803Y147904D02*
X313592Y188693D01*
G01X255393Y114269D02*
X278435Y137311D01*
G01X254333Y114709D02*
X277375Y137751D01*
G01X278435Y137311D02*
Y146618D01*
G01X277375Y137751D02*
Y147058D01*
G01X278435Y146618D02*
X323382Y191565D01*
G01X277375Y147058D02*
X317685Y187368D01*
G01X278435Y146618D02*
X323382Y191565D01*
G01X278435Y146618D02*
X323382Y191565D01*
G01X278435Y146618D02*
X323382Y191565D01*
G01X278435Y146618D02*
X323382Y191565D01*
G01X255393Y114269D02*
X278435Y137311D01*
G01X254333Y114709D02*
X277375Y137751D01*
G01X278435Y137311D02*
Y146618D01*
G01X277375Y137751D02*
Y147058D01*
G01X278435Y146618D02*
X323382Y191565D01*
G01X277375Y147058D02*
X317685Y187368D01*
G01X278435Y146618D02*
X323382Y191565D01*
G01X278435Y146618D02*
X323382Y191565D01*
G01X278435Y146618D02*
X323382Y191565D01*
G01X278435Y146618D02*
X323382Y191565D01*
G01X232081Y200857D02*
X233161Y201937D01*
G01X234505Y203281D02*
X235218Y203994D01*
G01X236563Y205339D02*
X237289Y206065D01*
G01X238633Y207409D02*
X239340Y208116D01*
G01X240684Y209460D02*
X241391Y210167D01*
G01X242735Y211511D02*
X243631Y212407D01*
G01X244976Y213752D02*
X245849Y214625D01*
G01X247193Y215969D02*
X247906Y216682D01*
G01X249251Y218027D02*
X250176Y218952D01*
G01X232081Y200857D02*
X233161Y201937D01*
G01X234505Y203281D02*
X235218Y203994D01*
G01X236563Y205339D02*
X237289Y206065D01*
G01X238633Y207409D02*
X239340Y208116D01*
G01X240684Y209460D02*
X241391Y210167D01*
G01X242735Y211511D02*
X243631Y212407D01*
G01X244976Y213752D02*
X245849Y214625D01*
G01X247193Y215969D02*
X247906Y216682D01*
G01X249251Y218027D02*
X250176Y218952D01*
G01X274218Y197703D02*
X273404Y196265D01*
G01X275141Y197181D02*
X274194Y195507D01*
G01X273404Y196265D02*
X270194Y194271D01*
G01X274194Y195507D02*
X270858Y193434D01*
G01X270194Y194271D02*
X261930Y186007D01*
G01X270858Y193434D02*
X268373Y190949D01*
G01X270194Y194271D02*
X261930Y186007D01*
G01X267028Y189604D02*
X265927Y188503D01*
G01X270194Y194271D02*
X261930Y186007D01*
G01X264581Y187158D02*
X262990Y185567D01*
G01X261930Y186007D02*
Y182230D01*
G01X262990Y185567D02*
Y181790D01*
G01D02*
X262213Y181013D01*
G01X261505Y179669D02*
X260869D01*
G01D02*
X259676Y178476D01*
G01X258968Y177131D02*
X258331D01*
G01D02*
X257624Y176424D01*
G01X256916Y175080D02*
X256280D01*
G01D02*
X255573Y174373D01*
G01X254865Y173029D02*
X254229D01*
G01D02*
X253522Y172322D01*
G01X252814Y170978D02*
X252178D01*
G01D02*
X251471Y170271D01*
G01X250763Y168927D02*
X250127D01*
G01D02*
X249420Y168220D01*
G01X248712Y166876D02*
X248076D01*
G01D02*
X247369Y166169D01*
G01X246661Y164825D02*
X246025D01*
G01D02*
X245113Y163913D01*
G01X244405Y162569D02*
X243769D01*
G01X274218Y197703D02*
X273404Y196265D01*
G01X275141Y197181D02*
X274194Y195507D01*
G01X273404Y196265D02*
X270194Y194271D01*
G01X274194Y195507D02*
X270858Y193434D01*
G01X270194Y194271D02*
X261930Y186007D01*
G01X270858Y193434D02*
X268373Y190949D01*
G01X270194Y194271D02*
X261930Y186007D01*
G01X267028Y189604D02*
X265927Y188503D01*
G01X270194Y194271D02*
X261930Y186007D01*
G01X264581Y187158D02*
X262990Y185567D01*
G01X261930Y186007D02*
Y182230D01*
G01X262990Y185567D02*
Y181790D01*
G01D02*
X262213Y181013D01*
G01X261505Y179669D02*
X260869D01*
G01D02*
X259676Y178476D01*
G01X258968Y177131D02*
X258331D01*
G01D02*
X257624Y176424D01*
G01X256916Y175080D02*
X256280D01*
G01D02*
X255573Y174373D01*
G01X254865Y173029D02*
X254229D01*
G01D02*
X253522Y172322D01*
G01X252814Y170978D02*
X252178D01*
G01D02*
X251471Y170271D01*
G01X250763Y168927D02*
X250127D01*
G01D02*
X249420Y168220D01*
G01X248712Y166876D02*
X248076D01*
G01D02*
X247369Y166169D01*
G01X246661Y164825D02*
X246025D01*
G01D02*
X245113Y163913D01*
G01X244405Y162569D02*
X243769D01*
G01X243077Y206253D02*
X243790Y206966D01*
G01X245135Y208311D02*
X245848Y209024D01*
G01X247192Y210368D02*
X248774Y211950D01*
G01X250119Y213295D02*
X251540Y214716D01*
G01X252885Y216061D02*
X256992Y220168D01*
G01X243077Y206253D02*
X243790Y206966D01*
G01X245135Y208311D02*
X245848Y209024D01*
G01X247192Y210368D02*
X248774Y211950D01*
G01X250119Y213295D02*
X251540Y214716D01*
G01X252885Y216061D02*
X256992Y220168D01*
G01X265464Y180279D02*
Y184165D01*
G01X266524Y179839D02*
Y183725D01*
G01X265464Y184165D02*
X272135Y190836D01*
G01X266524Y183725D02*
X267681Y184882D01*
G01X265464Y184165D02*
X272135Y190836D01*
G01X267681Y184882D02*
X268318D01*
G01X265464Y184165D02*
X272135Y190836D01*
G01X269026Y186227D02*
X270333Y187534D01*
G01X265464Y184165D02*
X272135Y190836D01*
G01X270333Y187534D02*
X270970D01*
G01X265464Y184165D02*
X272135Y190836D01*
G01X271678Y188879D02*
X272845Y190046D01*
G01X272135Y190836D02*
X278393Y195878D01*
G01X272845Y190046D02*
X279103Y195088D01*
G01X278393Y195878D02*
X280384Y197869D01*
G01X279103Y195088D02*
X281133Y197119D01*
G01X265464Y180279D02*
Y184165D01*
G01X266524Y179839D02*
Y183725D01*
G01X265464Y184165D02*
X272135Y190836D01*
G01X266524Y183725D02*
X267681Y184882D01*
G01X265464Y184165D02*
X272135Y190836D01*
G01X267681Y184882D02*
X268318D01*
G01X265464Y184165D02*
X272135Y190836D01*
G01X269026Y186227D02*
X270333Y187534D01*
G01X265464Y184165D02*
X272135Y190836D01*
G01X270333Y187534D02*
X270970D01*
G01X265464Y184165D02*
X272135Y190836D01*
G01X271678Y188879D02*
X272845Y190046D01*
G01X272135Y190836D02*
X278393Y195878D01*
G01X272845Y190046D02*
X279103Y195088D01*
G01X278393Y195878D02*
X280384Y197869D01*
G01X279103Y195088D02*
X281133Y197119D01*
G01X232081Y200857D02*
X233161Y201937D01*
G01X234505Y203281D02*
X235218Y203994D01*
G01X236563Y205339D02*
X237289Y206065D01*
G01X238633Y207409D02*
X239340Y208116D01*
G01X240684Y209460D02*
X241391Y210167D01*
G01X242735Y211511D02*
X243631Y212407D01*
G01X244976Y213752D02*
X245849Y214625D01*
G01X247193Y215969D02*
X247906Y216682D01*
G01X249251Y218027D02*
X250176Y218952D01*
G01X232081Y200857D02*
X233161Y201937D01*
G01X234505Y203281D02*
X235218Y203994D01*
G01X236563Y205339D02*
X237289Y206065D01*
G01X238633Y207409D02*
X239340Y208116D01*
G01X240684Y209460D02*
X241391Y210167D01*
G01X242735Y211511D02*
X243631Y212407D01*
G01X244976Y213752D02*
X245849Y214625D01*
G01X247193Y215969D02*
X247906Y216682D01*
G01X249251Y218027D02*
X250176Y218952D01*
G01X275141Y197181D02*
X274194Y195507D01*
G01X274218Y197703D02*
X273404Y196265D01*
G01X274194Y195507D02*
X270858Y193434D01*
G01X273404Y196265D02*
X270194Y194271D01*
G01X270858Y193434D02*
X268373Y190949D01*
G01X267028Y189604D02*
X265927Y188503D01*
G01X264581Y187158D02*
X262990Y185567D01*
G01X270194Y194271D02*
X261930Y186007D01*
G01X262990Y185567D02*
Y181790D01*
G01X261930Y186007D02*
Y182230D01*
G01X262990Y181790D02*
X262213Y181013D01*
G01X261505Y179669D02*
X260869D01*
G01D02*
X259676Y178476D01*
G01X258968Y177131D02*
X258331D01*
G01D02*
X257624Y176424D01*
G01X256916Y175080D02*
X256280D01*
G01D02*
X255573Y174373D01*
G01X254865Y173029D02*
X254229D01*
G01D02*
X253522Y172322D01*
G01X252814Y170978D02*
X252178D01*
G01D02*
X251471Y170271D01*
G01X250763Y168927D02*
X250127D01*
G01D02*
X249420Y168220D01*
G01X248712Y166876D02*
X248076D01*
G01D02*
X247369Y166169D01*
G01X246661Y164825D02*
X246025D01*
G01D02*
X245113Y163913D01*
G01X244405Y162569D02*
X243769D01*
G01X275141Y197181D02*
X274194Y195507D01*
G01X274218Y197703D02*
X273404Y196265D01*
G01X274194Y195507D02*
X270858Y193434D01*
G01X273404Y196265D02*
X270194Y194271D01*
G01X270858Y193434D02*
X268373Y190949D01*
G01X267028Y189604D02*
X265927Y188503D01*
G01X264581Y187158D02*
X262990Y185567D01*
G01X270194Y194271D02*
X261930Y186007D01*
G01X262990Y185567D02*
Y181790D01*
G01X261930Y186007D02*
Y182230D01*
G01X262990Y181790D02*
X262213Y181013D01*
G01X261505Y179669D02*
X260869D01*
G01D02*
X259676Y178476D01*
G01X258968Y177131D02*
X258331D01*
G01D02*
X257624Y176424D01*
G01X256916Y175080D02*
X256280D01*
G01D02*
X255573Y174373D01*
G01X254865Y173029D02*
X254229D01*
G01D02*
X253522Y172322D01*
G01X252814Y170978D02*
X252178D01*
G01D02*
X251471Y170271D01*
G01X250763Y168927D02*
X250127D01*
G01D02*
X249420Y168220D01*
G01X248712Y166876D02*
X248076D01*
G01D02*
X247369Y166169D01*
G01X246661Y164825D02*
X246025D01*
G01D02*
X245113Y163913D01*
G01X244405Y162569D02*
X243769D01*
G01X243077Y206253D02*
X243790Y206966D01*
G01X245135Y208311D02*
X245848Y209024D01*
G01X247192Y210368D02*
X248774Y211950D01*
G01X250119Y213295D02*
X251540Y214716D01*
G01X252885Y216061D02*
X256992Y220168D01*
G01X243077Y206253D02*
X243790Y206966D01*
G01X245135Y208311D02*
X245848Y209024D01*
G01X247192Y210368D02*
X248774Y211950D01*
G01X250119Y213295D02*
X251540Y214716D01*
G01X252885Y216061D02*
X256992Y220168D01*
G01X266524Y179839D02*
Y183725D01*
G01X265464Y180279D02*
Y184165D01*
G01X266524Y183725D02*
X267681Y184882D01*
G01D02*
X268318D01*
G01X269026Y186227D02*
X270333Y187534D01*
G01D02*
X270970D01*
G01X271678Y188879D02*
X272845Y190046D01*
G01X265464Y184165D02*
X272135Y190836D01*
G01X272845Y190046D02*
X279103Y195088D01*
G01X272135Y190836D02*
X278393Y195878D01*
G01X279103Y195088D02*
X281133Y197119D01*
G01X278393Y195878D02*
X280384Y197869D01*
G01X266524Y179839D02*
Y183725D01*
G01X265464Y180279D02*
Y184165D01*
G01X266524Y183725D02*
X267681Y184882D01*
G01D02*
X268318D01*
G01X269026Y186227D02*
X270333Y187534D01*
G01D02*
X270970D01*
G01X271678Y188879D02*
X272845Y190046D01*
G01X265464Y184165D02*
X272135Y190836D01*
G01X272845Y190046D02*
X279103Y195088D01*
G01X272135Y190836D02*
X278393Y195878D01*
G01X279103Y195088D02*
X281133Y197119D01*
G01X278393Y195878D02*
X280384Y197869D01*
G01X234037Y243117D02*
X234979Y244059D01*
G01X236323Y245403D02*
X237516Y246596D01*
G01X238861Y247941D02*
X240349Y249429D01*
G01X241693Y250773D02*
X242400Y251480D01*
G01X241960Y252540D02*
X261014D01*
G01X242400Y251480D02*
X245113D01*
G01X241960Y252540D02*
X261014D01*
G01X247013Y251480D02*
X248177D01*
G01X241960Y252540D02*
X261014D01*
G01X250077Y251480D02*
X251240D01*
G01X241960Y252540D02*
X261014D01*
G01X253140Y251480D02*
X255401D01*
G01X241960Y252540D02*
X261014D01*
G01X257301Y251480D02*
X261014D01*
G01X234037Y243117D02*
X234979Y244059D01*
G01X236323Y245403D02*
X237516Y246596D01*
G01X238861Y247941D02*
X240349Y249429D01*
G01X241693Y250773D02*
X242400Y251480D01*
G01X241960Y252540D02*
X261014D01*
G01X242400Y251480D02*
X245113D01*
G01X241960Y252540D02*
X261014D01*
G01X247013Y251480D02*
X248177D01*
G01X241960Y252540D02*
X261014D01*
G01X250077Y251480D02*
X251240D01*
G01X241960Y252540D02*
X261014D01*
G01X253140Y251480D02*
X255401D01*
G01X241960Y252540D02*
X261014D01*
G01X257301Y251480D02*
X261014D01*
G01X233465Y247987D02*
X234178Y248700D01*
G01X235523Y250045D02*
X236533Y251055D01*
G01X237878Y252400D02*
X238807Y253329D01*
G01X240151Y254673D02*
X240858Y255380D01*
G01X240418Y256440D02*
X258792D01*
G01X240858Y255380D02*
X242964D01*
G01X240418Y256440D02*
X258792D01*
G01X244864Y255380D02*
X246073D01*
G01X240418Y256440D02*
X258792D01*
G01X247973Y255380D02*
X249300D01*
G01X240418Y256440D02*
X258792D01*
G01X251200Y255380D02*
X252200D01*
G01X240418Y256440D02*
X258792D01*
G01X254100Y255380D02*
X255892D01*
G01X240418Y256440D02*
X258792D01*
G01X257792Y255380D02*
X258792D01*
G01X233465Y247987D02*
X234178Y248700D01*
G01X235523Y250045D02*
X236533Y251055D01*
G01X237878Y252400D02*
X238807Y253329D01*
G01X240151Y254673D02*
X240858Y255380D01*
G01X240418Y256440D02*
X258792D01*
G01X240858Y255380D02*
X242964D01*
G01X240418Y256440D02*
X258792D01*
G01X244864Y255380D02*
X246073D01*
G01X240418Y256440D02*
X258792D01*
G01X247973Y255380D02*
X249300D01*
G01X240418Y256440D02*
X258792D01*
G01X251200Y255380D02*
X252200D01*
G01X240418Y256440D02*
X258792D01*
G01X254100Y255380D02*
X255892D01*
G01X240418Y256440D02*
X258792D01*
G01X257792Y255380D02*
X258792D01*
G01X234037Y243117D02*
X234979Y244059D01*
G01X236323Y245403D02*
X237516Y246596D01*
G01X238861Y247941D02*
X240349Y249429D01*
G01X241693Y250773D02*
X242400Y251480D01*
G01D02*
X245113D01*
G01X247013D02*
X248177D01*
G01X250077D02*
X251240D01*
G01X253140D02*
X255401D01*
G01X257301D02*
X261014D01*
G01X241960Y252540D02*
X261014D01*
G01X234037Y243117D02*
X234979Y244059D01*
G01X236323Y245403D02*
X237516Y246596D01*
G01X238861Y247941D02*
X240349Y249429D01*
G01X241693Y250773D02*
X242400Y251480D01*
G01D02*
X245113D01*
G01X247013D02*
X248177D01*
G01X250077D02*
X251240D01*
G01X253140D02*
X255401D01*
G01X257301D02*
X261014D01*
G01X241960Y252540D02*
X261014D01*
G01X233465Y247987D02*
X234178Y248700D01*
G01X235523Y250045D02*
X236533Y251055D01*
G01X237878Y252400D02*
X238807Y253329D01*
G01X240151Y254673D02*
X240858Y255380D01*
G01D02*
X242964D01*
G01X244864D02*
X246073D01*
G01X247973D02*
X249300D01*
G01X251200D02*
X252200D01*
G01X254100D02*
X255892D01*
G01X257792D02*
X258792D01*
G01X240418Y256440D02*
X258792D01*
G01X233465Y247987D02*
X234178Y248700D01*
G01X235523Y250045D02*
X236533Y251055D01*
G01X237878Y252400D02*
X238807Y253329D01*
G01X240151Y254673D02*
X240858Y255380D01*
G01D02*
X242964D01*
G01X244864D02*
X246073D01*
G01X247973D02*
X249300D01*
G01X251200D02*
X252200D01*
G01X254100D02*
X255892D01*
G01X257792D02*
X258792D01*
G01X240418Y256440D02*
X258792D01*
G01X251520Y220296D02*
X252227Y221003D01*
G01X253572Y222348D02*
X255404Y224180D01*
G01X254964Y225240D02*
X257892D01*
G01X255404Y224180D02*
X257892D01*
G01X251520Y220296D02*
X252227Y221003D01*
G01X253572Y222348D02*
X255404Y224180D01*
G01X254964Y225240D02*
X257892D01*
G01X255404Y224180D02*
X257892D01*
G01X256552Y221228D02*
X257710D01*
G01X256992Y220168D02*
X257710D01*
G01X256552Y221228D02*
X257710D01*
G01X256992Y220168D02*
X257710D01*
G01X251520Y220296D02*
X252227Y221003D01*
G01X253572Y222348D02*
X255404Y224180D01*
G01D02*
X257892D01*
G01X254964Y225240D02*
X257892D01*
G01X251520Y220296D02*
X252227Y221003D01*
G01X253572Y222348D02*
X255404Y224180D01*
G01D02*
X257892D01*
G01X254964Y225240D02*
X257892D01*
G01X256992Y220168D02*
X257710D01*
G01X256552Y221228D02*
X257710D01*
G01X256992Y220168D02*
X257710D01*
G01X256552Y221228D02*
X257710D01*
G01X249718Y352736D02*
X247356D01*
G01X249718Y351676D02*
X246916D01*
G01X246383Y347779D02*
X258105D01*
G01X246823Y348839D02*
X258105D01*
G01X249718Y351676D02*
X246916D01*
G01X249718Y352736D02*
X247356D01*
G01X246823Y348839D02*
X258105D01*
G01X246383Y347779D02*
X258105D01*
G01X249718Y352736D02*
X247356D01*
G01X249718Y351676D02*
X246916D01*
G01X246383Y347779D02*
X258105D01*
G01X246823Y348839D02*
X258105D01*
G01X249718Y351676D02*
X246916D01*
G01X249718Y352736D02*
X247356D01*
G01X246823Y348839D02*
X258105D01*
G01X246383Y347779D02*
X258105D01*
G01X254072Y378415D02*
X248977D01*
G01X254072Y379475D02*
X249417D01*
G01X248977Y378415D02*
X241732Y385660D01*
G01X249417Y379475D02*
X242792Y386100D01*
G01X241732Y385660D02*
Y398431D01*
G01X242792Y386100D02*
Y398871D01*
G01X246792Y400271D02*
Y386800D01*
G01X245732Y399831D02*
Y386360D01*
G01X246792Y386800D02*
X249860Y383732D01*
G01X245732Y386360D02*
X249420Y382672D01*
G01X249860Y383732D02*
X251977D01*
G01D02*
X252597Y383720D01*
G01X249420Y382672D02*
X251966D01*
G01X249860Y383732D02*
X251977D01*
G01D02*
X252597Y383720D01*
G01X251966Y382672D02*
X252577Y382660D01*
G01X254072Y379475D02*
X249417D01*
G01X254072Y378415D02*
X248977D01*
G01X249417Y379475D02*
X242792Y386100D01*
G01X248977Y378415D02*
X241732Y385660D01*
G01X242792Y386100D02*
Y398871D01*
G01X241732Y385660D02*
Y398431D01*
G01X245732Y399831D02*
Y386360D01*
G01X246792Y400271D02*
Y386800D01*
G01X245732Y386360D02*
X249420Y382672D01*
G01X246792Y386800D02*
X249860Y383732D01*
G01X249420Y382672D02*
X251966D01*
G01D02*
X252577Y382660D01*
G01X249860Y383732D02*
X251977D01*
G01X249420Y382672D02*
X251966D01*
G01D02*
X252577Y382660D01*
G01X251977Y383732D02*
X252597Y383720D01*
G01X254072Y378415D02*
X248977D01*
G01X254072Y379475D02*
X249417D01*
G01X248977Y378415D02*
X241732Y385660D01*
G01X249417Y379475D02*
X242792Y386100D01*
G01X241732Y385660D02*
Y398431D01*
G01X242792Y386100D02*
Y398871D01*
G01X246792Y400271D02*
Y386800D01*
G01X245732Y399831D02*
Y386360D01*
G01X246792Y386800D02*
X249860Y383732D01*
G01X245732Y386360D02*
X249420Y382672D01*
G01X249860Y383732D02*
X251977D01*
G01D02*
X252597Y383720D01*
G01X249420Y382672D02*
X251966D01*
G01X249860Y383732D02*
X251977D01*
G01D02*
X252597Y383720D01*
G01X251966Y382672D02*
X252577Y382660D01*
G01X254072Y379475D02*
X249417D01*
G01X254072Y378415D02*
X248977D01*
G01X249417Y379475D02*
X242792Y386100D01*
G01X248977Y378415D02*
X241732Y385660D01*
G01X242792Y386100D02*
Y398871D01*
G01X241732Y385660D02*
Y398431D01*
G01X245732Y399831D02*
Y386360D01*
G01X246792Y400271D02*
Y386800D01*
G01X245732Y386360D02*
X249420Y382672D01*
G01X246792Y386800D02*
X249860Y383732D01*
G01X249420Y382672D02*
X251966D01*
G01D02*
X252577Y382660D01*
G01X249860Y383732D02*
X251977D01*
G01X249420Y382672D02*
X251966D01*
G01D02*
X252577Y382660D01*
G01X251977Y383732D02*
X252597Y383720D01*
G01X272866Y408786D02*
X267892Y413760D01*
G01X273616Y409536D02*
X268952Y414200D01*
G01X267892Y413760D02*
Y422632D01*
G01X268952Y414200D02*
Y423072D01*
G01X273616Y409536D02*
X268952Y414200D01*
G01X272866Y408786D02*
X267892Y413760D01*
G01X268952Y414200D02*
Y423072D01*
G01X267892Y413760D02*
Y422632D01*
G01X275503Y413237D02*
X272892Y415847D01*
G01X274753Y412486D02*
X271832Y415407D01*
G01X272892Y415847D02*
Y426172D01*
G01X271832Y415407D02*
Y425732D01*
G01X272892Y426172D02*
X270480Y428584D01*
G01X271832Y425732D02*
X270040Y427524D01*
G01X270480Y428584D02*
X269840D01*
G01X270040Y427524D02*
X269400D01*
G01X269840Y428584D02*
X267737Y430687D01*
G01X269400Y427524D02*
X266677Y430247D01*
G01X267737Y430687D02*
Y432987D01*
G01X266677Y430247D02*
Y432544D01*
G01X267737Y432987D02*
X265773Y434951D01*
G01X266677Y432544D02*
X265330Y433891D01*
G01X265773Y434951D02*
X262713D01*
G01X265330Y433891D02*
X262270D01*
G01X262713Y434951D02*
X261370Y436294D01*
G01X262270Y433891D02*
X260310Y435851D01*
G01X261370Y436294D02*
Y439354D01*
G01X260310Y435851D02*
Y438911D01*
G01X261370Y439354D02*
X259406Y441318D01*
G01X260310Y438911D02*
X258963Y440258D01*
G01X259406Y441318D02*
X256346D01*
G01X258963Y440258D02*
X255903D01*
G01X256346Y441318D02*
X255003Y442661D01*
G01X255903Y440258D02*
X253943Y442218D01*
G01X255003Y442661D02*
Y445721D01*
G01X253943Y442218D02*
Y445278D01*
G01X255003Y445721D02*
X253039Y447685D01*
G01X253943Y445278D02*
X252596Y446625D01*
G01X253039Y447685D02*
X249979D01*
G01X252596Y446625D02*
X249536D01*
G01X249979Y447685D02*
X248636Y449028D01*
G01X249536Y446625D02*
X247576Y448585D01*
G01X248636Y449028D02*
Y452088D01*
G01X247576Y448585D02*
Y451645D01*
G01X248636Y452088D02*
X246672Y454052D01*
G01X247576Y451645D02*
X246229Y452992D01*
G01X246672Y454052D02*
X243612D01*
G01X246229Y452992D02*
X243169D01*
G01X243612Y454052D02*
X242269Y455395D01*
G01X243169Y452992D02*
X241209Y454952D01*
G01X242269Y455395D02*
Y458455D01*
G01X241209Y454952D02*
Y458012D01*
G01X242269Y458455D02*
X240305Y460419D01*
G01X241209Y458012D02*
X239862Y459359D01*
G01X240305Y460419D02*
X237245D01*
G01X239862Y459359D02*
X236802D01*
G01X237245Y460419D02*
X235902Y461762D01*
G01X236802Y459359D02*
X234842Y461319D01*
G01X235902Y461762D02*
Y464822D01*
G01X234842Y461319D02*
Y464379D01*
G01X235902Y464822D02*
X233938Y466786D01*
G01X234842Y464379D02*
X233495Y465726D01*
G01X274753Y412486D02*
X271832Y415407D01*
G01X275503Y413237D02*
X272892Y415847D01*
G01X271832Y415407D02*
Y425732D01*
G01X272892Y415847D02*
Y426172D01*
G01X271832Y425732D02*
X270040Y427524D01*
G01X272892Y426172D02*
X270480Y428584D01*
G01X270040Y427524D02*
X269400D01*
G01X270480Y428584D02*
X269840D01*
G01X269400Y427524D02*
X266677Y430247D01*
G01X269840Y428584D02*
X267737Y430687D01*
G01X266677Y430247D02*
Y432544D01*
G01X267737Y430687D02*
Y432987D01*
G01X266677Y432544D02*
X265330Y433891D01*
G01X267737Y432987D02*
X265773Y434951D01*
G01X265330Y433891D02*
X262270D01*
G01X265773Y434951D02*
X262713D01*
G01X262270Y433891D02*
X260310Y435851D01*
G01X262713Y434951D02*
X261370Y436294D01*
G01X260310Y435851D02*
Y438911D01*
G01X261370Y436294D02*
Y439354D01*
G01X260310Y438911D02*
X258963Y440258D01*
G01X261370Y439354D02*
X259406Y441318D01*
G01X258963Y440258D02*
X255903D01*
G01X259406Y441318D02*
X256346D01*
G01X255903Y440258D02*
X253943Y442218D01*
G01X256346Y441318D02*
X255003Y442661D01*
G01X253943Y442218D02*
Y445278D01*
G01X255003Y442661D02*
Y445721D01*
G01X253943Y445278D02*
X252596Y446625D01*
G01X255003Y445721D02*
X253039Y447685D01*
G01X252596Y446625D02*
X249536D01*
G01X253039Y447685D02*
X249979D01*
G01X249536Y446625D02*
X247576Y448585D01*
G01X249979Y447685D02*
X248636Y449028D01*
G01X247576Y448585D02*
Y451645D01*
G01X248636Y449028D02*
Y452088D01*
G01X247576Y451645D02*
X246229Y452992D01*
G01X248636Y452088D02*
X246672Y454052D01*
G01X246229Y452992D02*
X243169D01*
G01X246672Y454052D02*
X243612D01*
G01X243169Y452992D02*
X241209Y454952D01*
G01X243612Y454052D02*
X242269Y455395D01*
G01X241209Y454952D02*
Y458012D01*
G01X242269Y455395D02*
Y458455D01*
G01X241209Y458012D02*
X239862Y459359D01*
G01X242269Y458455D02*
X240305Y460419D01*
G01X239862Y459359D02*
X236802D01*
G01X240305Y460419D02*
X237245D01*
G01X236802Y459359D02*
X234842Y461319D01*
G01X237245Y460419D02*
X235902Y461762D01*
G01X234842Y461319D02*
Y464379D01*
G01X235902Y461762D02*
Y464822D01*
G01X234842Y464379D02*
X233495Y465726D01*
G01X235902Y464822D02*
X233938Y466786D01*
G01X272866Y408786D02*
X267892Y413760D01*
G01X273616Y409536D02*
X268952Y414200D01*
G01X267892Y413760D02*
Y422632D01*
G01X268952Y414200D02*
Y423072D01*
G01X275503Y413237D02*
X272892Y415847D01*
G01X274753Y412486D02*
X271832Y415407D01*
G01X272892Y415847D02*
Y426172D01*
G01X271832Y415407D02*
Y425732D01*
G01X272892Y426172D02*
X270480Y428584D01*
G01X271832Y425732D02*
X270040Y427524D01*
G01X270480Y428584D02*
X269840D01*
G01X270040Y427524D02*
X269400D01*
G01X269840Y428584D02*
X267737Y430687D01*
G01X269400Y427524D02*
X266677Y430247D01*
G01X267737Y430687D02*
Y432987D01*
G01X266677Y430247D02*
Y432544D01*
G01X267737Y432987D02*
X265773Y434951D01*
G01X266677Y432544D02*
X265330Y433891D01*
G01X265773Y434951D02*
X262713D01*
G01X265330Y433891D02*
X262270D01*
G01X262713Y434951D02*
X261370Y436294D01*
G01X262270Y433891D02*
X260310Y435851D01*
G01X261370Y436294D02*
Y439354D01*
G01X260310Y435851D02*
Y438911D01*
G01X261370Y439354D02*
X259406Y441318D01*
G01X260310Y438911D02*
X258963Y440258D01*
G01X259406Y441318D02*
X256346D01*
G01X258963Y440258D02*
X255903D01*
G01X256346Y441318D02*
X255003Y442661D01*
G01X255903Y440258D02*
X253943Y442218D01*
G01X255003Y442661D02*
Y445721D01*
G01X253943Y442218D02*
Y445278D01*
G01X255003Y445721D02*
X253039Y447685D01*
G01X253943Y445278D02*
X252596Y446625D01*
G01X253039Y447685D02*
X249979D01*
G01X252596Y446625D02*
X249536D01*
G01X249979Y447685D02*
X248636Y449028D01*
G01X249536Y446625D02*
X247576Y448585D01*
G01X248636Y449028D02*
Y452088D01*
G01X247576Y448585D02*
Y451645D01*
G01X248636Y452088D02*
X246672Y454052D01*
G01X247576Y451645D02*
X246229Y452992D01*
G01X246672Y454052D02*
X243612D01*
G01X246229Y452992D02*
X243169D01*
G01X243612Y454052D02*
X242269Y455395D01*
G01X243169Y452992D02*
X241209Y454952D01*
G01X242269Y455395D02*
Y458455D01*
G01X241209Y454952D02*
Y458012D01*
G01X242269Y458455D02*
X240305Y460419D01*
G01X241209Y458012D02*
X239862Y459359D01*
G01X240305Y460419D02*
X237245D01*
G01X239862Y459359D02*
X236802D01*
G01X237245Y460419D02*
X235902Y461762D01*
G01X236802Y459359D02*
X234842Y461319D01*
G01X235902Y461762D02*
Y464822D01*
G01X234842Y461319D02*
Y464379D01*
G01X235902Y464822D02*
X233938Y466786D01*
G01X234842Y464379D02*
X233495Y465726D01*
G01X273616Y409536D02*
X268952Y414200D01*
G01X272866Y408786D02*
X267892Y413760D01*
G01X268952Y414200D02*
Y423072D01*
G01X267892Y413760D02*
Y422632D01*
G01X274753Y412486D02*
X271832Y415407D01*
G01X275503Y413237D02*
X272892Y415847D01*
G01X271832Y415407D02*
Y425732D01*
G01X272892Y415847D02*
Y426172D01*
G01X271832Y425732D02*
X270040Y427524D01*
G01X272892Y426172D02*
X270480Y428584D01*
G01X270040Y427524D02*
X269400D01*
G01X270480Y428584D02*
X269840D01*
G01X269400Y427524D02*
X266677Y430247D01*
G01X269840Y428584D02*
X267737Y430687D01*
G01X266677Y430247D02*
Y432544D01*
G01X267737Y430687D02*
Y432987D01*
G01X266677Y432544D02*
X265330Y433891D01*
G01X267737Y432987D02*
X265773Y434951D01*
G01X265330Y433891D02*
X262270D01*
G01X265773Y434951D02*
X262713D01*
G01X262270Y433891D02*
X260310Y435851D01*
G01X262713Y434951D02*
X261370Y436294D01*
G01X260310Y435851D02*
Y438911D01*
G01X261370Y436294D02*
Y439354D01*
G01X260310Y438911D02*
X258963Y440258D01*
G01X261370Y439354D02*
X259406Y441318D01*
G01X258963Y440258D02*
X255903D01*
G01X259406Y441318D02*
X256346D01*
G01X255903Y440258D02*
X253943Y442218D01*
G01X256346Y441318D02*
X255003Y442661D01*
G01X253943Y442218D02*
Y445278D01*
G01X255003Y442661D02*
Y445721D01*
G01X253943Y445278D02*
X252596Y446625D01*
G01X255003Y445721D02*
X253039Y447685D01*
G01X252596Y446625D02*
X249536D01*
G01X253039Y447685D02*
X249979D01*
G01X249536Y446625D02*
X247576Y448585D01*
G01X249979Y447685D02*
X248636Y449028D01*
G01X247576Y448585D02*
Y451645D01*
G01X248636Y449028D02*
Y452088D01*
G01X247576Y451645D02*
X246229Y452992D01*
G01X248636Y452088D02*
X246672Y454052D01*
G01X246229Y452992D02*
X243169D01*
G01X246672Y454052D02*
X243612D01*
G01X243169Y452992D02*
X241209Y454952D01*
G01X243612Y454052D02*
X242269Y455395D01*
G01X241209Y454952D02*
Y458012D01*
G01X242269Y455395D02*
Y458455D01*
G01X241209Y458012D02*
X239862Y459359D01*
G01X242269Y458455D02*
X240305Y460419D01*
G01X239862Y459359D02*
X236802D01*
G01X240305Y460419D02*
X237245D01*
G01X236802Y459359D02*
X234842Y461319D01*
G01X237245Y460419D02*
X235902Y461762D01*
G01X234842Y461319D02*
Y464379D01*
G01X235902Y461762D02*
Y464822D01*
G01X234842Y464379D02*
X233495Y465726D01*
G01X235902Y464822D02*
X233938Y466786D01*
G01X300412Y449609D02*
X276501Y473520D01*
G01X301472Y450052D02*
X276944Y474580D01*
G01X293748Y464443D02*
X292520D01*
G01X294191Y463383D02*
X292077D01*
G01X292520Y464443D02*
X291317Y465646D01*
G01X292077Y463383D02*
X290257Y465203D01*
G01X301472Y450052D02*
X276944Y474580D01*
G01X300412Y449609D02*
X276501Y473520D01*
G01X294191Y463383D02*
X292077D01*
G01X293748Y464443D02*
X292520D01*
G01X292077Y463383D02*
X290257Y465203D01*
G01X292520Y464443D02*
X291317Y465646D01*
G01X300412Y449609D02*
X276501Y473520D01*
G01X301472Y450052D02*
X276944Y474580D01*
G01X293748Y464443D02*
X292520D01*
G01X294191Y463383D02*
X292077D01*
G01X292520Y464443D02*
X291317Y465646D01*
G01X292077Y463383D02*
X290257Y465203D01*
G01X301472Y450052D02*
X276944Y474580D01*
G01X300412Y449609D02*
X276501Y473520D01*
G01X294191Y463383D02*
X292077D01*
G01X293748Y464443D02*
X292520D01*
G01X292077Y463383D02*
X290257Y465203D01*
G01X292520Y464443D02*
X291317Y465646D01*
G01X276501Y473520D02*
X263501D01*
G01X276944Y474580D02*
X263941D01*
G01X263501Y473520D02*
X251255Y485766D01*
G01X263941Y474580D02*
X252154Y486367D01*
G01X251255Y485766D02*
X249233Y490649D01*
G01X252154Y486367D02*
X250293Y490860D01*
G01X249233Y490649D02*
Y577044D01*
G01X250293Y490860D02*
Y587849D01*
G01X291317Y465646D02*
Y466874D01*
G01X290257Y465203D02*
Y467317D01*
G01X291317Y466874D02*
X291877Y467434D01*
G01X290257Y467317D02*
X290817Y467877D01*
G01X291877Y467434D02*
Y469546D01*
G01X290817Y467877D02*
Y469106D01*
G01X291877Y469546D02*
X290053Y471370D01*
G01X290817Y469106D02*
X289613Y470310D01*
G01X290053Y471370D02*
X287611D01*
G01X289613Y470310D02*
X287171D01*
G01X287611Y471370D02*
X284950Y474031D01*
G01X287171Y470310D02*
X283890Y473591D01*
G01X284950Y474031D02*
Y475914D01*
G01X283890Y473591D02*
Y475474D01*
G01X284950Y475914D02*
X282484Y478380D01*
G01X283890Y475474D02*
X282044Y477320D01*
G01X282484Y478380D02*
X265741D01*
G01X282044Y477320D02*
X265301D01*
G01X265741Y478380D02*
X255393Y488728D01*
G01X265301Y477320D02*
X254333Y488288D01*
G01X255393Y488728D02*
Y588035D01*
G01X254333Y488288D02*
Y507212D01*
G01X255393Y488728D02*
Y588035D01*
G01X254333Y509034D02*
Y519493D01*
G01X255393Y488728D02*
Y588035D01*
G01X254333Y521481D02*
Y522509D01*
G01X255393Y488728D02*
Y588035D01*
G01X254333Y524749D02*
Y525749D01*
G01X255393Y488728D02*
Y588035D01*
G01Y488728D02*
Y588035D01*
G01Y488728D02*
Y588035D01*
G01Y488728D02*
Y588035D01*
G01Y488728D02*
Y588035D01*
G01Y488728D02*
Y588035D01*
G01Y488728D02*
Y588035D01*
G01Y488728D02*
Y588035D01*
G01Y488728D02*
Y588035D01*
G01Y488728D02*
Y588035D01*
G01X276944Y474580D02*
X263941D01*
G01X276501Y473520D02*
X263501D01*
G01X263941Y474580D02*
X252154Y486367D01*
G01X263501Y473520D02*
X251255Y485766D01*
G01X252154Y486367D02*
X250293Y490860D01*
G01X251255Y485766D02*
X249233Y490649D01*
G01X250293Y490860D02*
Y587849D01*
G01X249233Y490649D02*
Y577044D01*
G01X250293Y490860D02*
Y587849D01*
G01Y490860D02*
Y587849D01*
G01Y490860D02*
Y587849D01*
G01X290257Y465203D02*
Y467317D01*
G01X291317Y465646D02*
Y466874D01*
G01X290257Y467317D02*
X290817Y467877D01*
G01X291317Y466874D02*
X291877Y467434D01*
G01X290817Y467877D02*
Y469106D01*
G01X291877Y467434D02*
Y469546D01*
G01X290817Y469106D02*
X289613Y470310D01*
G01X291877Y469546D02*
X290053Y471370D01*
G01X289613Y470310D02*
X287171D01*
G01X290053Y471370D02*
X287611D01*
G01X287171Y470310D02*
X283890Y473591D01*
G01X287611Y471370D02*
X284950Y474031D01*
G01X283890Y473591D02*
Y475474D01*
G01X284950Y474031D02*
Y475914D01*
G01X283890Y475474D02*
X282044Y477320D01*
G01X284950Y475914D02*
X282484Y478380D01*
G01X282044Y477320D02*
X265301D01*
G01X282484Y478380D02*
X265741D01*
G01X265301Y477320D02*
X254333Y488288D01*
G01X265741Y478380D02*
X255393Y488728D01*
G01X254333Y488288D02*
Y507212D01*
G01Y509034D02*
Y519493D01*
G01Y521481D02*
Y522509D01*
G01Y524749D02*
Y525749D01*
G01X255393Y488728D02*
Y588035D01*
G01X282312Y502066D02*
X286044Y505798D01*
G01X285804Y504058D02*
X287104Y505358D01*
G01X286044Y505798D02*
Y548509D01*
G01X287104Y505358D02*
Y550049D01*
G01X290892Y497712D02*
Y502549D01*
G01X289832Y502140D02*
Y502989D01*
G01X290892Y502549D02*
X292204Y503861D01*
G01X289832Y502989D02*
X291144Y504301D01*
G01X292204Y503861D02*
Y520840D01*
G01X291144Y504301D02*
Y520400D01*
G01X292204Y520840D02*
X290192Y522852D01*
G01X291144Y520400D02*
X289132Y522412D01*
G01X290192Y522852D02*
Y525000D01*
G01X289132Y522412D02*
Y525440D01*
G01X290192Y525000D02*
X292204Y527012D01*
G01X289132Y525440D02*
X291144Y527452D01*
G01X285804Y504058D02*
X287104Y505358D01*
G01X282312Y502066D02*
X286044Y505798D01*
G01X287104Y505358D02*
Y550049D01*
G01X286044Y505798D02*
Y548509D01*
G01X289832Y502140D02*
Y502989D01*
G01X290892Y497712D02*
Y502549D01*
G01X289832Y502989D02*
X291144Y504301D01*
G01X290892Y502549D02*
X292204Y503861D01*
G01X291144Y504301D02*
Y520400D01*
G01X292204Y503861D02*
Y520840D01*
G01X291144Y520400D02*
X289132Y522412D01*
G01X292204Y520840D02*
X290192Y522852D01*
G01X289132Y522412D02*
Y525440D01*
G01X290192Y522852D02*
Y525000D01*
G01X289132Y525440D02*
X291144Y527452D01*
G01X290192Y525000D02*
X292204Y527012D01*
G01X276501Y473520D02*
X263501D01*
G01X276944Y474580D02*
X263941D01*
G01X263501Y473520D02*
X251255Y485766D01*
G01X263941Y474580D02*
X252154Y486367D01*
G01X251255Y485766D02*
X249233Y490649D01*
G01X252154Y486367D02*
X250293Y490860D01*
G01X249233Y490649D02*
Y577044D01*
G01X250293Y490860D02*
Y587849D01*
G01X291317Y465646D02*
Y466874D01*
G01X290257Y465203D02*
Y467317D01*
G01X291317Y466874D02*
X291877Y467434D01*
G01X290257Y467317D02*
X290817Y467877D01*
G01X291877Y467434D02*
Y469546D01*
G01X290817Y467877D02*
Y469106D01*
G01X291877Y469546D02*
X290053Y471370D01*
G01X290817Y469106D02*
X289613Y470310D01*
G01X290053Y471370D02*
X287611D01*
G01X289613Y470310D02*
X287171D01*
G01X287611Y471370D02*
X284950Y474031D01*
G01X287171Y470310D02*
X283890Y473591D01*
G01X284950Y474031D02*
Y475914D01*
G01X283890Y473591D02*
Y475474D01*
G01X284950Y475914D02*
X282484Y478380D01*
G01X283890Y475474D02*
X282044Y477320D01*
G01X282484Y478380D02*
X265741D01*
G01X282044Y477320D02*
X265301D01*
G01X265741Y478380D02*
X255393Y488728D01*
G01X265301Y477320D02*
X254333Y488288D01*
G01X255393Y488728D02*
Y588035D01*
G01X254333Y488288D02*
Y507212D01*
G01X255393Y488728D02*
Y588035D01*
G01X254333Y509034D02*
Y519493D01*
G01X255393Y488728D02*
Y588035D01*
G01X254333Y521481D02*
Y522509D01*
G01X255393Y488728D02*
Y588035D01*
G01X254333Y524749D02*
Y525749D01*
G01X255393Y488728D02*
Y588035D01*
G01Y488728D02*
Y588035D01*
G01Y488728D02*
Y588035D01*
G01Y488728D02*
Y588035D01*
G01Y488728D02*
Y588035D01*
G01Y488728D02*
Y588035D01*
G01Y488728D02*
Y588035D01*
G01Y488728D02*
Y588035D01*
G01Y488728D02*
Y588035D01*
G01Y488728D02*
Y588035D01*
G01X276944Y474580D02*
X263941D01*
G01X276501Y473520D02*
X263501D01*
G01X263941Y474580D02*
X252154Y486367D01*
G01X263501Y473520D02*
X251255Y485766D01*
G01X252154Y486367D02*
X250293Y490860D01*
G01X251255Y485766D02*
X249233Y490649D01*
G01X250293Y490860D02*
Y587849D01*
G01X249233Y490649D02*
Y577044D01*
G01X250293Y490860D02*
Y587849D01*
G01Y490860D02*
Y587849D01*
G01Y490860D02*
Y587849D01*
G01X290257Y465203D02*
Y467317D01*
G01X291317Y465646D02*
Y466874D01*
G01X290257Y467317D02*
X290817Y467877D01*
G01X291317Y466874D02*
X291877Y467434D01*
G01X290817Y467877D02*
Y469106D01*
G01X291877Y467434D02*
Y469546D01*
G01X290817Y469106D02*
X289613Y470310D01*
G01X291877Y469546D02*
X290053Y471370D01*
G01X289613Y470310D02*
X287171D01*
G01X290053Y471370D02*
X287611D01*
G01X287171Y470310D02*
X283890Y473591D01*
G01X287611Y471370D02*
X284950Y474031D01*
G01X283890Y473591D02*
Y475474D01*
G01X284950Y474031D02*
Y475914D01*
G01X283890Y475474D02*
X282044Y477320D01*
G01X284950Y475914D02*
X282484Y478380D01*
G01X282044Y477320D02*
X265301D01*
G01X282484Y478380D02*
X265741D01*
G01X265301Y477320D02*
X254333Y488288D01*
G01X265741Y478380D02*
X255393Y488728D01*
G01X254333Y488288D02*
Y507212D01*
G01Y509034D02*
Y519493D01*
G01Y521481D02*
Y522509D01*
G01Y524749D02*
Y525749D01*
G01X255393Y488728D02*
Y588035D01*
G01X249233Y579004D02*
Y580004D01*
G01Y581964D02*
Y582964D01*
G01Y584924D02*
Y587409D01*
G01D02*
X248342Y588300D01*
G01X250293Y587849D02*
X247242Y590900D01*
G01X254333Y527989D02*
Y538042D01*
G01Y540282D02*
Y541282D01*
G01Y543522D02*
Y544522D01*
G01Y546762D02*
Y556983D01*
G01Y559223D02*
Y560223D01*
G01Y562463D02*
Y563463D01*
G01Y565703D02*
Y576036D01*
G01Y578276D02*
Y579276D01*
G01Y581516D02*
Y582516D01*
G01Y584756D02*
Y587595D01*
G01X255393Y588035D02*
X252314Y591114D01*
G01X254333Y587595D02*
X253414Y588514D01*
G01X249233Y579004D02*
Y580004D01*
G01Y581964D02*
Y582964D01*
G01Y584924D02*
Y587409D01*
G01X250293Y587849D02*
X247242Y590900D01*
G01X249233Y587409D02*
X248342Y588300D01*
G01X254333Y527989D02*
Y538042D01*
G01Y540282D02*
Y541282D01*
G01Y543522D02*
Y544522D01*
G01Y546762D02*
Y556983D01*
G01Y559223D02*
Y560223D01*
G01Y562463D02*
Y563463D01*
G01Y565703D02*
Y576036D01*
G01Y578276D02*
Y579276D01*
G01Y581516D02*
Y582516D01*
G01Y584756D02*
Y587595D01*
G01D02*
X253414Y588514D01*
G01X255393Y588035D02*
X252314Y591114D01*
G01X292204Y527012D02*
Y540588D01*
G01X291144Y527452D02*
Y540148D01*
G01X292204Y540588D02*
X291252Y541540D01*
G01X291144Y540148D02*
X290192Y541100D01*
G01X291252Y541540D02*
Y544960D01*
G01X290192Y541100D02*
Y545400D01*
G01X291252Y544960D02*
X292204Y545912D01*
G01X290192Y545400D02*
X291144Y546352D01*
G01X292204Y545912D02*
Y550235D01*
G01X291144Y546352D02*
Y548695D01*
G01Y527452D02*
Y540148D01*
G01X292204Y527012D02*
Y540588D01*
G01X291144Y540148D02*
X290192Y541100D01*
G01X292204Y540588D02*
X291252Y541540D01*
G01X290192Y541100D02*
Y545400D01*
G01X291252Y541540D02*
Y544960D01*
G01X290192Y545400D02*
X291144Y546352D01*
G01X291252Y544960D02*
X292204Y545912D01*
G01X291144Y546352D02*
Y548695D01*
G01X292204Y545912D02*
Y550235D01*
G01X249233Y579004D02*
Y580004D01*
G01Y581964D02*
Y582964D01*
G01Y584924D02*
Y587409D01*
G01D02*
X248342Y588300D01*
G01X250293Y587849D02*
X247242Y590900D01*
G01X254333Y527989D02*
Y538042D01*
G01Y540282D02*
Y541282D01*
G01Y543522D02*
Y544522D01*
G01Y546762D02*
Y556983D01*
G01Y559223D02*
Y560223D01*
G01Y562463D02*
Y563463D01*
G01Y565703D02*
Y576036D01*
G01Y578276D02*
Y579276D01*
G01Y581516D02*
Y582516D01*
G01Y584756D02*
Y587595D01*
G01X255393Y588035D02*
X252314Y591114D01*
G01X254333Y587595D02*
X253414Y588514D01*
G01X249233Y579004D02*
Y580004D01*
G01Y581964D02*
Y582964D01*
G01Y584924D02*
Y587409D01*
G01X250293Y587849D02*
X247242Y590900D01*
G01X249233Y587409D02*
X248342Y588300D01*
G01X254333Y527989D02*
Y538042D01*
G01Y540282D02*
Y541282D01*
G01Y543522D02*
Y544522D01*
G01Y546762D02*
Y556983D01*
G01Y559223D02*
Y560223D01*
G01Y562463D02*
Y563463D01*
G01Y565703D02*
Y576036D01*
G01Y578276D02*
Y579276D01*
G01Y581516D02*
Y582516D01*
G01Y584756D02*
Y587595D01*
G01D02*
X253414Y588514D01*
G01X255393Y588035D02*
X252314Y591114D01*
G01X245225Y590000D02*
Y608011D01*
G01X246285Y595890D02*
Y597260D01*
G01X245225Y590000D02*
Y608011D01*
G01X246285Y600940D02*
Y602360D01*
G01X251509Y595500D02*
X250838Y596171D01*
G01X250608Y594900D02*
X249778Y595730D01*
G01X250838Y596171D02*
Y597448D01*
G01Y600938D02*
Y601829D01*
G01X249778Y595730D02*
Y602270D01*
G01X250838Y601829D02*
X251609Y602600D01*
G01X249778Y602270D02*
X250608Y603100D01*
G01X246285Y595890D02*
Y597260D01*
G01Y600940D02*
Y602360D01*
G01X245225Y590000D02*
Y608011D01*
G01X250608Y594900D02*
X249778Y595730D01*
G01X251509Y595500D02*
X250838Y596171D01*
G01X249778Y595730D02*
Y602270D01*
G01X250838Y596171D02*
Y597448D01*
G01X249778Y595730D02*
Y602270D01*
G01X250838Y600938D02*
Y601829D01*
G01X249778Y602270D02*
X250608Y603100D01*
G01X250838Y601829D02*
X251609Y602600D01*
G01X245225Y590000D02*
Y608011D01*
G01X246285Y595890D02*
Y597260D01*
G01X245225Y590000D02*
Y608011D01*
G01X246285Y600940D02*
Y602360D01*
G01X282036Y608011D02*
Y590288D01*
G01X283096Y602066D02*
Y600940D01*
G01X282036Y608011D02*
Y590288D01*
G01X283096Y597260D02*
Y595890D01*
G01X251509Y595500D02*
X250838Y596171D01*
G01X250608Y594900D02*
X249778Y595730D01*
G01X250838Y596171D02*
Y597448D01*
G01Y600938D02*
Y601829D01*
G01X249778Y595730D02*
Y602270D01*
G01X250838Y601829D02*
X251609Y602600D01*
G01X249778Y602270D02*
X250608Y603100D01*
G01X287649Y597448D02*
Y596171D01*
G01X286589Y601994D02*
Y595730D01*
G01X287649Y596171D02*
X288320Y595500D01*
G01X286589Y595730D02*
X287419Y594900D01*
G01X246285Y595890D02*
Y597260D01*
G01Y600940D02*
Y602360D01*
G01X245225Y590000D02*
Y608011D01*
G01X283096Y602066D02*
Y600940D01*
G01Y597260D02*
Y595890D01*
G01X282036Y608011D02*
Y590288D01*
G01X250608Y594900D02*
X249778Y595730D01*
G01X251509Y595500D02*
X250838Y596171D01*
G01X249778Y595730D02*
Y602270D01*
G01X250838Y596171D02*
Y597448D01*
G01X249778Y595730D02*
Y602270D01*
G01X250838Y600938D02*
Y601829D01*
G01X249778Y602270D02*
X250608Y603100D01*
G01X250838Y601829D02*
X251609Y602600D01*
G01X286589Y601994D02*
Y595730D01*
G01X287649Y597448D02*
Y596171D01*
G01X286589Y595730D02*
X287419Y594900D01*
G01X287649Y596171D02*
X288320Y595500D01*
G01X298903Y172504D02*
X299610Y173211D01*
G01X300954Y174555D02*
X301735Y175336D01*
G01X303080Y176681D02*
X304051Y177652D01*
G01X305395Y178996D02*
X306102Y179703D01*
G01X307447Y181048D02*
X308258Y181859D01*
G01X309602Y183203D02*
X310309Y183910D01*
G01X311653Y185254D02*
X312572Y186173D01*
G01X313917Y187518D02*
X314652Y188253D01*
G01X313592Y188693D02*
Y193888D01*
G01X314652Y188253D02*
Y190343D01*
G01X313592Y188693D02*
Y193888D01*
G01X314652Y192243D02*
Y193448D01*
G01X313592Y193888D02*
X318942Y199238D01*
G01X314652Y193448D02*
X319692Y198488D01*
G01X298903Y172504D02*
X299610Y173211D01*
G01X300954Y174555D02*
X301735Y175336D01*
G01X303080Y176681D02*
X304051Y177652D01*
G01X305395Y178996D02*
X306102Y179703D01*
G01X307447Y181048D02*
X308258Y181859D01*
G01X309602Y183203D02*
X310309Y183910D01*
G01X311653Y185254D02*
X312572Y186173D01*
G01X313917Y187518D02*
X314652Y188253D01*
G01X313592Y188693D02*
Y193888D01*
G01X314652Y188253D02*
Y190343D01*
G01X313592Y188693D02*
Y193888D01*
G01X314652Y192243D02*
Y193448D01*
G01X313592Y193888D02*
X318942Y199238D01*
G01X314652Y193448D02*
X319692Y198488D01*
G01X318393Y188713D02*
X319030D01*
G01D02*
X320132Y189815D01*
G01X320840Y191159D02*
X321476D01*
G01D02*
X322322Y192005D01*
G01D02*
Y194243D01*
G01X323382Y191565D02*
Y193803D01*
G01X322322Y194243D02*
X323029Y194950D01*
G01X324373Y196294D02*
X325110Y197031D01*
G01X323382Y193803D02*
X325860Y196281D01*
G01X318393Y188713D02*
X319030D01*
G01D02*
X320132Y189815D01*
G01X320840Y191159D02*
X321476D01*
G01D02*
X322322Y192005D01*
G01D02*
Y194243D01*
G01X323382Y191565D02*
Y193803D01*
G01X322322Y194243D02*
X323029Y194950D01*
G01X324373Y196294D02*
X325110Y197031D01*
G01X323382Y193803D02*
X325860Y196281D01*
G01X298903Y172504D02*
X299610Y173211D01*
G01X300954Y174555D02*
X301735Y175336D01*
G01X303080Y176681D02*
X304051Y177652D01*
G01X305395Y178996D02*
X306102Y179703D01*
G01X307447Y181048D02*
X308258Y181859D01*
G01X309602Y183203D02*
X310309Y183910D01*
G01X311653Y185254D02*
X312572Y186173D01*
G01X313917Y187518D02*
X314652Y188253D01*
G01D02*
Y190343D01*
G01Y192243D02*
Y193448D01*
G01X313592Y188693D02*
Y193888D01*
G01X314652Y193448D02*
X319692Y198488D01*
G01X313592Y193888D02*
X318942Y199238D01*
G01X298903Y172504D02*
X299610Y173211D01*
G01X300954Y174555D02*
X301735Y175336D01*
G01X303080Y176681D02*
X304051Y177652D01*
G01X305395Y178996D02*
X306102Y179703D01*
G01X307447Y181048D02*
X308258Y181859D01*
G01X309602Y183203D02*
X310309Y183910D01*
G01X311653Y185254D02*
X312572Y186173D01*
G01X313917Y187518D02*
X314652Y188253D01*
G01D02*
Y190343D01*
G01Y192243D02*
Y193448D01*
G01X313592Y188693D02*
Y193888D01*
G01X314652Y193448D02*
X319692Y198488D01*
G01X313592Y193888D02*
X318942Y199238D01*
G01X318393Y188713D02*
X319030D01*
G01D02*
X320132Y189815D01*
G01X320840Y191159D02*
X321476D01*
G01D02*
X322322Y192005D01*
G01X323382Y191565D02*
Y193803D01*
G01X322322Y192005D02*
Y194243D01*
G01X323382Y193803D02*
X325860Y196281D01*
G01X322322Y194243D02*
X323029Y194950D01*
G01X323382Y193803D02*
X325860Y196281D01*
G01X324373Y196294D02*
X325110Y197031D01*
G01X318393Y188713D02*
X319030D01*
G01D02*
X320132Y189815D01*
G01X320840Y191159D02*
X321476D01*
G01D02*
X322322Y192005D01*
G01X323382Y191565D02*
Y193803D01*
G01X322322Y192005D02*
Y194243D01*
G01X323382Y193803D02*
X325860Y196281D01*
G01X322322Y194243D02*
X323029Y194950D01*
G01X323382Y193803D02*
X325860Y196281D01*
G01X324373Y196294D02*
X325110Y197031D01*
G01X315145Y406287D02*
Y413419D01*
G01X316205Y406287D02*
Y413859D01*
G01X315145Y413419D02*
X300414Y428150D01*
G01X316205Y413859D02*
X301472Y428592D01*
G01X300412Y428150D02*
Y449609D01*
G01X301472Y428592D02*
Y450052D01*
G01X320435Y408160D02*
Y415029D01*
G01X319375Y408160D02*
Y414589D01*
G01X320435Y415029D02*
X305272Y430192D01*
G01X319375Y414589D02*
X304214Y429750D01*
G01X305272Y430192D02*
Y451691D01*
G01X304212Y429750D02*
Y451248D01*
G01X305272Y451691D02*
X297684Y459279D01*
G01X304212Y451248D02*
X296624Y458836D01*
G01X297684Y459279D02*
Y460507D01*
G01X296624Y458836D02*
Y460950D01*
G01X297684Y460507D02*
X298244Y461067D01*
G01X296624Y460950D02*
X297184Y461510D01*
G01X298244Y461067D02*
Y463179D01*
G01X297184Y461510D02*
Y462736D01*
G01X298244Y463179D02*
X296420Y465003D01*
G01X297184Y462736D02*
X295977Y463943D01*
G01X298244Y463179D02*
X296420Y465003D01*
G01X294308D02*
X293748Y464443D01*
G01X295977Y463943D02*
X294751D01*
G01X294308Y465003D02*
X293748Y464443D01*
G01X294751Y463943D02*
X294191Y463383D01*
G01X316205Y406287D02*
Y413859D01*
G01X315145Y406287D02*
Y413419D01*
G01X316205Y413859D02*
X301472Y428592D01*
G01X315145Y413419D02*
X300414Y428150D01*
G01X301472Y428592D02*
Y450052D01*
G01X300412Y428150D02*
Y449609D01*
G01X319375Y408160D02*
Y414589D01*
G01X320435Y408160D02*
Y415029D01*
G01X319375Y414589D02*
X304214Y429750D01*
G01X320435Y415029D02*
X305272Y430192D01*
G01X304212Y429750D02*
Y451248D01*
G01X305272Y430192D02*
Y451691D01*
G01X304212Y451248D02*
X296624Y458836D01*
G01X305272Y451691D02*
X297684Y459279D01*
G01X296624Y458836D02*
Y460950D01*
G01X297684Y459279D02*
Y460507D01*
G01X296624Y460950D02*
X297184Y461510D01*
G01X297684Y460507D02*
X298244Y461067D01*
G01X297184Y461510D02*
Y462736D01*
G01X298244Y461067D02*
Y463179D01*
G01X297184Y462736D02*
X295977Y463943D01*
G01D02*
X294751D01*
G01X298244Y463179D02*
X296420Y465003D01*
G01X295977Y463943D02*
X294751D01*
G01X295977D02*
X294751D01*
G01D02*
X294191Y463383D01*
G01X294308Y465003D02*
X293748Y464443D01*
G01X315145Y406287D02*
Y413419D01*
G01X316205Y406287D02*
Y413859D01*
G01X315145Y413419D02*
X300414Y428150D01*
G01X316205Y413859D02*
X301472Y428592D01*
G01X300412Y428150D02*
Y449609D01*
G01X301472Y428592D02*
Y450052D01*
G01X320435Y408160D02*
Y415029D01*
G01X319375Y408160D02*
Y414589D01*
G01X320435Y415029D02*
X305272Y430192D01*
G01X319375Y414589D02*
X304214Y429750D01*
G01X305272Y430192D02*
Y451691D01*
G01X304212Y429750D02*
Y451248D01*
G01X305272Y451691D02*
X297684Y459279D01*
G01X304212Y451248D02*
X296624Y458836D01*
G01X297684Y459279D02*
Y460507D01*
G01X296624Y458836D02*
Y460950D01*
G01X297684Y460507D02*
X298244Y461067D01*
G01X296624Y460950D02*
X297184Y461510D01*
G01X298244Y461067D02*
Y463179D01*
G01X297184Y461510D02*
Y462736D01*
G01X298244Y463179D02*
X296420Y465003D01*
G01X297184Y462736D02*
X295977Y463943D01*
G01X298244Y463179D02*
X296420Y465003D01*
G01X294308D02*
X293748Y464443D01*
G01X295977Y463943D02*
X294751D01*
G01X294308Y465003D02*
X293748Y464443D01*
G01X294751Y463943D02*
X294191Y463383D01*
G01X316205Y406287D02*
Y413859D01*
G01X315145Y406287D02*
Y413419D01*
G01X316205Y413859D02*
X301472Y428592D01*
G01X315145Y413419D02*
X300414Y428150D01*
G01X301472Y428592D02*
Y450052D01*
G01X300412Y428150D02*
Y449609D01*
G01X319375Y408160D02*
Y414589D01*
G01X320435Y408160D02*
Y415029D01*
G01X319375Y414589D02*
X304214Y429750D01*
G01X320435Y415029D02*
X305272Y430192D01*
G01X304212Y429750D02*
Y451248D01*
G01X305272Y430192D02*
Y451691D01*
G01X304212Y451248D02*
X296624Y458836D01*
G01X305272Y451691D02*
X297684Y459279D01*
G01X296624Y458836D02*
Y460950D01*
G01X297684Y459279D02*
Y460507D01*
G01X296624Y460950D02*
X297184Y461510D01*
G01X297684Y460507D02*
X298244Y461067D01*
G01X297184Y461510D02*
Y462736D01*
G01X298244Y461067D02*
Y463179D01*
G01X297184Y462736D02*
X295977Y463943D01*
G01D02*
X294751D01*
G01X298244Y463179D02*
X296420Y465003D01*
G01X295977Y463943D02*
X294751D01*
G01X295977D02*
X294751D01*
G01D02*
X294191Y463383D01*
G01X294308Y465003D02*
X293748Y464443D01*
G01X296420Y465003D02*
X294308D01*
G01X296420D02*
X294308D01*
G01X296420D02*
X294308D01*
G01X296420D02*
X294308D01*
G01X466753Y99229D02*
Y25006D01*
G01Y99229D02*
Y25006D01*
G01Y99229D02*
Y25006D01*
G01X467813Y55580D02*
Y24563D01*
G01X466753Y25006D02*
X462878Y21131D01*
G01X467813Y24563D02*
X463938Y20688D01*
G01X462878Y21131D02*
Y13554D01*
G01X463938Y20688D02*
Y19620D01*
G01X464732Y11700D02*
X465831D01*
G01D02*
X466778Y10753D01*
G01X464732Y14300D02*
X467838Y11194D01*
G01X466778Y10753D02*
Y8220D01*
G01Y4080D02*
Y3120D01*
G01Y-1220D02*
Y-4509D01*
G01X467838Y11194D02*
Y-4952D01*
G01X466778Y-4509D02*
X466067Y-5220D01*
G01X467838Y-4952D02*
X466510Y-6280D01*
G01X466067Y-5220D02*
X465551D01*
G01X466510Y-6280D02*
X465528D01*
G01X466753Y99229D02*
Y25006D01*
G01Y99229D02*
Y25006D01*
G01Y99229D02*
Y25006D01*
G01X467813Y55580D02*
Y24563D01*
G01X466753Y25006D02*
X462878Y21131D01*
G01X467813Y24563D02*
X463938Y20688D01*
G01X462878Y21131D02*
Y13554D01*
G01X463938Y20688D02*
Y19620D01*
G01X464732Y11700D02*
X465831D01*
G01D02*
X466778Y10753D01*
G01X464732Y14300D02*
X467838Y11194D01*
G01X466778Y10753D02*
Y8220D01*
G01Y4080D02*
Y3120D01*
G01Y-1220D02*
Y-4509D01*
G01X467838Y11194D02*
Y-4952D01*
G01X466778Y-4509D02*
X466067Y-5220D01*
G01X467838Y-4952D02*
X466510Y-6280D01*
G01X466067Y-5220D02*
X465551D01*
G01X466510Y-6280D02*
X465528D01*
G01X471904Y118467D02*
Y24557D01*
G01Y118467D02*
Y24557D01*
G01Y118467D02*
Y24557D01*
G01X472964Y37280D02*
Y27186D01*
G01X471904Y118467D02*
Y24557D01*
G01X472964Y24946D02*
Y24114D01*
G01X471904Y24557D02*
X468578Y21231D01*
G01X472964Y24114D02*
X472196Y23346D01*
G01X471904Y24557D02*
X468578Y21231D01*
G01X471488Y21762D02*
X470612D01*
G01X471904Y24557D02*
X468578Y21231D01*
G01X470612Y21762D02*
X469638Y20788D01*
G01X468578Y21231D02*
Y18687D01*
G01X469638Y20788D02*
Y19920D01*
G01X469832Y11915D02*
X470930D01*
G01D02*
X471964Y10881D01*
G01X469832Y14514D02*
X473024Y11322D01*
G01X471964Y10881D02*
Y8106D01*
G01Y4280D02*
Y2907D01*
G01Y-1007D02*
Y-3628D01*
G01X473024Y11322D02*
Y-4068D01*
G01X471964Y-3628D02*
X470941Y-4651D01*
G01D02*
X469832D01*
G01X473024Y-4068D02*
X469832Y-7260D01*
G01X471904Y118467D02*
Y24557D01*
G01Y118467D02*
Y24557D01*
G01Y118467D02*
Y24557D01*
G01X472964Y37280D02*
Y27186D01*
G01X471904Y118467D02*
Y24557D01*
G01X472964Y24946D02*
Y24114D01*
G01X471904Y24557D02*
X468578Y21231D01*
G01X472964Y24114D02*
X472196Y23346D01*
G01X471904Y24557D02*
X468578Y21231D01*
G01X471488Y21762D02*
X470612D01*
G01X471904Y24557D02*
X468578Y21231D01*
G01X470612Y21762D02*
X469638Y20788D01*
G01X468578Y21231D02*
Y18687D01*
G01X469638Y20788D02*
Y19920D01*
G01X469832Y11915D02*
X470930D01*
G01D02*
X471964Y10881D01*
G01X469832Y14514D02*
X473024Y11322D01*
G01X471964Y10881D02*
Y8106D01*
G01Y4280D02*
Y2907D01*
G01Y-1007D02*
Y-3628D01*
G01X473024Y11322D02*
Y-4068D01*
G01X471964Y-3628D02*
X470941Y-4651D01*
G01D02*
X469832D01*
G01X473024Y-4068D02*
X469832Y-7260D01*
G01X467813Y55580D02*
Y24563D01*
G01X466753Y99229D02*
Y25006D01*
G01X467813Y24563D02*
X463938Y20688D01*
G01X466753Y25006D02*
X462878Y21131D01*
G01X463938Y20688D02*
Y19620D01*
G01X462878Y21131D02*
Y13554D01*
G01X464732Y14300D02*
X467838Y11194D01*
G01X464732Y11700D02*
X465831D01*
G01X464732Y14300D02*
X467838Y11194D01*
G01X465831Y11700D02*
X466778Y10753D01*
G01X467838Y11194D02*
Y-4952D01*
G01X466778Y10753D02*
Y8220D01*
G01X467838Y11194D02*
Y-4952D01*
G01X466778Y4080D02*
Y3120D01*
G01X467838Y11194D02*
Y-4952D01*
G01X466778Y-1220D02*
Y-4509D01*
G01X467838Y-4952D02*
X466510Y-6280D01*
G01X466778Y-4509D02*
X466067Y-5220D01*
G01X466510Y-6280D02*
X465528D01*
G01X466067Y-5220D02*
X465551D01*
G01X467813Y55580D02*
Y24563D01*
G01X466753Y99229D02*
Y25006D01*
G01X467813Y24563D02*
X463938Y20688D01*
G01X466753Y25006D02*
X462878Y21131D01*
G01X463938Y20688D02*
Y19620D01*
G01X462878Y21131D02*
Y13554D01*
G01X464732Y14300D02*
X467838Y11194D01*
G01X464732Y11700D02*
X465831D01*
G01X464732Y14300D02*
X467838Y11194D01*
G01X465831Y11700D02*
X466778Y10753D01*
G01X467838Y11194D02*
Y-4952D01*
G01X466778Y10753D02*
Y8220D01*
G01X467838Y11194D02*
Y-4952D01*
G01X466778Y4080D02*
Y3120D01*
G01X467838Y11194D02*
Y-4952D01*
G01X466778Y-1220D02*
Y-4509D01*
G01X467838Y-4952D02*
X466510Y-6280D01*
G01X466778Y-4509D02*
X466067Y-5220D01*
G01X466510Y-6280D02*
X465528D01*
G01X466067Y-5220D02*
X465551D01*
G01X472964Y37280D02*
Y27186D01*
G01Y24946D02*
Y24114D01*
G01X471904Y118467D02*
Y24557D01*
G01X472964Y24114D02*
X472196Y23346D01*
G01X471488Y21762D02*
X470612D01*
G01D02*
X469638Y20788D01*
G01X471904Y24557D02*
X468578Y21231D01*
G01X469638Y20788D02*
Y19920D01*
G01X468578Y21231D02*
Y18687D01*
G01X469832Y14514D02*
X473024Y11322D01*
G01X469832Y11915D02*
X470930D01*
G01X469832Y14514D02*
X473024Y11322D01*
G01X470930Y11915D02*
X471964Y10881D01*
G01X473024Y11322D02*
Y-4068D01*
G01X471964Y10881D02*
Y8106D01*
G01X473024Y11322D02*
Y-4068D01*
G01X471964Y4280D02*
Y2907D01*
G01X473024Y11322D02*
Y-4068D01*
G01X471964Y-1007D02*
Y-3628D01*
G01X473024Y-4068D02*
X469832Y-7260D01*
G01X471964Y-3628D02*
X470941Y-4651D01*
G01X473024Y-4068D02*
X469832Y-7260D01*
G01X470941Y-4651D02*
X469832D01*
G01X472964Y37280D02*
Y27186D01*
G01Y24946D02*
Y24114D01*
G01X471904Y118467D02*
Y24557D01*
G01X472964Y24114D02*
X472196Y23346D01*
G01X471488Y21762D02*
X470612D01*
G01D02*
X469638Y20788D01*
G01X471904Y24557D02*
X468578Y21231D01*
G01X469638Y20788D02*
Y19920D01*
G01X468578Y21231D02*
Y18687D01*
G01X469832Y14514D02*
X473024Y11322D01*
G01X469832Y11915D02*
X470930D01*
G01X469832Y14514D02*
X473024Y11322D01*
G01X470930Y11915D02*
X471964Y10881D01*
G01X473024Y11322D02*
Y-4068D01*
G01X471964Y10881D02*
Y8106D01*
G01X473024Y11322D02*
Y-4068D01*
G01X471964Y4280D02*
Y2907D01*
G01X473024Y11322D02*
Y-4068D01*
G01X471964Y-1007D02*
Y-3628D01*
G01X473024Y-4068D02*
X469832Y-7260D01*
G01X471964Y-3628D02*
X470941Y-4651D01*
G01X473024Y-4068D02*
X469832Y-7260D01*
G01X470941Y-4651D02*
X469832D01*
G01X467813Y98789D02*
Y60820D01*
G01Y58580D02*
Y57820D01*
G01Y98789D02*
Y60820D01*
G01Y58580D02*
Y57820D01*
G01X472964Y118907D02*
Y42520D01*
G01Y40280D02*
Y39520D01*
G01Y118907D02*
Y42520D01*
G01Y40280D02*
Y39520D01*
G01X467813Y98789D02*
Y60820D01*
G01Y58580D02*
Y57820D01*
G01Y98789D02*
Y60820D01*
G01Y58580D02*
Y57820D01*
G01X472964Y118907D02*
Y42520D01*
G01Y40280D02*
Y39520D01*
G01Y118907D02*
Y42520D01*
G01Y40280D02*
Y39520D01*
G01X430237Y186013D02*
Y154575D01*
G01Y186013D02*
Y154575D01*
G01Y186013D02*
Y154575D01*
G01Y186013D02*
Y154575D01*
G01Y186013D02*
Y154575D01*
G01Y186013D02*
Y154575D01*
G01Y186013D02*
Y154575D01*
G01Y186013D02*
Y154575D01*
G01Y186013D02*
Y154575D01*
G01Y186013D02*
Y154575D01*
G01X431297Y157250D02*
Y155015D01*
G01X430237Y154575D02*
X468012Y116800D01*
G01X431297Y155015D02*
X432004Y154308D01*
G01X430237Y154575D02*
X468012Y116800D01*
G01X433348Y152964D02*
X434086Y152226D01*
G01X430237Y154575D02*
X468012Y116800D01*
G01X435430Y150882D02*
X469072Y117240D01*
G01X468012Y116800D02*
Y115367D01*
G01X469072Y117240D02*
Y114924D01*
G01X468012Y115367D02*
X467140Y114495D01*
G01X469072Y114924D02*
X467583Y113435D01*
G01X467140Y114495D02*
X463901D01*
G01X467583Y113435D02*
X464344D01*
G01X463901Y114495D02*
X462412Y113006D01*
G01X464344Y113435D02*
X463472Y112563D01*
G01X462412Y113006D02*
Y109727D01*
G01X463472Y112563D02*
Y110167D01*
G01X462412Y109727D02*
X464004Y108135D01*
G01X463472Y110167D02*
X464444Y109195D01*
G01X464004Y108135D02*
X467511D01*
G01X464444Y109195D02*
X467951D01*
G01X467511Y108135D02*
X468012Y107634D01*
G01X467951Y109195D02*
X469072Y108074D01*
G01X468012Y107634D02*
Y100488D01*
G01X469072Y108074D02*
Y100048D01*
G01X468012Y100488D02*
X466753Y99229D01*
G01X469072Y100048D02*
X467813Y98789D01*
G01X430237Y186013D02*
Y154575D01*
G01Y186013D02*
Y154575D01*
G01Y186013D02*
Y154575D01*
G01Y186013D02*
Y154575D01*
G01Y186013D02*
Y154575D01*
G01Y186013D02*
Y154575D01*
G01Y186013D02*
Y154575D01*
G01Y186013D02*
Y154575D01*
G01Y186013D02*
Y154575D01*
G01Y186013D02*
Y154575D01*
G01X431297Y157250D02*
Y155015D01*
G01X430237Y154575D02*
X468012Y116800D01*
G01X431297Y155015D02*
X432004Y154308D01*
G01X430237Y154575D02*
X468012Y116800D01*
G01X433348Y152964D02*
X434086Y152226D01*
G01X430237Y154575D02*
X468012Y116800D01*
G01X435430Y150882D02*
X469072Y117240D01*
G01X468012Y116800D02*
Y115367D01*
G01X469072Y117240D02*
Y114924D01*
G01X468012Y115367D02*
X467140Y114495D01*
G01X469072Y114924D02*
X467583Y113435D01*
G01X467140Y114495D02*
X463901D01*
G01X467583Y113435D02*
X464344D01*
G01X463901Y114495D02*
X462412Y113006D01*
G01X464344Y113435D02*
X463472Y112563D01*
G01X462412Y113006D02*
Y109727D01*
G01X463472Y112563D02*
Y110167D01*
G01X462412Y109727D02*
X464004Y108135D01*
G01X463472Y110167D02*
X464444Y109195D01*
G01X464004Y108135D02*
X467511D01*
G01X464444Y109195D02*
X467951D01*
G01X467511Y108135D02*
X468012Y107634D01*
G01X467951Y109195D02*
X469072Y108074D01*
G01X468012Y107634D02*
Y100488D01*
G01X469072Y108074D02*
Y100048D01*
G01X468012Y100488D02*
X466753Y99229D01*
G01X469072Y100048D02*
X467813Y98789D01*
G01X434608Y167925D02*
Y155763D01*
G01X435668Y183955D02*
Y156203D01*
G01X434608Y155763D02*
X471904Y118467D01*
G01X435668Y156203D02*
X472964Y118907D01*
G01X434608Y167925D02*
Y155763D01*
G01X435668Y183955D02*
Y156203D01*
G01X434608Y155763D02*
X471904Y118467D01*
G01X435668Y156203D02*
X472964Y118907D01*
G01X431297Y157250D02*
Y155015D01*
G01X430237Y186013D02*
Y154575D01*
G01X431297Y155015D02*
X432004Y154308D01*
G01X433348Y152964D02*
X434086Y152226D01*
G01X435430Y150882D02*
X469072Y117240D01*
G01X430237Y154575D02*
X468012Y116800D01*
G01X469072Y117240D02*
Y114924D01*
G01X468012Y116800D02*
Y115367D01*
G01X469072Y114924D02*
X467583Y113435D01*
G01X468012Y115367D02*
X467140Y114495D01*
G01X467583Y113435D02*
X464344D01*
G01X467140Y114495D02*
X463901D01*
G01X464344Y113435D02*
X463472Y112563D01*
G01X463901Y114495D02*
X462412Y113006D01*
G01X463472Y112563D02*
Y110167D01*
G01X462412Y113006D02*
Y109727D01*
G01X463472Y110167D02*
X464444Y109195D01*
G01X462412Y109727D02*
X464004Y108135D01*
G01X464444Y109195D02*
X467951D01*
G01X464004Y108135D02*
X467511D01*
G01X467951Y109195D02*
X469072Y108074D01*
G01X467511Y108135D02*
X468012Y107634D01*
G01X469072Y108074D02*
Y100048D01*
G01X468012Y107634D02*
Y100488D01*
G01X469072Y100048D02*
X467813Y98789D01*
G01X468012Y100488D02*
X466753Y99229D01*
G01X431297Y157250D02*
Y155015D01*
G01X430237Y186013D02*
Y154575D01*
G01X431297Y155015D02*
X432004Y154308D01*
G01X433348Y152964D02*
X434086Y152226D01*
G01X435430Y150882D02*
X469072Y117240D01*
G01X430237Y154575D02*
X468012Y116800D01*
G01X469072Y117240D02*
Y114924D01*
G01X468012Y116800D02*
Y115367D01*
G01X469072Y114924D02*
X467583Y113435D01*
G01X468012Y115367D02*
X467140Y114495D01*
G01X467583Y113435D02*
X464344D01*
G01X467140Y114495D02*
X463901D01*
G01X464344Y113435D02*
X463472Y112563D01*
G01X463901Y114495D02*
X462412Y113006D01*
G01X463472Y112563D02*
Y110167D01*
G01X462412Y113006D02*
Y109727D01*
G01X463472Y110167D02*
X464444Y109195D01*
G01X462412Y109727D02*
X464004Y108135D01*
G01X464444Y109195D02*
X467951D01*
G01X464004Y108135D02*
X467511D01*
G01X467951Y109195D02*
X469072Y108074D01*
G01X467511Y108135D02*
X468012Y107634D01*
G01X469072Y108074D02*
Y100048D01*
G01X468012Y107634D02*
Y100488D01*
G01X469072Y100048D02*
X467813Y98789D01*
G01X468012Y100488D02*
X466753Y99229D01*
G01X435668Y183955D02*
Y156203D01*
G01Y183955D02*
Y156203D01*
G01Y183955D02*
Y156203D01*
G01Y183955D02*
Y156203D01*
G01Y183955D02*
Y156203D01*
G01X434608Y167925D02*
Y155763D01*
G01X435668Y156203D02*
X472964Y118907D01*
G01X434608Y155763D02*
X471904Y118467D01*
G01X435668Y183955D02*
Y156203D01*
G01Y183955D02*
Y156203D01*
G01Y183955D02*
Y156203D01*
G01Y183955D02*
Y156203D01*
G01Y183955D02*
Y156203D01*
G01X434608Y167925D02*
Y155763D01*
G01X435668Y156203D02*
X472964Y118907D01*
G01X434608Y155763D02*
X471904Y118467D01*
G01X471365Y169156D02*
Y155246D01*
G01Y169156D02*
Y155246D01*
G01Y169156D02*
Y155246D01*
G01Y169156D02*
Y155246D01*
G01Y169156D02*
Y155246D01*
G01X472425Y157866D02*
Y155686D01*
G01X471365Y155246D02*
X488989Y137620D01*
G01X472425Y155686D02*
X489429Y138680D01*
G01X477059Y170030D02*
Y154950D01*
G01X478119Y170470D02*
Y155390D01*
G01X477059Y154950D02*
X490589Y141420D01*
G01X478119Y155390D02*
X491029Y142480D01*
G01X472425Y157866D02*
Y155686D01*
G01X471365Y169156D02*
Y155246D01*
G01X472425Y155686D02*
X489429Y138680D01*
G01X471365Y155246D02*
X488989Y137620D01*
G01X478119Y170470D02*
Y155390D01*
G01X477059Y170030D02*
Y154950D01*
G01X478119Y155390D02*
X491029Y142480D01*
G01X477059Y154950D02*
X490589Y141420D01*
G01X471365Y169156D02*
Y155246D01*
G01Y169156D02*
Y155246D01*
G01Y169156D02*
Y155246D01*
G01Y169156D02*
Y155246D01*
G01Y169156D02*
Y155246D01*
G01X472425Y157866D02*
Y155686D01*
G01X471365Y155246D02*
X488989Y137620D01*
G01X472425Y155686D02*
X489429Y138680D01*
G01X472425Y157866D02*
Y155686D01*
G01X471365Y169156D02*
Y155246D01*
G01X472425Y155686D02*
X489429Y138680D01*
G01X471365Y155246D02*
X488989Y137620D01*
G01X477059Y170030D02*
Y154950D01*
G01X478119Y170470D02*
Y155390D01*
G01X477059Y154950D02*
X490589Y141420D01*
G01X478119Y155390D02*
X491029Y142480D01*
G01X478119Y170470D02*
Y155390D01*
G01X477059Y170030D02*
Y154950D01*
G01X478119Y155390D02*
X491029Y142480D01*
G01X477059Y154950D02*
X490589Y141420D01*
G01X431297Y186013D02*
Y183019D01*
G01Y181119D02*
Y180119D01*
G01Y178219D02*
Y176779D01*
G01Y174879D02*
Y173822D01*
G01Y171922D02*
Y170922D01*
G01Y169022D02*
Y168022D01*
G01Y166122D02*
Y164950D01*
G01Y163050D02*
Y162050D01*
G01Y160150D02*
Y159150D01*
G01Y186013D02*
Y183019D01*
G01Y181119D02*
Y180119D01*
G01Y178219D02*
Y176779D01*
G01Y174879D02*
Y173822D01*
G01Y171922D02*
Y170922D01*
G01Y169022D02*
Y168022D01*
G01Y166122D02*
Y164950D01*
G01Y163050D02*
Y162050D01*
G01Y160150D02*
Y159150D01*
G01X433937Y186413D02*
Y184186D01*
G01X434997Y186413D02*
Y184626D01*
G01X433937Y184186D02*
X434608Y183515D01*
G01X434997Y184626D02*
X435668Y183955D01*
G01X434608Y183515D02*
Y181947D01*
G01Y180047D02*
Y177657D01*
G01Y175757D02*
Y173660D01*
G01Y171760D02*
Y169825D01*
G01X433937Y186413D02*
Y184186D01*
G01X434997Y186413D02*
Y184626D01*
G01X433937Y184186D02*
X434608Y183515D01*
G01X434997Y184626D02*
X435668Y183955D01*
G01X434608Y183515D02*
Y181947D01*
G01Y180047D02*
Y177657D01*
G01Y175757D02*
Y173660D01*
G01Y171760D02*
Y169825D01*
G01X431297Y186013D02*
Y183019D01*
G01Y181119D02*
Y180119D01*
G01Y178219D02*
Y176779D01*
G01Y174879D02*
Y173822D01*
G01Y171922D02*
Y170922D01*
G01Y169022D02*
Y168022D01*
G01Y166122D02*
Y164950D01*
G01Y163050D02*
Y162050D01*
G01Y160150D02*
Y159150D01*
G01Y186013D02*
Y183019D01*
G01Y181119D02*
Y180119D01*
G01Y178219D02*
Y176779D01*
G01Y174879D02*
Y173822D01*
G01Y171922D02*
Y170922D01*
G01Y169022D02*
Y168022D01*
G01Y166122D02*
Y164950D01*
G01Y163050D02*
Y162050D01*
G01Y160150D02*
Y159150D01*
G01X434997Y186413D02*
Y184626D01*
G01X433937Y186413D02*
Y184186D01*
G01X434997Y184626D02*
X435668Y183955D01*
G01X433937Y184186D02*
X434608Y183515D01*
G01D02*
Y181947D01*
G01Y180047D02*
Y177657D01*
G01Y175757D02*
Y173660D01*
G01Y171760D02*
Y169825D01*
G01X434997Y186413D02*
Y184626D01*
G01X433937Y186413D02*
Y184186D01*
G01X434997Y184626D02*
X435668Y183955D01*
G01X433937Y184186D02*
X434608Y183515D01*
G01D02*
Y181947D01*
G01Y180047D02*
Y177657D01*
G01Y175757D02*
Y173660D01*
G01Y171760D02*
Y169825D01*
G01X459958Y183900D02*
Y180563D01*
G01X461018Y183900D02*
Y181003D01*
G01X459958Y180563D02*
X471365Y169156D01*
G01X461018Y181003D02*
X461725Y180296D01*
G01X459958Y180563D02*
X471365Y169156D01*
G01X463069Y178952D02*
X463776Y178245D01*
G01X459958Y180563D02*
X471365Y169156D01*
G01X465120Y176901D02*
X465827Y176194D01*
G01X459958Y180563D02*
X471365Y169156D01*
G01X467171Y174850D02*
X467878Y174143D01*
G01X459958Y180563D02*
X471365Y169156D01*
G01X469222Y172799D02*
X469929Y172092D01*
G01X459958Y180563D02*
X471365Y169156D01*
G01X471273Y170748D02*
X472425Y169596D01*
G01D02*
Y168466D01*
G01Y166566D02*
Y165566D01*
G01Y163666D02*
Y162666D01*
G01Y160766D02*
Y159766D01*
G01X463759Y185913D02*
Y183330D01*
G01X464819Y185913D02*
Y183770D01*
G01X463759Y183330D02*
X466121Y180968D01*
G01X467466Y179623D02*
X468567Y178522D01*
G01X469912Y177177D02*
X470900Y176189D01*
G01X472244Y174845D02*
X473003Y174086D01*
G01X474347Y172742D02*
X477059Y170030D01*
G01X464819Y183770D02*
X478119Y170470D01*
G01X461018Y183900D02*
Y181003D01*
G01X459958Y183900D02*
Y180563D01*
G01X461018Y181003D02*
X461725Y180296D01*
G01X463069Y178952D02*
X463776Y178245D01*
G01X465120Y176901D02*
X465827Y176194D01*
G01X467171Y174850D02*
X467878Y174143D01*
G01X469222Y172799D02*
X469929Y172092D01*
G01X471273Y170748D02*
X472425Y169596D01*
G01X459958Y180563D02*
X471365Y169156D01*
G01X472425Y169596D02*
Y168466D01*
G01Y166566D02*
Y165566D01*
G01Y163666D02*
Y162666D01*
G01Y160766D02*
Y159766D01*
G01X464819Y185913D02*
Y183770D01*
G01X463759Y185913D02*
Y183330D01*
G01X464819Y183770D02*
X478119Y170470D01*
G01X463759Y183330D02*
X466121Y180968D01*
G01X464819Y183770D02*
X478119Y170470D01*
G01X467466Y179623D02*
X468567Y178522D01*
G01X464819Y183770D02*
X478119Y170470D01*
G01X469912Y177177D02*
X470900Y176189D01*
G01X464819Y183770D02*
X478119Y170470D01*
G01X472244Y174845D02*
X473003Y174086D01*
G01X464819Y183770D02*
X478119Y170470D01*
G01X474347Y172742D02*
X477059Y170030D01*
G01X459958Y183900D02*
Y180563D01*
G01X461018Y183900D02*
Y181003D01*
G01X459958Y180563D02*
X471365Y169156D01*
G01X461018Y181003D02*
X461725Y180296D01*
G01X459958Y180563D02*
X471365Y169156D01*
G01X463069Y178952D02*
X463776Y178245D01*
G01X459958Y180563D02*
X471365Y169156D01*
G01X465120Y176901D02*
X465827Y176194D01*
G01X459958Y180563D02*
X471365Y169156D01*
G01X467171Y174850D02*
X467878Y174143D01*
G01X459958Y180563D02*
X471365Y169156D01*
G01X469222Y172799D02*
X469929Y172092D01*
G01X459958Y180563D02*
X471365Y169156D01*
G01X471273Y170748D02*
X472425Y169596D01*
G01D02*
Y168466D01*
G01Y166566D02*
Y165566D01*
G01Y163666D02*
Y162666D01*
G01Y160766D02*
Y159766D01*
G01X461018Y183900D02*
Y181003D01*
G01X459958Y183900D02*
Y180563D01*
G01X461018Y181003D02*
X461725Y180296D01*
G01X463069Y178952D02*
X463776Y178245D01*
G01X465120Y176901D02*
X465827Y176194D01*
G01X467171Y174850D02*
X467878Y174143D01*
G01X469222Y172799D02*
X469929Y172092D01*
G01X471273Y170748D02*
X472425Y169596D01*
G01X459958Y180563D02*
X471365Y169156D01*
G01X472425Y169596D02*
Y168466D01*
G01Y166566D02*
Y165566D01*
G01Y163666D02*
Y162666D01*
G01Y160766D02*
Y159766D01*
G01X463759Y185913D02*
Y183330D01*
G01X464819Y185913D02*
Y183770D01*
G01X463759Y183330D02*
X466121Y180968D01*
G01X467466Y179623D02*
X468567Y178522D01*
G01X469912Y177177D02*
X470900Y176189D01*
G01X472244Y174845D02*
X473003Y174086D01*
G01X474347Y172742D02*
X477059Y170030D01*
G01X464819Y183770D02*
X478119Y170470D01*
G01X464819Y185913D02*
Y183770D01*
G01X463759Y185913D02*
Y183330D01*
G01X464819Y183770D02*
X478119Y170470D01*
G01X463759Y183330D02*
X466121Y180968D01*
G01X464819Y183770D02*
X478119Y170470D01*
G01X467466Y179623D02*
X468567Y178522D01*
G01X464819Y183770D02*
X478119Y170470D01*
G01X469912Y177177D02*
X470900Y176189D01*
G01X464819Y183770D02*
X478119Y170470D01*
G01X472244Y174845D02*
X473003Y174086D01*
G01X464819Y183770D02*
X478119Y170470D01*
G01X474347Y172742D02*
X477059Y170030D01*
G01X431517Y412574D02*
Y457457D01*
G01X432577Y412574D02*
Y457017D01*
G01X431517Y457457D02*
X453341Y479281D01*
G01X432577Y457017D02*
X454401Y478841D01*
G01X461630Y422000D02*
Y445838D01*
G01X462690Y422000D02*
Y445398D01*
G01X461630Y445838D02*
X491620Y475828D01*
G01X462690Y445398D02*
X492060Y474768D01*
G01X436327Y412574D02*
Y455435D01*
G01X435267Y412574D02*
Y455875D01*
G01X436327Y455435D02*
X459961Y479069D01*
G01X435267Y455875D02*
X458901Y479509D01*
G01X466453Y422000D02*
Y444685D01*
G01X465393Y422000D02*
Y445125D01*
G01X466453Y444685D02*
X493490Y471722D01*
G01X465393Y445125D02*
X493050Y472782D01*
G01X432577Y412574D02*
Y457017D01*
G01X431517Y412574D02*
Y457457D01*
G01X432577Y457017D02*
X454401Y478841D01*
G01X431517Y457457D02*
X453341Y479281D01*
G01X462690Y422000D02*
Y445398D01*
G01X461630Y422000D02*
Y445838D01*
G01X462690Y445398D02*
X492060Y474768D01*
G01X461630Y445838D02*
X491620Y475828D01*
G01X435267Y412574D02*
Y455875D01*
G01X436327Y412574D02*
Y455435D01*
G01X435267Y455875D02*
X458901Y479509D01*
G01X436327Y455435D02*
X459961Y479069D01*
G01X465393Y422000D02*
Y445125D01*
G01X466453Y422000D02*
Y444685D01*
G01X465393Y445125D02*
X493050Y472782D01*
G01X466453Y444685D02*
X493490Y471722D01*
G01X431517Y412574D02*
Y457457D01*
G01X432577Y412574D02*
Y457017D01*
G01X431517Y457457D02*
X453341Y479281D01*
G01X432577Y457017D02*
X454401Y478841D01*
G01X431517Y412574D02*
Y457457D01*
G01X432577Y412574D02*
Y457017D01*
G01X431517Y457457D02*
X453341Y479281D01*
G01X432577Y457017D02*
X454401Y478841D01*
G01X436327Y412574D02*
Y455435D01*
G01X435267Y412574D02*
Y455875D01*
G01X436327Y455435D02*
X459961Y479069D01*
G01X435267Y455875D02*
X458901Y479509D01*
G01X432577Y412574D02*
Y457017D01*
G01X431517Y412574D02*
Y457457D01*
G01X432577Y457017D02*
X454401Y478841D01*
G01X431517Y457457D02*
X453341Y479281D01*
G01X435267Y412574D02*
Y455875D01*
G01X436327Y412574D02*
Y455435D01*
G01X435267Y455875D02*
X458901Y479509D01*
G01X436327Y455435D02*
X459961Y479069D01*
G01X461630Y422000D02*
Y445838D01*
G01X462690Y422000D02*
Y445398D01*
G01X461630Y445838D02*
X491620Y475828D01*
G01X462690Y445398D02*
X492060Y474768D01*
G01X462690Y422000D02*
Y445398D01*
G01X461630Y422000D02*
Y445838D01*
G01X462690Y445398D02*
X492060Y474768D01*
G01X461630Y445838D02*
X491620Y475828D01*
G01X466453Y422000D02*
Y444685D01*
G01X465393Y422000D02*
Y445125D01*
G01X466453Y444685D02*
X493490Y471722D01*
G01X465393Y445125D02*
X493050Y472782D01*
G01X465393Y422000D02*
Y445125D01*
G01X466453Y422000D02*
Y444685D01*
G01X465393Y445125D02*
X493050Y472782D01*
G01X466453Y444685D02*
X493490Y471722D01*
G01X453341Y479281D02*
Y484030D01*
G01X454401Y478841D02*
Y483590D01*
G01X453341Y484030D02*
X465150Y495840D01*
G01X454401Y483590D02*
X466050Y495239D01*
G01X465150Y495840D02*
X465951Y497774D01*
G01D02*
X466342Y498717D01*
G01D02*
X466753Y499708D01*
G01X466050Y495239D02*
X467490Y498717D01*
G01X466342D02*
X466753Y499708D01*
G01X467490Y498717D02*
X467813Y499497D01*
G01X466753Y499708D02*
Y563854D01*
G01X467813Y499497D02*
Y586915D01*
G01X459961Y479069D02*
Y480811D01*
G01X458901Y479509D02*
Y480371D01*
G01X459961Y480811D02*
X458955Y481817D01*
G01X458901Y480371D02*
X457895Y481377D01*
G01X458955Y481817D02*
Y482677D01*
G01X457895Y481377D02*
Y483117D01*
G01X458955Y482677D02*
X459943Y483665D01*
G01X457895Y483117D02*
X459503Y484725D01*
G01X459943Y483665D02*
X460803D01*
G01X459503Y484725D02*
X461243D01*
G01X460803Y483665D02*
X461809Y482659D01*
G01X461243Y484725D02*
X462249Y483719D01*
G01X460803Y483665D02*
X461809Y482659D01*
G01D02*
X463551D01*
G01X462249Y483719D02*
X463111D01*
G01X463551Y482659D02*
X465155Y484263D01*
G01X463111Y483719D02*
X464095Y484703D01*
G01X465155Y484263D02*
Y486005D01*
G01X464095Y484703D02*
Y485565D01*
G01X465155Y486005D02*
X464038Y487122D01*
G01X464095Y485565D02*
X462978Y486682D01*
G01X464038Y487122D02*
Y487941D01*
G01X462978Y486682D02*
Y488381D01*
G01X464038Y487941D02*
X465026Y488929D01*
G01X462978Y488381D02*
X464586Y489989D01*
G01X465026Y488929D02*
X465927D01*
G01X464586Y489989D02*
X466367D01*
G01X465927Y488929D02*
X467003Y487853D01*
G01X466367Y489989D02*
X467443Y488913D01*
G01X467003Y487853D02*
X468745D01*
G01X467443Y488913D02*
X468305D01*
G01X468745Y487853D02*
X471447Y490555D01*
G01X468305Y488913D02*
X470387Y490995D01*
G01X471447Y490555D02*
Y508355D01*
G01X470387Y490995D02*
Y508795D01*
G01X471447Y508355D02*
X472913Y509821D01*
G01X470387Y508795D02*
X471853Y510261D01*
G01X472913Y509821D02*
Y588034D01*
G01X471853Y510261D02*
Y576231D01*
G01X472913Y509821D02*
Y588034D01*
G01Y509821D02*
Y588034D01*
G01Y509821D02*
Y588034D01*
G01X454401Y478841D02*
Y483590D01*
G01X453341Y479281D02*
Y484030D01*
G01X454401Y483590D02*
X466050Y495239D01*
G01X453341Y484030D02*
X465150Y495840D01*
G01X466050Y495239D02*
X467490Y498717D01*
G01X465150Y495840D02*
X465951Y497774D01*
G01X466050Y495239D02*
X467490Y498717D01*
G01X465951Y497774D02*
X466342Y498717D01*
G01X466050Y495239D02*
X467490Y498717D01*
G01D02*
X467813Y499497D01*
G01X466342Y498717D02*
X466753Y499708D01*
G01X467813Y499497D02*
Y586915D01*
G01X466753Y499708D02*
Y563854D01*
G01X467813Y499497D02*
Y586915D01*
G01Y499497D02*
Y586915D01*
G01Y499497D02*
Y586915D01*
G01Y499497D02*
Y586915D01*
G01X458901Y479509D02*
Y480371D01*
G01X459961Y479069D02*
Y480811D01*
G01X458901Y480371D02*
X457895Y481377D01*
G01X459961Y480811D02*
X458955Y481817D01*
G01X457895Y481377D02*
Y483117D01*
G01X458955Y481817D02*
Y482677D01*
G01X457895Y483117D02*
X459503Y484725D01*
G01X458955Y482677D02*
X459943Y483665D01*
G01X459503Y484725D02*
X461243D01*
G01X459943Y483665D02*
X460803D01*
G01X461243Y484725D02*
X462249Y483719D01*
G01D02*
X463111D01*
G01X460803Y483665D02*
X461809Y482659D01*
G01X462249Y483719D02*
X463111D01*
G01X461809Y482659D02*
X463551D01*
G01X463111Y483719D02*
X464095Y484703D01*
G01X463551Y482659D02*
X465155Y484263D01*
G01X464095Y484703D02*
Y485565D01*
G01X465155Y484263D02*
Y486005D01*
G01X464095Y485565D02*
X462978Y486682D01*
G01X465155Y486005D02*
X464038Y487122D01*
G01X462978Y486682D02*
Y488381D01*
G01X464038Y487122D02*
Y487941D01*
G01X462978Y488381D02*
X464586Y489989D01*
G01X464038Y487941D02*
X465026Y488929D01*
G01X464586Y489989D02*
X466367D01*
G01X465026Y488929D02*
X465927D01*
G01X466367Y489989D02*
X467443Y488913D01*
G01X465927Y488929D02*
X467003Y487853D01*
G01X467443Y488913D02*
X468305D01*
G01X467003Y487853D02*
X468745D01*
G01X468305Y488913D02*
X470387Y490995D01*
G01X468745Y487853D02*
X471447Y490555D01*
G01X470387Y490995D02*
Y508795D01*
G01X471447Y490555D02*
Y508355D01*
G01X470387Y508795D02*
X471853Y510261D01*
G01X471447Y508355D02*
X472913Y509821D01*
G01X471853Y510261D02*
Y576231D01*
G01X472913Y509821D02*
Y588034D01*
G01X453341Y479281D02*
Y484030D01*
G01X454401Y478841D02*
Y483590D01*
G01X453341Y484030D02*
X465150Y495840D01*
G01X454401Y483590D02*
X466050Y495239D01*
G01X465150Y495840D02*
X465951Y497774D01*
G01D02*
X466342Y498717D01*
G01D02*
X466753Y499708D01*
G01X466050Y495239D02*
X467490Y498717D01*
G01X466342D02*
X466753Y499708D01*
G01X467490Y498717D02*
X467813Y499497D01*
G01X466753Y499708D02*
Y563854D01*
G01X467813Y499497D02*
Y586915D01*
G01X453341Y479281D02*
Y484030D01*
G01X454401Y478841D02*
Y483590D01*
G01X453341Y484030D02*
X465150Y495840D01*
G01X454401Y483590D02*
X466050Y495239D01*
G01X465150Y495840D02*
X465951Y497774D01*
G01D02*
X466342Y498717D01*
G01D02*
X466753Y499708D01*
G01X466050Y495239D02*
X467490Y498717D01*
G01X466342D02*
X466753Y499708D01*
G01X467490Y498717D02*
X467813Y499497D01*
G01X466753Y499708D02*
Y563854D01*
G01X467813Y499497D02*
Y586915D01*
G01X459961Y479069D02*
Y480811D01*
G01X458901Y479509D02*
Y480371D01*
G01X459961Y480811D02*
X458955Y481817D01*
G01X458901Y480371D02*
X457895Y481377D01*
G01X458955Y481817D02*
Y482677D01*
G01X457895Y481377D02*
Y483117D01*
G01X458955Y482677D02*
X459943Y483665D01*
G01X457895Y483117D02*
X459503Y484725D01*
G01X459943Y483665D02*
X460803D01*
G01X459503Y484725D02*
X461243D01*
G01X460803Y483665D02*
X461809Y482659D01*
G01X461243Y484725D02*
X462249Y483719D01*
G01X460803Y483665D02*
X461809Y482659D01*
G01D02*
X463551D01*
G01X462249Y483719D02*
X463111D01*
G01X463551Y482659D02*
X465155Y484263D01*
G01X463111Y483719D02*
X464095Y484703D01*
G01X465155Y484263D02*
Y486005D01*
G01X464095Y484703D02*
Y485565D01*
G01X465155Y486005D02*
X464038Y487122D01*
G01X464095Y485565D02*
X462978Y486682D01*
G01X464038Y487122D02*
Y487941D01*
G01X462978Y486682D02*
Y488381D01*
G01X464038Y487941D02*
X465026Y488929D01*
G01X462978Y488381D02*
X464586Y489989D01*
G01X465026Y488929D02*
X465927D01*
G01X464586Y489989D02*
X466367D01*
G01X465927Y488929D02*
X467003Y487853D01*
G01X466367Y489989D02*
X467443Y488913D01*
G01X467003Y487853D02*
X468745D01*
G01X467443Y488913D02*
X468305D01*
G01X468745Y487853D02*
X471447Y490555D01*
G01X468305Y488913D02*
X470387Y490995D01*
G01X471447Y490555D02*
Y508355D01*
G01X470387Y490995D02*
Y508795D01*
G01X471447Y508355D02*
X472913Y509821D01*
G01X470387Y508795D02*
X471853Y510261D01*
G01X472913Y509821D02*
Y588034D01*
G01X471853Y510261D02*
Y576231D01*
G01X472913Y509821D02*
Y588034D01*
G01Y509821D02*
Y588034D01*
G01Y509821D02*
Y588034D01*
G01X454401Y478841D02*
Y483590D01*
G01X453341Y479281D02*
Y484030D01*
G01X454401Y483590D02*
X466050Y495239D01*
G01X453341Y484030D02*
X465150Y495840D01*
G01X466050Y495239D02*
X467490Y498717D01*
G01X465150Y495840D02*
X465951Y497774D01*
G01X466050Y495239D02*
X467490Y498717D01*
G01X465951Y497774D02*
X466342Y498717D01*
G01X466050Y495239D02*
X467490Y498717D01*
G01D02*
X467813Y499497D01*
G01X466342Y498717D02*
X466753Y499708D01*
G01X467813Y499497D02*
Y586915D01*
G01X466753Y499708D02*
Y563854D01*
G01X467813Y499497D02*
Y586915D01*
G01Y499497D02*
Y586915D01*
G01Y499497D02*
Y586915D01*
G01Y499497D02*
Y586915D01*
G01X458901Y479509D02*
Y480371D01*
G01X459961Y479069D02*
Y480811D01*
G01X458901Y480371D02*
X457895Y481377D01*
G01X459961Y480811D02*
X458955Y481817D01*
G01X457895Y481377D02*
Y483117D01*
G01X458955Y481817D02*
Y482677D01*
G01X457895Y483117D02*
X459503Y484725D01*
G01X458955Y482677D02*
X459943Y483665D01*
G01X459503Y484725D02*
X461243D01*
G01X459943Y483665D02*
X460803D01*
G01X461243Y484725D02*
X462249Y483719D01*
G01D02*
X463111D01*
G01X460803Y483665D02*
X461809Y482659D01*
G01X462249Y483719D02*
X463111D01*
G01X461809Y482659D02*
X463551D01*
G01X463111Y483719D02*
X464095Y484703D01*
G01X463551Y482659D02*
X465155Y484263D01*
G01X464095Y484703D02*
Y485565D01*
G01X465155Y484263D02*
Y486005D01*
G01X464095Y485565D02*
X462978Y486682D01*
G01X465155Y486005D02*
X464038Y487122D01*
G01X462978Y486682D02*
Y488381D01*
G01X464038Y487122D02*
Y487941D01*
G01X462978Y488381D02*
X464586Y489989D01*
G01X464038Y487941D02*
X465026Y488929D01*
G01X464586Y489989D02*
X466367D01*
G01X465026Y488929D02*
X465927D01*
G01X466367Y489989D02*
X467443Y488913D01*
G01X465927Y488929D02*
X467003Y487853D01*
G01X467443Y488913D02*
X468305D01*
G01X467003Y487853D02*
X468745D01*
G01X468305Y488913D02*
X470387Y490995D01*
G01X468745Y487853D02*
X471447Y490555D01*
G01X470387Y490995D02*
Y508795D01*
G01X471447Y490555D02*
Y508355D01*
G01X470387Y508795D02*
X471853Y510261D01*
G01X471447Y508355D02*
X472913Y509821D01*
G01X471853Y510261D02*
Y576231D01*
G01X472913Y509821D02*
Y588034D01*
G01X466753Y565758D02*
Y576050D01*
G01Y578038D02*
Y579164D01*
G01Y581404D02*
Y582404D01*
G01Y584644D02*
Y586474D01*
G01D02*
X464927Y588300D01*
G01X467813Y586915D02*
X466733Y587995D01*
G01X471853Y578471D02*
Y579471D01*
G01Y581711D02*
Y582711D01*
G01Y584951D02*
Y587594D01*
G01X472913Y588034D02*
X469833Y591114D01*
G01X471853Y587594D02*
X470933Y588514D01*
G01X466753Y565758D02*
Y576050D01*
G01Y578038D02*
Y579164D01*
G01Y581404D02*
Y582404D01*
G01Y584644D02*
Y586474D01*
G01X467813Y586915D02*
X466733Y587995D01*
G01X466753Y586474D02*
X464927Y588300D01*
G01X471853Y578471D02*
Y579471D01*
G01Y581711D02*
Y582711D01*
G01Y584951D02*
Y587594D01*
G01D02*
X470933Y588514D01*
G01X472913Y588034D02*
X469833Y591114D01*
G01X466753Y565758D02*
Y576050D01*
G01Y578038D02*
Y579164D01*
G01Y581404D02*
Y582404D01*
G01Y584644D02*
Y586474D01*
G01D02*
X464927Y588300D01*
G01X467813Y586915D02*
X466733Y587995D01*
G01X466753Y565758D02*
Y576050D01*
G01Y578038D02*
Y579164D01*
G01Y581404D02*
Y582404D01*
G01Y584644D02*
Y586474D01*
G01D02*
X464927Y588300D01*
G01X467813Y586915D02*
X466733Y587995D01*
G01X471853Y578471D02*
Y579471D01*
G01Y581711D02*
Y582711D01*
G01Y584951D02*
Y587594D01*
G01X472913Y588034D02*
X469833Y591114D01*
G01X471853Y587594D02*
X470933Y588514D01*
G01X466753Y565758D02*
Y576050D01*
G01Y578038D02*
Y579164D01*
G01Y581404D02*
Y582404D01*
G01Y584644D02*
Y586474D01*
G01X467813Y586915D02*
X466733Y587995D01*
G01X466753Y586474D02*
X464927Y588300D01*
G01X471853Y578471D02*
Y579471D01*
G01Y581711D02*
Y582711D01*
G01Y584951D02*
Y587594D01*
G01D02*
X470933Y588514D01*
G01X472913Y588034D02*
X469833Y591114D01*
G01X462745Y590000D02*
Y608012D01*
G01X463805Y595890D02*
Y597260D01*
G01X462745Y590000D02*
Y608012D01*
G01X463805Y600940D02*
Y602360D01*
G01X469029Y595500D02*
X468358Y596171D01*
G01X468127Y594901D02*
X467298Y595730D01*
G01X468358Y596171D02*
Y597448D01*
G01Y600938D02*
Y601829D01*
G01X467298Y595730D02*
Y602270D01*
G01X468358Y601829D02*
X469129Y602600D01*
G01X467298Y602270D02*
X468127Y603099D01*
G01X463805Y595890D02*
Y597260D01*
G01Y600940D02*
Y602360D01*
G01X462745Y590000D02*
Y608012D01*
G01X468127Y594901D02*
X467298Y595730D01*
G01X469029Y595500D02*
X468358Y596171D01*
G01X467298Y595730D02*
Y602270D01*
G01X468358Y596171D02*
Y597448D01*
G01X467298Y595730D02*
Y602270D01*
G01X468358Y600938D02*
Y601829D01*
G01X467298Y602270D02*
X468127Y603099D01*
G01X468358Y601829D02*
X469129Y602600D01*
G01X462745Y590000D02*
Y608012D01*
G01X463805Y595890D02*
Y597260D01*
G01X462745Y590000D02*
Y608012D01*
G01X463805Y600940D02*
Y602360D01*
G01X462745Y590000D02*
Y608012D01*
G01X463805Y595890D02*
Y597260D01*
G01X462745Y590000D02*
Y608012D01*
G01X463805Y600940D02*
Y602360D01*
G01X469029Y595500D02*
X468358Y596171D01*
G01X468127Y594901D02*
X467298Y595730D01*
G01X468358Y596171D02*
Y597448D01*
G01Y600938D02*
Y601829D01*
G01X467298Y595730D02*
Y602270D01*
G01X468358Y601829D02*
X469129Y602600D01*
G01X467298Y602270D02*
X468127Y603099D01*
G01X463805Y595890D02*
Y597260D01*
G01Y600940D02*
Y602360D01*
G01X462745Y590000D02*
Y608012D01*
G01X468127Y594901D02*
X467298Y595730D01*
G01X469029Y595500D02*
X468358Y596171D01*
G01X467298Y595730D02*
Y602270D01*
G01X468358Y596171D02*
Y597448D01*
G01X467298Y595730D02*
Y602270D01*
G01X468358Y600938D02*
Y601829D01*
G01X467298Y602270D02*
X468127Y603099D01*
G01X468358Y601829D02*
X469129Y602600D01*
G01X539454Y11700D02*
X540401Y10753D01*
G01X538355Y14300D02*
X541461Y11194D01*
G01X540401Y-4509D02*
X539690Y-5220D01*
G01D02*
X539174D01*
G01X540133Y-6280D02*
X539151D01*
G01X540375Y25753D02*
X536501Y21879D01*
G01X541435Y25310D02*
X537561Y21436D01*
G01X536501Y21879D02*
Y13554D01*
G01X537561Y21436D02*
Y19620D01*
G01X538355Y14300D02*
X541461Y11194D01*
G01X539454Y11700D02*
X540401Y10753D01*
G01Y-4509D02*
X539690Y-5220D01*
G01X540133Y-6280D02*
X539151D01*
G01X539690Y-5220D02*
X539174D01*
G01X541435Y25310D02*
X537561Y21436D01*
G01X540375Y25753D02*
X536501Y21879D01*
G01X537561Y21436D02*
Y19620D01*
G01X536501Y21879D02*
Y13554D01*
G01X502879Y32580D02*
X503590Y33291D01*
G01X504650Y32848D02*
X503322Y31520D01*
G01X502362Y32580D02*
X502879D01*
G01X503322Y31520D02*
X502339D01*
G01X503322D02*
X502339D01*
G01X502362Y32580D02*
X502879D01*
G01X504650Y32848D02*
X503322Y31520D01*
G01X502879Y32580D02*
X503590Y33291D01*
G01X506644Y30540D02*
X509836Y33732D01*
G01X501544Y11700D02*
X502643D01*
G01D02*
X503590Y10753D01*
G01X501544Y14300D02*
X504650Y11194D01*
G01X503590Y10753D02*
Y8220D01*
G01Y4080D02*
Y3120D01*
G01Y-1220D02*
Y-4509D01*
G01X504650Y11194D02*
Y-4952D01*
G01X503590Y-4509D02*
X502879Y-5220D01*
G01X504650Y-4952D02*
X503322Y-6280D01*
G01X502879Y-5220D02*
X502363D01*
G01X503322Y-6280D02*
X502340D01*
G01X539454Y11700D02*
X540401Y10753D01*
G01X538355Y14300D02*
X541461Y11194D01*
G01X540401Y-4509D02*
X539690Y-5220D01*
G01D02*
X539174D01*
G01X540133Y-6280D02*
X539151D01*
G01X540375Y25753D02*
X536501Y21879D01*
G01X541435Y25310D02*
X537561Y21436D01*
G01X536501Y21879D02*
Y13554D01*
G01X537561Y21436D02*
Y19620D01*
G01X506644Y11915D02*
X507742D01*
G01D02*
X508776Y10881D01*
G01X506644Y14514D02*
X509836Y11322D01*
G01X508776Y10881D02*
Y8106D01*
G01Y4280D02*
Y2907D01*
G01Y-1007D02*
Y-3628D01*
G01X509836Y11322D02*
Y-4068D01*
G01X508776Y-3628D02*
X507753Y-4651D01*
G01D02*
X506644D01*
G01X509836Y-4068D02*
X506644Y-7260D01*
G01X501544Y14300D02*
X504650Y11194D01*
G01X501544Y11700D02*
X502643D01*
G01X501544Y14300D02*
X504650Y11194D01*
G01X502643Y11700D02*
X503590Y10753D01*
G01X504650Y11194D02*
Y-4952D01*
G01X503590Y10753D02*
Y8220D01*
G01X504650Y11194D02*
Y-4952D01*
G01X503590Y4080D02*
Y3120D01*
G01X504650Y11194D02*
Y-4952D01*
G01X503590Y-1220D02*
Y-4509D01*
G01X504650Y-4952D02*
X503322Y-6280D01*
G01X503590Y-4509D02*
X502879Y-5220D01*
G01X503322Y-6280D02*
X502340D01*
G01X502879Y-5220D02*
X502363D01*
G01X538355Y14300D02*
X541461Y11194D01*
G01X539454Y11700D02*
X540401Y10753D01*
G01Y-4509D02*
X539690Y-5220D01*
G01X540133Y-6280D02*
X539151D01*
G01X539690Y-5220D02*
X539174D01*
G01X541435Y25310D02*
X537561Y21436D01*
G01X540375Y25753D02*
X536501Y21879D01*
G01X537561Y21436D02*
Y19620D01*
G01X536501Y21879D02*
Y13554D01*
G01X506644Y14514D02*
X509836Y11322D01*
G01X506644Y11915D02*
X507742D01*
G01X506644Y14514D02*
X509836Y11322D01*
G01X507742Y11915D02*
X508776Y10881D01*
G01X509836Y11322D02*
Y-4068D01*
G01X508776Y10881D02*
Y8106D01*
G01X509836Y11322D02*
Y-4068D01*
G01X508776Y4280D02*
Y2907D01*
G01X509836Y11322D02*
Y-4068D01*
G01X508776Y-1007D02*
Y-3628D01*
G01X509836Y-4068D02*
X506644Y-7260D01*
G01X508776Y-3628D02*
X507753Y-4651D01*
G01X509836Y-4068D02*
X506644Y-7260D01*
G01X507753Y-4651D02*
X506644D01*
G01X502879Y32580D02*
X503590Y33291D01*
G01X504650Y32848D02*
X503322Y31520D01*
G01X502362Y32580D02*
X502879D01*
G01X503322Y31520D02*
X502339D01*
G01X506644Y30540D02*
X509836Y33732D01*
G01X506644Y30540D02*
X509836Y33732D01*
G01X506644Y30540D02*
X509836Y33732D01*
G01X506644Y30540D02*
X509836Y33732D01*
G01X506644Y30540D02*
X509836Y33732D01*
G01X506644Y30540D02*
X509836Y33732D01*
G01X503322Y31520D02*
X502339D01*
G01X502362Y32580D02*
X502879D01*
G01X504650Y32848D02*
X503322Y31520D01*
G01X502879Y32580D02*
X503590Y33291D01*
G01X503322Y31520D02*
X502339D01*
G01X502362Y32580D02*
X502879D01*
G01X504650Y32848D02*
X503322Y31520D01*
G01X502879Y32580D02*
X503590Y33291D01*
G01X506644Y30540D02*
X509836Y33732D01*
G01X503501Y105934D02*
Y84109D01*
G01X504561Y107497D02*
Y83669D01*
G01X503501Y84109D02*
X502532Y83140D01*
G01X504561Y83669D02*
X503592Y82700D01*
G01X502532Y83140D02*
Y75561D01*
G01X503592Y82700D02*
Y76001D01*
G01X502532Y75561D02*
X503501Y74592D01*
G01X503592Y76001D02*
X504561Y75032D01*
G01X503501Y74592D02*
Y62609D01*
G01X504561Y75032D02*
Y62169D01*
G01X503501Y62609D02*
X501501Y60609D01*
G01X504561Y62169D02*
X502561Y60169D01*
G01X501501Y60609D02*
Y57320D01*
G01X502561Y60169D02*
Y56781D01*
G01X503590Y48552D02*
X502642Y49500D01*
G01X501543Y52100D02*
X504650Y48993D01*
G01X503590Y33291D02*
Y36580D01*
G01Y40920D02*
Y41880D01*
G01Y46020D02*
Y48552D01*
G01X504650Y48993D02*
Y32848D01*
G01X504561Y107497D02*
Y83669D01*
G01X503501Y105934D02*
Y84109D01*
G01X504561Y83669D02*
X503592Y82700D01*
G01X503501Y84109D02*
X502532Y83140D01*
G01X503592Y82700D02*
Y76001D01*
G01X502532Y83140D02*
Y75561D01*
G01X503592Y76001D02*
X504561Y75032D01*
G01X502532Y75561D02*
X503501Y74592D01*
G01X504561Y75032D02*
Y62169D01*
G01X503501Y74592D02*
Y62609D01*
G01X504561Y62169D02*
X502561Y60169D01*
G01X503501Y62609D02*
X501501Y60609D01*
G01X502561Y60169D02*
Y56781D01*
G01X501501Y60609D02*
Y57320D01*
G01X504650Y48993D02*
Y32848D01*
G01X503590Y33291D02*
Y36580D01*
G01X504650Y48993D02*
Y32848D01*
G01X503590Y40920D02*
Y41880D01*
G01X504650Y48993D02*
Y32848D01*
G01X503590Y46020D02*
Y48552D01*
G01X501543Y52100D02*
X504650Y48993D01*
G01X503590Y48552D02*
X502642Y49500D01*
G01X506701Y57520D02*
Y58192D01*
G01X507761Y56620D02*
Y57749D01*
G01X506701Y58192D02*
X508601Y60092D01*
G01X507761Y57749D02*
X509661Y59649D01*
G01X508601Y60092D02*
Y105698D01*
G01X509661Y59649D02*
Y107247D01*
G01X506643Y33149D02*
X507753D01*
G01D02*
X508776Y34172D01*
G01D02*
Y36793D01*
G01Y40707D02*
Y42080D01*
G01Y45906D02*
Y48681D01*
G01X509836Y33732D02*
Y49121D01*
G01X508776Y48681D02*
X507742Y49715D01*
G01X509836Y49121D02*
X506643Y52314D01*
G01X503501Y105934D02*
Y84109D01*
G01X504561Y107497D02*
Y83669D01*
G01X503501Y84109D02*
X502532Y83140D01*
G01X504561Y83669D02*
X503592Y82700D01*
G01X502532Y83140D02*
Y75561D01*
G01X503592Y82700D02*
Y76001D01*
G01X502532Y75561D02*
X503501Y74592D01*
G01X503592Y76001D02*
X504561Y75032D01*
G01X503501Y74592D02*
Y62609D01*
G01X504561Y75032D02*
Y62169D01*
G01X503501Y62609D02*
X501501Y60609D01*
G01X504561Y62169D02*
X502561Y60169D01*
G01X501501Y60609D02*
Y57320D01*
G01X502561Y60169D02*
Y56781D01*
G01X503590Y48552D02*
X502642Y49500D01*
G01X501543Y52100D02*
X504650Y48993D01*
G01X503590Y33291D02*
Y36580D01*
G01Y40920D02*
Y41880D01*
G01Y46020D02*
Y48552D01*
G01X504650Y48993D02*
Y32848D01*
G01X507761Y56620D02*
Y57749D01*
G01X506701Y57520D02*
Y58192D01*
G01X507761Y57749D02*
X509661Y59649D01*
G01X506701Y58192D02*
X508601Y60092D01*
G01X509661Y59649D02*
Y107247D01*
G01X508601Y60092D02*
Y105698D01*
G01X506643Y33149D02*
X507753D01*
G01D02*
X508776Y34172D01*
G01X509836Y33732D02*
Y49121D01*
G01X508776Y34172D02*
Y36793D01*
G01X509836Y33732D02*
Y49121D01*
G01X508776Y40707D02*
Y42080D01*
G01X509836Y33732D02*
Y49121D01*
G01X508776Y45906D02*
Y48681D01*
G01X509836Y49121D02*
X506643Y52314D01*
G01X508776Y48681D02*
X507742Y49715D01*
G01X507761Y56620D02*
Y57749D01*
G01X506701Y57520D02*
Y58192D01*
G01X507761Y57749D02*
X509661Y59649D01*
G01X506701Y58192D02*
X508601Y60092D01*
G01X509661Y59649D02*
Y107247D01*
G01X508601Y60092D02*
Y105698D01*
G01X506643Y33149D02*
X507753D01*
G01D02*
X508776Y34172D01*
G01X509836Y33732D02*
Y49121D01*
G01X508776Y34172D02*
Y36793D01*
G01X509836Y33732D02*
Y49121D01*
G01X508776Y40707D02*
Y42080D01*
G01X509836Y33732D02*
Y49121D01*
G01X508776Y45906D02*
Y48681D01*
G01X509836Y49121D02*
X506643Y52314D01*
G01X508776Y48681D02*
X507742Y49715D01*
G01X507761Y56620D02*
Y57749D01*
G01X506701Y57520D02*
Y58192D01*
G01X507761Y57749D02*
X509661Y59649D01*
G01X506701Y58192D02*
X508601Y60092D01*
G01X509661Y59649D02*
Y107247D01*
G01X508601Y60092D02*
Y105698D01*
G01X506643Y33149D02*
X507753D01*
G01D02*
X508776Y34172D01*
G01X509836Y33732D02*
Y49121D01*
G01X508776Y34172D02*
Y36793D01*
G01X509836Y33732D02*
Y49121D01*
G01X508776Y40707D02*
Y42080D01*
G01X509836Y33732D02*
Y49121D01*
G01X508776Y45906D02*
Y48681D01*
G01X509836Y49121D02*
X506643Y52314D01*
G01X508776Y48681D02*
X507742Y49715D01*
G01X504561Y107497D02*
Y83669D01*
G01X503501Y105934D02*
Y84109D01*
G01X504561Y83669D02*
X503592Y82700D01*
G01X503501Y84109D02*
X502532Y83140D01*
G01X503592Y82700D02*
Y76001D01*
G01X502532Y83140D02*
Y75561D01*
G01X503592Y76001D02*
X504561Y75032D01*
G01X502532Y75561D02*
X503501Y74592D01*
G01X504561Y75032D02*
Y62169D01*
G01X503501Y74592D02*
Y62609D01*
G01X504561Y62169D02*
X502561Y60169D01*
G01X503501Y62609D02*
X501501Y60609D01*
G01X502561Y60169D02*
Y56781D01*
G01X501501Y60609D02*
Y57320D01*
G01X504650Y48993D02*
Y32848D01*
G01X503590Y33291D02*
Y36580D01*
G01X504650Y48993D02*
Y32848D01*
G01X503590Y40920D02*
Y41880D01*
G01X504650Y48993D02*
Y32848D01*
G01X503590Y46020D02*
Y48552D01*
G01X501543Y52100D02*
X504650Y48993D01*
G01X503590Y48552D02*
X502642Y49500D01*
G01X504561Y107497D02*
Y83669D01*
G01X503501Y105934D02*
Y84109D01*
G01X504561Y83669D02*
X503592Y82700D01*
G01X503501Y84109D02*
X502532Y83140D01*
G01X503592Y82700D02*
Y76001D01*
G01X502532Y83140D02*
Y75561D01*
G01X503592Y76001D02*
X504561Y75032D01*
G01X502532Y75561D02*
X503501Y74592D01*
G01X504561Y75032D02*
Y62169D01*
G01X503501Y74592D02*
Y62609D01*
G01X504561Y62169D02*
X502561Y60169D01*
G01X503501Y62609D02*
X501501Y60609D01*
G01X502561Y60169D02*
Y56781D01*
G01X501501Y60609D02*
Y57320D01*
G01X504650Y48993D02*
Y32848D01*
G01X503590Y33291D02*
Y36580D01*
G01X504650Y48993D02*
Y32848D01*
G01X503590Y40920D02*
Y41880D01*
G01X504650Y48993D02*
Y32848D01*
G01X503590Y46020D02*
Y48552D01*
G01X501543Y52100D02*
X504650Y48993D01*
G01X503590Y48552D02*
X502642Y49500D01*
G01X506701Y57520D02*
Y58192D01*
G01X507761Y56620D02*
Y57749D01*
G01X506701Y58192D02*
X508601Y60092D01*
G01X507761Y57749D02*
X509661Y59649D01*
G01X508601Y60092D02*
Y105698D01*
G01X509661Y59649D02*
Y107247D01*
G01X506643Y33149D02*
X507753D01*
G01D02*
X508776Y34172D01*
G01D02*
Y36793D01*
G01Y40707D02*
Y42080D01*
G01Y45906D02*
Y48681D01*
G01X509836Y33732D02*
Y49121D01*
G01X508776Y48681D02*
X507742Y49715D01*
G01X509836Y49121D02*
X506643Y52314D01*
G01X488989Y137620D02*
X496608D01*
G01X489429Y138680D02*
X497048D01*
G01X496608Y137620D02*
X497244Y136984D01*
G01X497048Y138680D02*
X498304Y137424D01*
G01X497244Y136984D02*
Y135466D01*
G01X498304Y137424D02*
Y135906D01*
G01X497244Y135466D02*
X498990Y133720D01*
G01X498304Y135906D02*
X499430Y134780D01*
G01X498990Y133720D02*
X502871D01*
G01X499430Y134780D02*
X502431D01*
G01X502871Y133720D02*
X504360Y135209D01*
G01X502431Y134780D02*
X503300Y135649D01*
G01X504360Y135209D02*
Y136748D01*
G01X503300Y135649D02*
Y137191D01*
G01X504360Y136748D02*
X505232Y137620D01*
G01X503300Y137191D02*
X504789Y138680D01*
G01X505232Y137620D02*
X507728D01*
G01X504789Y138680D02*
X508171D01*
G01X507728Y137620D02*
X508600Y136748D01*
G01X508171Y138680D02*
X509660Y137191D01*
G01X508600Y136748D02*
Y135209D01*
G01X509660Y137191D02*
Y135652D01*
G01X508600Y135209D02*
X510089Y133720D01*
G01X509660Y135652D02*
X510532Y134780D01*
G01X510089Y133720D02*
X513840D01*
G01X510532Y134780D02*
X513400D01*
G01X513840Y133720D02*
X514960Y134840D01*
G01X513400Y134780D02*
X513900Y135280D01*
G01X514960Y134840D02*
Y137119D01*
G01X513900Y135280D02*
Y137559D01*
G01X514960Y137119D02*
X515461Y137620D01*
G01X513900Y137559D02*
X515021Y138680D01*
G01X515461Y137620D02*
X518143D01*
G01X515021Y138680D02*
X518583D01*
G01X518143Y137620D02*
X540375Y115388D01*
G01X518583Y138680D02*
X541435Y115828D01*
G01X490589Y141420D02*
X520140D01*
G01X491029Y142480D02*
X520583D01*
G01X520140Y141420D02*
X545612Y115948D01*
G01X520583Y142480D02*
X546672Y116391D01*
G01X489429Y138680D02*
X497048D01*
G01X488989Y137620D02*
X496608D01*
G01X497048Y138680D02*
X498304Y137424D01*
G01X496608Y137620D02*
X497244Y136984D01*
G01X498304Y137424D02*
Y135906D01*
G01X497244Y136984D02*
Y135466D01*
G01X498304Y135906D02*
X499430Y134780D01*
G01X497244Y135466D02*
X498990Y133720D01*
G01X499430Y134780D02*
X502431D01*
G01X498990Y133720D02*
X502871D01*
G01X502431Y134780D02*
X503300Y135649D01*
G01X502871Y133720D02*
X504360Y135209D01*
G01X503300Y135649D02*
Y137191D01*
G01X504360Y135209D02*
Y136748D01*
G01X503300Y137191D02*
X504789Y138680D01*
G01X504360Y136748D02*
X505232Y137620D01*
G01X504789Y138680D02*
X508171D01*
G01X505232Y137620D02*
X507728D01*
G01X508171Y138680D02*
X509660Y137191D01*
G01X507728Y137620D02*
X508600Y136748D01*
G01X509660Y137191D02*
Y135652D01*
G01X508600Y136748D02*
Y135209D01*
G01X509660Y135652D02*
X510532Y134780D01*
G01X508600Y135209D02*
X510089Y133720D01*
G01X510532Y134780D02*
X513400D01*
G01X510089Y133720D02*
X513840D01*
G01X513400Y134780D02*
X513900Y135280D01*
G01X513840Y133720D02*
X514960Y134840D01*
G01X513900Y135280D02*
Y137559D01*
G01X514960Y134840D02*
Y137119D01*
G01X513900Y137559D02*
X515021Y138680D01*
G01X514960Y137119D02*
X515461Y137620D01*
G01X515021Y138680D02*
X518583D01*
G01X515461Y137620D02*
X518143D01*
G01X518583Y138680D02*
X541435Y115828D01*
G01X518143Y137620D02*
X540375Y115388D01*
G01X491029Y142480D02*
X520583D01*
G01X490589Y141420D02*
X520140D01*
G01X520583Y142480D02*
X546672Y116391D01*
G01X520140Y141420D02*
X545612Y115948D01*
G01X488989Y137620D02*
X496608D01*
G01X489429Y138680D02*
X497048D01*
G01X496608Y137620D02*
X497244Y136984D01*
G01X497048Y138680D02*
X498304Y137424D01*
G01X497244Y136984D02*
Y135466D01*
G01X498304Y137424D02*
Y135906D01*
G01X497244Y135466D02*
X498990Y133720D01*
G01X498304Y135906D02*
X499430Y134780D01*
G01X498990Y133720D02*
X502871D01*
G01X499430Y134780D02*
X502431D01*
G01X502871Y133720D02*
X504360Y135209D01*
G01X502431Y134780D02*
X503300Y135649D01*
G01X504360Y135209D02*
Y136748D01*
G01X503300Y135649D02*
Y137191D01*
G01X504360Y136748D02*
X505232Y137620D01*
G01X503300Y137191D02*
X504789Y138680D01*
G01X505232Y137620D02*
X507728D01*
G01X504789Y138680D02*
X508171D01*
G01X507728Y137620D02*
X508600Y136748D01*
G01X508171Y138680D02*
X509660Y137191D01*
G01X508600Y136748D02*
Y135209D01*
G01X509660Y137191D02*
Y135652D01*
G01X508600Y135209D02*
X510089Y133720D01*
G01X509660Y135652D02*
X510532Y134780D01*
G01X510089Y133720D02*
X513840D01*
G01X510532Y134780D02*
X513400D01*
G01X513840Y133720D02*
X514960Y134840D01*
G01X513400Y134780D02*
X513900Y135280D01*
G01X514960Y134840D02*
Y137119D01*
G01X513900Y135280D02*
Y137559D01*
G01X514960Y137119D02*
X515461Y137620D01*
G01X513900Y137559D02*
X515021Y138680D01*
G01X515461Y137620D02*
X518143D01*
G01X515021Y138680D02*
X518583D01*
G01X518143Y137620D02*
X540375Y115388D01*
G01X518583Y138680D02*
X541435Y115828D01*
G01X489429Y138680D02*
X497048D01*
G01X488989Y137620D02*
X496608D01*
G01X497048Y138680D02*
X498304Y137424D01*
G01X496608Y137620D02*
X497244Y136984D01*
G01X498304Y137424D02*
Y135906D01*
G01X497244Y136984D02*
Y135466D01*
G01X498304Y135906D02*
X499430Y134780D01*
G01X497244Y135466D02*
X498990Y133720D01*
G01X499430Y134780D02*
X502431D01*
G01X498990Y133720D02*
X502871D01*
G01X502431Y134780D02*
X503300Y135649D01*
G01X502871Y133720D02*
X504360Y135209D01*
G01X503300Y135649D02*
Y137191D01*
G01X504360Y135209D02*
Y136748D01*
G01X503300Y137191D02*
X504789Y138680D01*
G01X504360Y136748D02*
X505232Y137620D01*
G01X504789Y138680D02*
X508171D01*
G01X505232Y137620D02*
X507728D01*
G01X508171Y138680D02*
X509660Y137191D01*
G01X507728Y137620D02*
X508600Y136748D01*
G01X509660Y137191D02*
Y135652D01*
G01X508600Y136748D02*
Y135209D01*
G01X509660Y135652D02*
X510532Y134780D01*
G01X508600Y135209D02*
X510089Y133720D01*
G01X510532Y134780D02*
X513400D01*
G01X510089Y133720D02*
X513840D01*
G01X513400Y134780D02*
X513900Y135280D01*
G01X513840Y133720D02*
X514960Y134840D01*
G01X513900Y135280D02*
Y137559D01*
G01X514960Y134840D02*
Y137119D01*
G01X513900Y137559D02*
X515021Y138680D01*
G01X514960Y137119D02*
X515461Y137620D01*
G01X515021Y138680D02*
X518583D01*
G01X515461Y137620D02*
X518143D01*
G01X518583Y138680D02*
X541435Y115828D01*
G01X518143Y137620D02*
X540375Y115388D01*
G01X490589Y141420D02*
X520140D01*
G01X491029Y142480D02*
X520583D01*
G01X520140Y141420D02*
X545612Y115948D01*
G01X520583Y142480D02*
X546672Y116391D01*
G01X491029Y142480D02*
X520583D01*
G01X490589Y141420D02*
X520140D01*
G01X520583Y142480D02*
X546672Y116391D01*
G01X520140Y141420D02*
X545612Y115948D01*
G01X486542Y195950D02*
X487389Y195103D01*
G01X488734Y193758D02*
X489441Y193051D01*
G01X490856Y191636D02*
X491563Y190929D01*
G01X492978Y189514D02*
X493685Y188807D01*
G01X495100Y187392D02*
X496432Y186060D01*
G01X485792Y195200D02*
X495992Y185000D01*
G01X496432Y186060D02*
X497432D01*
G01X499432D02*
X500492D01*
G01X502492D02*
X503992D01*
G01X505992D02*
X509232D01*
G01X495992Y185000D02*
X508792D01*
G01X509232Y186060D02*
X510134Y185158D01*
G01X511550Y183742D02*
X512384Y182908D01*
G01X513800Y181492D02*
X514507Y180785D01*
G01X508792Y185000D02*
X513757Y180035D01*
G01X514507Y180783D02*
X533192Y162100D01*
G01X513757Y180033D02*
X532752Y161040D01*
G01X533192Y162100D02*
X537392D01*
G01X532752Y161040D02*
X536952D01*
G01X537392Y162100D02*
X575972Y123520D01*
G01X536952Y161040D02*
X574912Y123080D01*
G01X485792Y195200D02*
X495992Y185000D01*
G01X486542Y195950D02*
X487389Y195103D01*
G01X485792Y195200D02*
X495992Y185000D01*
G01X488734Y193758D02*
X489441Y193051D01*
G01X485792Y195200D02*
X495992Y185000D01*
G01X490856Y191636D02*
X491563Y190929D01*
G01X485792Y195200D02*
X495992Y185000D01*
G01X492978Y189514D02*
X493685Y188807D01*
G01X485792Y195200D02*
X495992Y185000D01*
G01X495100Y187392D02*
X496432Y186060D01*
G01X495992Y185000D02*
X508792D01*
G01X496432Y186060D02*
X497432D01*
G01X495992Y185000D02*
X508792D01*
G01X499432Y186060D02*
X500492D01*
G01X495992Y185000D02*
X508792D01*
G01X502492Y186060D02*
X503992D01*
G01X495992Y185000D02*
X508792D01*
G01X505992Y186060D02*
X509232D01*
G01X508792Y185000D02*
X513757Y180035D01*
G01X509232Y186060D02*
X510134Y185158D01*
G01X508792Y185000D02*
X513757Y180035D01*
G01X511550Y183742D02*
X512384Y182908D01*
G01X508792Y185000D02*
X513757Y180035D01*
G01X513800Y181492D02*
X514507Y180785D01*
G01X513757Y180033D02*
X532752Y161040D01*
G01X514507Y180783D02*
X533192Y162100D01*
G01X532752Y161040D02*
X536952D01*
G01X533192Y162100D02*
X537392D01*
G01X536952Y161040D02*
X574912Y123080D01*
G01X537392Y162100D02*
X575972Y123520D01*
G01X487042Y199650D02*
X496547Y190145D01*
G01X487792Y200400D02*
X496987Y191205D01*
G01X496547Y190145D02*
X498210D01*
G01X500110D02*
X501947D01*
G01X503847D02*
X508647D01*
G01X496987Y191205D02*
X509087D01*
G01X508647Y190145D02*
X534292Y164500D01*
G01X509087Y191205D02*
X534732Y165560D01*
G01X534292Y164500D02*
X537892D01*
G01X534732Y165560D02*
X538332D01*
G01X537892Y164500D02*
X582286Y120106D01*
G01X538332Y165560D02*
X583346Y120546D01*
G01X487792Y200400D02*
X496987Y191205D01*
G01X487042Y199650D02*
X496547Y190145D01*
G01X496987Y191205D02*
X509087D01*
G01X496547Y190145D02*
X498210D01*
G01X496987Y191205D02*
X509087D01*
G01X500110Y190145D02*
X501947D01*
G01X496987Y191205D02*
X509087D01*
G01X503847Y190145D02*
X508647D01*
G01X509087Y191205D02*
X534732Y165560D01*
G01X508647Y190145D02*
X534292Y164500D01*
G01X534732Y165560D02*
X538332D01*
G01X534292Y164500D02*
X537892D01*
G01X538332Y165560D02*
X583346Y120546D01*
G01X537892Y164500D02*
X582286Y120106D01*
G01X485792Y195200D02*
X495992Y185000D01*
G01X486542Y195950D02*
X487389Y195103D01*
G01X485792Y195200D02*
X495992Y185000D01*
G01X488734Y193758D02*
X489441Y193051D01*
G01X485792Y195200D02*
X495992Y185000D01*
G01X490856Y191636D02*
X491563Y190929D01*
G01X485792Y195200D02*
X495992Y185000D01*
G01X492978Y189514D02*
X493685Y188807D01*
G01X485792Y195200D02*
X495992Y185000D01*
G01X495100Y187392D02*
X496432Y186060D01*
G01X495992Y185000D02*
X508792D01*
G01X496432Y186060D02*
X497432D01*
G01X495992Y185000D02*
X508792D01*
G01X499432Y186060D02*
X500492D01*
G01X495992Y185000D02*
X508792D01*
G01X502492Y186060D02*
X503992D01*
G01X495992Y185000D02*
X508792D01*
G01X505992Y186060D02*
X509232D01*
G01X508792Y185000D02*
X513757Y180035D01*
G01X509232Y186060D02*
X510134Y185158D01*
G01X508792Y185000D02*
X513757Y180035D01*
G01X511550Y183742D02*
X512384Y182908D01*
G01X508792Y185000D02*
X513757Y180035D01*
G01X513800Y181492D02*
X514507Y180785D01*
G01X513757Y180033D02*
X532752Y161040D01*
G01X514507Y180783D02*
X533192Y162100D01*
G01X532752Y161040D02*
X536952D01*
G01X533192Y162100D02*
X537392D01*
G01X536952Y161040D02*
X574912Y123080D01*
G01X537392Y162100D02*
X575972Y123520D01*
G01X487042Y199650D02*
X496547Y190145D01*
G01X487792Y200400D02*
X496987Y191205D01*
G01X496547Y190145D02*
X498210D01*
G01X500110D02*
X501947D01*
G01X503847D02*
X508647D01*
G01X496987Y191205D02*
X509087D01*
G01X508647Y190145D02*
X534292Y164500D01*
G01X509087Y191205D02*
X534732Y165560D01*
G01X534292Y164500D02*
X537892D01*
G01X534732Y165560D02*
X538332D01*
G01X537892Y164500D02*
X582286Y120106D01*
G01X538332Y165560D02*
X583346Y120546D01*
G01X486542Y195950D02*
X487389Y195103D01*
G01X488734Y193758D02*
X489441Y193051D01*
G01X490856Y191636D02*
X491563Y190929D01*
G01X492978Y189514D02*
X493685Y188807D01*
G01X495100Y187392D02*
X496432Y186060D01*
G01X485792Y195200D02*
X495992Y185000D01*
G01X496432Y186060D02*
X497432D01*
G01X499432D02*
X500492D01*
G01X502492D02*
X503992D01*
G01X505992D02*
X509232D01*
G01X495992Y185000D02*
X508792D01*
G01X509232Y186060D02*
X510134Y185158D01*
G01X511550Y183742D02*
X512384Y182908D01*
G01X513800Y181492D02*
X514507Y180785D01*
G01X508792Y185000D02*
X513757Y180035D01*
G01X514507Y180783D02*
X533192Y162100D01*
G01X513757Y180033D02*
X532752Y161040D01*
G01X533192Y162100D02*
X537392D01*
G01X532752Y161040D02*
X536952D01*
G01X537392Y162100D02*
X575972Y123520D01*
G01X536952Y161040D02*
X574912Y123080D01*
G01X487792Y200400D02*
X496987Y191205D01*
G01X487042Y199650D02*
X496547Y190145D01*
G01X496987Y191205D02*
X509087D01*
G01X496547Y190145D02*
X498210D01*
G01X496987Y191205D02*
X509087D01*
G01X500110Y190145D02*
X501947D01*
G01X496987Y191205D02*
X509087D01*
G01X503847Y190145D02*
X508647D01*
G01X509087Y191205D02*
X534732Y165560D01*
G01X508647Y190145D02*
X534292Y164500D01*
G01X534732Y165560D02*
X538332D01*
G01X534292Y164500D02*
X537892D01*
G01X538332Y165560D02*
X583346Y120546D01*
G01X537892Y164500D02*
X582286Y120106D01*
G01X491288Y411515D02*
Y412996D01*
G01X492348Y411515D02*
Y412556D01*
G01X491288Y412996D02*
X502422Y424130D01*
G01X492348Y412556D02*
X502862Y423070D01*
G01X502422Y424130D02*
X508756D01*
G01X502862Y423070D02*
X509196D01*
G01X508756Y424130D02*
X522459Y437833D01*
G01X509196Y423070D02*
X523519Y437393D01*
G01X522459Y437833D02*
Y444110D01*
G01X523519Y437393D02*
Y443670D01*
G01X522459Y444110D02*
X524229Y445880D01*
G01X523519Y443670D02*
X524669Y444820D01*
G01X524229Y445880D02*
X537500D01*
G01X524669Y444820D02*
X537940D01*
G01X537500Y445880D02*
X577186Y485566D01*
G01X537940Y444820D02*
X578246Y485126D01*
G01X496038Y410383D02*
Y411246D01*
G01X494978Y410383D02*
Y411686D01*
G01X496038Y411246D02*
X499852Y415060D01*
G01X494978Y411686D02*
X499412Y416120D01*
G01X499852Y415060D02*
X500948D01*
G01X499412Y416120D02*
X501388D01*
G01X500948Y415060D02*
X501751Y414257D01*
G01X501388Y416120D02*
X502191Y415317D01*
G01X501751Y414257D02*
X504010D01*
G01X502191Y415317D02*
X503570D01*
G01X504010Y414257D02*
X505612Y415859D01*
G01X503570Y415317D02*
X504552Y416299D01*
G01X505612Y415859D02*
Y419361D01*
G01X504552Y416299D02*
Y419801D01*
G01X505612Y419361D02*
X506291Y420040D01*
G01X504552Y419801D02*
X505851Y421100D01*
G01X506291Y420040D02*
X511084D01*
G01X505851Y421100D02*
X510644D01*
G01X511084Y420040D02*
X527231Y436187D01*
G01X510644Y421100D02*
X526171Y436627D01*
G01X527231Y436187D02*
Y441164D01*
G01X526171Y436627D02*
Y441604D01*
G01X527231Y441164D02*
X527813Y441746D01*
G01X526171Y441604D02*
X527373Y442806D01*
G01X527813Y441746D02*
X529203D01*
G01X527373Y442806D02*
X529643D01*
G01X529203Y441746D02*
X529841Y441108D01*
G01X529643Y442806D02*
X530901Y441548D01*
G01X529841Y441108D02*
Y438984D01*
G01X530901Y441548D02*
Y439424D01*
G01X529841Y438984D02*
X531159Y437666D01*
G01X530901Y439424D02*
X531599Y438726D01*
G01X531159Y437666D02*
X536037D01*
G01X531599Y438726D02*
X535597D01*
G01X536037Y437666D02*
X583346Y484975D01*
G01X535597Y438726D02*
X582286Y485415D01*
G01X492348Y411515D02*
Y412556D01*
G01X491288Y411515D02*
Y412996D01*
G01X492348Y412556D02*
X502862Y423070D01*
G01X491288Y412996D02*
X502422Y424130D01*
G01X502862Y423070D02*
X509196D01*
G01X502422Y424130D02*
X508756D01*
G01X509196Y423070D02*
X523519Y437393D01*
G01X508756Y424130D02*
X522459Y437833D01*
G01X523519Y437393D02*
Y443670D01*
G01X522459Y437833D02*
Y444110D01*
G01X523519Y443670D02*
X524669Y444820D01*
G01X522459Y444110D02*
X524229Y445880D01*
G01X524669Y444820D02*
X537940D01*
G01X524229Y445880D02*
X537500D01*
G01X537940Y444820D02*
X578246Y485126D01*
G01X537500Y445880D02*
X577186Y485566D01*
G01X494978Y410383D02*
Y411686D01*
G01X496038Y410383D02*
Y411246D01*
G01X494978Y411686D02*
X499412Y416120D01*
G01X496038Y411246D02*
X499852Y415060D01*
G01X499412Y416120D02*
X501388D01*
G01X499852Y415060D02*
X500948D01*
G01X501388Y416120D02*
X502191Y415317D01*
G01X500948Y415060D02*
X501751Y414257D01*
G01X502191Y415317D02*
X503570D01*
G01X501751Y414257D02*
X504010D01*
G01X503570Y415317D02*
X504552Y416299D01*
G01X504010Y414257D02*
X505612Y415859D01*
G01X504552Y416299D02*
Y419801D01*
G01X505612Y415859D02*
Y419361D01*
G01X504552Y419801D02*
X505851Y421100D01*
G01X505612Y419361D02*
X506291Y420040D01*
G01X505851Y421100D02*
X510644D01*
G01X506291Y420040D02*
X511084D01*
G01X510644Y421100D02*
X526171Y436627D01*
G01X511084Y420040D02*
X527231Y436187D01*
G01X526171Y436627D02*
Y441604D01*
G01X527231Y436187D02*
Y441164D01*
G01X526171Y441604D02*
X527373Y442806D01*
G01X527231Y441164D02*
X527813Y441746D01*
G01X527373Y442806D02*
X529643D01*
G01X527813Y441746D02*
X529203D01*
G01X529643Y442806D02*
X530901Y441548D01*
G01X529203Y441746D02*
X529841Y441108D01*
G01X530901Y441548D02*
Y439424D01*
G01X529841Y441108D02*
Y438984D01*
G01X530901Y439424D02*
X531599Y438726D01*
G01X529841Y438984D02*
X531159Y437666D01*
G01X531599Y438726D02*
X535597D01*
G01X531159Y437666D02*
X536037D01*
G01X535597Y438726D02*
X582286Y485415D01*
G01X536037Y437666D02*
X583346Y484975D01*
G01X491288Y411515D02*
Y412996D01*
G01X492348Y411515D02*
Y412556D01*
G01X491288Y412996D02*
X502422Y424130D01*
G01X492348Y412556D02*
X502862Y423070D01*
G01X502422Y424130D02*
X508756D01*
G01X502862Y423070D02*
X509196D01*
G01X508756Y424130D02*
X522459Y437833D01*
G01X509196Y423070D02*
X523519Y437393D01*
G01X522459Y437833D02*
Y444110D01*
G01X523519Y437393D02*
Y443670D01*
G01X522459Y444110D02*
X524229Y445880D01*
G01X523519Y443670D02*
X524669Y444820D01*
G01X524229Y445880D02*
X537500D01*
G01X524669Y444820D02*
X537940D01*
G01X537500Y445880D02*
X577186Y485566D01*
G01X537940Y444820D02*
X578246Y485126D01*
G01X496038Y410383D02*
Y411246D01*
G01X494978Y410383D02*
Y411686D01*
G01X496038Y411246D02*
X499852Y415060D01*
G01X494978Y411686D02*
X499412Y416120D01*
G01X499852Y415060D02*
X500948D01*
G01X499412Y416120D02*
X501388D01*
G01X500948Y415060D02*
X501751Y414257D01*
G01X501388Y416120D02*
X502191Y415317D01*
G01X501751Y414257D02*
X504010D01*
G01X502191Y415317D02*
X503570D01*
G01X504010Y414257D02*
X505612Y415859D01*
G01X503570Y415317D02*
X504552Y416299D01*
G01X505612Y415859D02*
Y419361D01*
G01X504552Y416299D02*
Y419801D01*
G01X505612Y419361D02*
X506291Y420040D01*
G01X504552Y419801D02*
X505851Y421100D01*
G01X506291Y420040D02*
X511084D01*
G01X505851Y421100D02*
X510644D01*
G01X511084Y420040D02*
X527231Y436187D01*
G01X510644Y421100D02*
X526171Y436627D01*
G01X527231Y436187D02*
Y441164D01*
G01X526171Y436627D02*
Y441604D01*
G01X527231Y441164D02*
X527813Y441746D01*
G01X526171Y441604D02*
X527373Y442806D01*
G01X527813Y441746D02*
X529203D01*
G01X527373Y442806D02*
X529643D01*
G01X529203Y441746D02*
X529841Y441108D01*
G01X529643Y442806D02*
X530901Y441548D01*
G01X529841Y441108D02*
Y438984D01*
G01X530901Y441548D02*
Y439424D01*
G01X529841Y438984D02*
X531159Y437666D01*
G01X530901Y439424D02*
X531599Y438726D01*
G01X531159Y437666D02*
X536037D01*
G01X531599Y438726D02*
X535597D01*
G01X536037Y437666D02*
X583346Y484975D01*
G01X535597Y438726D02*
X582286Y485415D01*
G01X492348Y411515D02*
Y412556D01*
G01X491288Y411515D02*
Y412996D01*
G01X492348Y412556D02*
X502862Y423070D01*
G01X491288Y412996D02*
X502422Y424130D01*
G01X502862Y423070D02*
X509196D01*
G01X502422Y424130D02*
X508756D01*
G01X509196Y423070D02*
X523519Y437393D01*
G01X508756Y424130D02*
X522459Y437833D01*
G01X523519Y437393D02*
Y443670D01*
G01X522459Y437833D02*
Y444110D01*
G01X523519Y443670D02*
X524669Y444820D01*
G01X522459Y444110D02*
X524229Y445880D01*
G01X524669Y444820D02*
X537940D01*
G01X524229Y445880D02*
X537500D01*
G01X537940Y444820D02*
X578246Y485126D01*
G01X537500Y445880D02*
X577186Y485566D01*
G01X494978Y410383D02*
Y411686D01*
G01X496038Y410383D02*
Y411246D01*
G01X494978Y411686D02*
X499412Y416120D01*
G01X496038Y411246D02*
X499852Y415060D01*
G01X499412Y416120D02*
X501388D01*
G01X499852Y415060D02*
X500948D01*
G01X501388Y416120D02*
X502191Y415317D01*
G01X500948Y415060D02*
X501751Y414257D01*
G01X502191Y415317D02*
X503570D01*
G01X501751Y414257D02*
X504010D01*
G01X503570Y415317D02*
X504552Y416299D01*
G01X504010Y414257D02*
X505612Y415859D01*
G01X504552Y416299D02*
Y419801D01*
G01X505612Y415859D02*
Y419361D01*
G01X504552Y419801D02*
X505851Y421100D01*
G01X505612Y419361D02*
X506291Y420040D01*
G01X505851Y421100D02*
X510644D01*
G01X506291Y420040D02*
X511084D01*
G01X510644Y421100D02*
X526171Y436627D01*
G01X511084Y420040D02*
X527231Y436187D01*
G01X526171Y436627D02*
Y441604D01*
G01X527231Y436187D02*
Y441164D01*
G01X526171Y441604D02*
X527373Y442806D01*
G01X527231Y441164D02*
X527813Y441746D01*
G01X527373Y442806D02*
X529643D01*
G01X527813Y441746D02*
X529203D01*
G01X529643Y442806D02*
X530901Y441548D01*
G01X529203Y441746D02*
X529841Y441108D01*
G01X530901Y441548D02*
Y439424D01*
G01X529841Y441108D02*
Y438984D01*
G01X530901Y439424D02*
X531599Y438726D01*
G01X529841Y438984D02*
X531159Y437666D01*
G01X531599Y438726D02*
X535597D01*
G01X531159Y437666D02*
X536037D01*
G01X535597Y438726D02*
X582286Y485415D01*
G01X536037Y437666D02*
X583346Y484975D01*
G01X491620Y475828D02*
X526343D01*
G01X492060Y474768D02*
X526783D01*
G01X526343Y475828D02*
X540375Y489860D01*
G01X526783Y474768D02*
X541435Y489420D01*
G01X493490Y471722D02*
X510007D01*
G01X493050Y472782D02*
X510447D01*
G01X510007Y471722D02*
X512884Y468845D01*
G01X510447Y472782D02*
X513324Y469905D01*
G01X512884Y468845D02*
X515552D01*
G01X513324Y469905D02*
X515112D01*
G01X515552Y468845D02*
X517899Y471192D01*
G01X515112Y469905D02*
X517459Y472252D01*
G01X517899Y471192D02*
X519751D01*
G01X517459Y472252D02*
X520191D01*
G01X519751Y471192D02*
X520361Y470582D01*
G01X520191Y472252D02*
X521421Y471022D01*
G01X520361Y470582D02*
Y469068D01*
G01X521421Y471022D02*
Y469508D01*
G01X520361Y469068D02*
X521591Y467838D01*
G01X521421Y469508D02*
X522031Y468898D01*
G01X521591Y467838D02*
X523861D01*
G01X522031Y468898D02*
X523421D01*
G01X523861Y467838D02*
X525091Y469068D01*
G01X523421Y468898D02*
X524031Y469508D01*
G01X525091Y469068D02*
Y470582D01*
G01X524031Y469508D02*
Y471022D01*
G01X525091Y470582D02*
X525701Y471192D01*
G01X524031Y471022D02*
X525261Y472252D01*
G01X525701Y471192D02*
X527790D01*
G01X525261Y472252D02*
X527350D01*
G01X527790Y471192D02*
X546535Y489937D01*
G01X527350Y472252D02*
X545475Y490377D01*
G01X492060Y474768D02*
X526783D01*
G01X491620Y475828D02*
X526343D01*
G01X526783Y474768D02*
X541435Y489420D01*
G01X526343Y475828D02*
X540375Y489860D01*
G01X493050Y472782D02*
X510447D01*
G01X493490Y471722D02*
X510007D01*
G01X510447Y472782D02*
X513324Y469905D01*
G01X510007Y471722D02*
X512884Y468845D01*
G01X513324Y469905D02*
X515112D01*
G01X512884Y468845D02*
X515552D01*
G01X515112Y469905D02*
X517459Y472252D01*
G01X515552Y468845D02*
X517899Y471192D01*
G01X517459Y472252D02*
X520191D01*
G01X517899Y471192D02*
X519751D01*
G01X520191Y472252D02*
X521421Y471022D01*
G01X519751Y471192D02*
X520361Y470582D01*
G01X521421Y471022D02*
Y469508D01*
G01X520361Y470582D02*
Y469068D01*
G01X521421Y469508D02*
X522031Y468898D01*
G01X520361Y469068D02*
X521591Y467838D01*
G01X522031Y468898D02*
X523421D01*
G01X521591Y467838D02*
X523861D01*
G01X523421Y468898D02*
X524031Y469508D01*
G01X523861Y467838D02*
X525091Y469068D01*
G01X524031Y469508D02*
Y471022D01*
G01X525091Y469068D02*
Y470582D01*
G01X524031Y471022D02*
X525261Y472252D01*
G01X525091Y470582D02*
X525701Y471192D01*
G01X525261Y472252D02*
X527350D01*
G01X525701Y471192D02*
X527790D01*
G01X527350Y472252D02*
X545475Y490377D01*
G01X527790Y471192D02*
X546535Y489937D01*
G01X503564Y548674D02*
Y505072D01*
G01X504624Y549114D02*
Y504632D01*
G01X503564Y505072D02*
X501832Y503340D01*
G01X504624Y504632D02*
X502892Y502900D01*
G01X501832Y503340D02*
Y501940D01*
G01X502892Y502900D02*
Y500400D01*
G01X509724Y549868D02*
Y504633D01*
G01X508664Y549428D02*
Y505073D01*
G01X509724Y504633D02*
X507492Y502401D01*
G01X508664Y505073D02*
X506432Y502841D01*
G01X507492Y502401D02*
Y500400D01*
G01X506432Y502841D02*
Y501040D01*
G01X504624Y549114D02*
Y504632D01*
G01X503564Y548674D02*
Y505072D01*
G01X504624Y504632D02*
X502892Y502900D01*
G01X503564Y505072D02*
X501832Y503340D01*
G01X502892Y502900D02*
Y500400D01*
G01X501832Y503340D02*
Y501940D01*
G01X508664Y549428D02*
Y505073D01*
G01X509724Y549868D02*
Y504633D01*
G01X508664Y505073D02*
X506432Y502841D01*
G01X509724Y504633D02*
X507492Y502401D01*
G01X506432Y502841D02*
Y501040D01*
G01X507492Y502401D02*
Y500400D01*
G01X491620Y475828D02*
X526343D01*
G01X492060Y474768D02*
X526783D01*
G01X526343Y475828D02*
X540375Y489860D01*
G01X526783Y474768D02*
X541435Y489420D01*
G01X492060Y474768D02*
X526783D01*
G01X491620Y475828D02*
X526343D01*
G01X526783Y474768D02*
X541435Y489420D01*
G01X526343Y475828D02*
X540375Y489860D01*
G01X493490Y471722D02*
X510007D01*
G01X493050Y472782D02*
X510447D01*
G01X510007Y471722D02*
X512884Y468845D01*
G01X510447Y472782D02*
X513324Y469905D01*
G01X512884Y468845D02*
X515552D01*
G01X513324Y469905D02*
X515112D01*
G01X515552Y468845D02*
X517899Y471192D01*
G01X515112Y469905D02*
X517459Y472252D01*
G01X517899Y471192D02*
X519751D01*
G01X517459Y472252D02*
X520191D01*
G01X519751Y471192D02*
X520361Y470582D01*
G01X520191Y472252D02*
X521421Y471022D01*
G01X520361Y470582D02*
Y469068D01*
G01X521421Y471022D02*
Y469508D01*
G01X520361Y469068D02*
X521591Y467838D01*
G01X521421Y469508D02*
X522031Y468898D01*
G01X521591Y467838D02*
X523861D01*
G01X522031Y468898D02*
X523421D01*
G01X523861Y467838D02*
X525091Y469068D01*
G01X523421Y468898D02*
X524031Y469508D01*
G01X525091Y469068D02*
Y470582D01*
G01X524031Y469508D02*
Y471022D01*
G01X525091Y470582D02*
X525701Y471192D01*
G01X524031Y471022D02*
X525261Y472252D01*
G01X525701Y471192D02*
X527790D01*
G01X525261Y472252D02*
X527350D01*
G01X527790Y471192D02*
X546535Y489937D01*
G01X527350Y472252D02*
X545475Y490377D01*
G01X493050Y472782D02*
X510447D01*
G01X493490Y471722D02*
X510007D01*
G01X510447Y472782D02*
X513324Y469905D01*
G01X510007Y471722D02*
X512884Y468845D01*
G01X513324Y469905D02*
X515112D01*
G01X512884Y468845D02*
X515552D01*
G01X515112Y469905D02*
X517459Y472252D01*
G01X515552Y468845D02*
X517899Y471192D01*
G01X517459Y472252D02*
X520191D01*
G01X517899Y471192D02*
X519751D01*
G01X520191Y472252D02*
X521421Y471022D01*
G01X519751Y471192D02*
X520361Y470582D01*
G01X521421Y471022D02*
Y469508D01*
G01X520361Y470582D02*
Y469068D01*
G01X521421Y469508D02*
X522031Y468898D01*
G01X520361Y469068D02*
X521591Y467838D01*
G01X522031Y468898D02*
X523421D01*
G01X521591Y467838D02*
X523861D01*
G01X523421Y468898D02*
X524031Y469508D01*
G01X523861Y467838D02*
X525091Y469068D01*
G01X524031Y469508D02*
Y471022D01*
G01X525091Y469068D02*
Y470582D01*
G01X524031Y471022D02*
X525261Y472252D01*
G01X525091Y470582D02*
X525701Y471192D01*
G01X525261Y472252D02*
X527350D01*
G01X525701Y471192D02*
X527790D01*
G01X527350Y472252D02*
X545475Y490377D01*
G01X527790Y471192D02*
X546535Y489937D01*
G01X540375Y586986D02*
X539061Y588300D01*
G01X540375Y586986D02*
X539061Y588300D01*
G01X501738Y550500D02*
X503564Y548674D01*
G01X503292Y550446D02*
X504624Y549114D01*
G01X508392Y551200D02*
X509724Y549868D01*
G01X507378Y550714D02*
X508664Y549428D01*
G01X503292Y550446D02*
X504624Y549114D01*
G01X501738Y550500D02*
X503564Y548674D01*
G01X507378Y550714D02*
X508664Y549428D01*
G01X508392Y551200D02*
X509724Y549868D01*
G01X540375Y586986D02*
X539061Y588300D01*
G01X540375Y586986D02*
X539061Y588300D01*
G01X536367Y590000D02*
Y608011D01*
G01X537427Y595890D02*
Y597260D01*
G01X536367Y590000D02*
Y608011D01*
G01X537427Y600940D02*
Y602360D01*
G01Y595890D02*
Y597260D01*
G01Y600940D02*
Y602360D01*
G01X536367Y590000D02*
Y608011D01*
G01X499556Y590000D02*
Y608011D01*
G01X500616Y595890D02*
Y597260D01*
G01X499556Y590000D02*
Y608011D01*
G01X500616Y600940D02*
Y602360D01*
G01X536367Y590000D02*
Y608011D01*
G01X537427Y595890D02*
Y597260D01*
G01X536367Y590000D02*
Y608011D01*
G01X537427Y600940D02*
Y602360D01*
G01X505840Y595500D02*
X505169Y596171D01*
G01X504938Y594901D02*
X504109Y595730D01*
G01X505169Y596171D02*
Y597448D01*
G01Y600938D02*
Y601829D01*
G01X504109Y595730D02*
Y602270D01*
G01X505169Y601829D02*
X505940Y602600D01*
G01X504109Y602270D02*
X504938Y603099D01*
G01X500616Y595890D02*
Y597260D01*
G01Y600940D02*
Y602360D01*
G01X499556Y590000D02*
Y608011D01*
G01X537427Y595890D02*
Y597260D01*
G01Y600940D02*
Y602360D01*
G01X536367Y590000D02*
Y608011D01*
G01X504938Y594901D02*
X504109Y595730D01*
G01X505840Y595500D02*
X505169Y596171D01*
G01X504109Y595730D02*
Y602270D01*
G01X505169Y596171D02*
Y597448D01*
G01X504109Y595730D02*
Y602270D01*
G01X505169Y600938D02*
Y601829D01*
G01X504109Y602270D02*
X504938Y603099D01*
G01X505169Y601829D02*
X505940Y602600D01*
G01X777601Y-42660D02*
X583560D01*
G01X777601Y-43720D02*
X583560D01*
G01Y-42660D02*
G03Y-47440I0J-2390D01*
G01Y-43720D02*
G03Y-46380I0J-1330D01*
G01Y-47440D02*
X777156D01*
G01X583560Y-46380D02*
X777156D01*
G01Y-50100D02*
X576480D01*
G01X777156Y-51160D02*
X576040D01*
G01X576480Y-50100D02*
X573151Y-46771D01*
G01X576040Y-51160D02*
X572711Y-47831D01*
G01X573151Y-46771D02*
X551716D01*
G01X572711Y-47831D02*
X551716D01*
G01X777601Y-43720D02*
X583560D01*
G01X777601Y-42660D02*
X583560D01*
G01Y-43720D02*
G03Y-46380I0J-1330D01*
G01Y-42660D02*
G03Y-47440I0J-2390D01*
G01Y-46380D02*
X777156D01*
G01X583560Y-47440D02*
X777156D01*
G01Y-51160D02*
X576040D01*
G01X777156Y-50100D02*
X576480D01*
G01X576040Y-51160D02*
X572711Y-47831D01*
G01X576480Y-50100D02*
X573151Y-46771D01*
G01X572711Y-47831D02*
X551716D01*
G01X573151Y-46771D02*
X551716D01*
G01X540401Y10753D02*
Y8220D01*
G01Y4080D02*
Y3120D01*
G01Y-1220D02*
Y-4509D01*
G01X541461Y11194D02*
Y-4952D01*
G01D02*
X540133Y-6280D01*
G01X540375Y115388D02*
Y25753D01*
G01Y115388D02*
Y25753D01*
G01Y115388D02*
Y25753D01*
G01Y115388D02*
Y25753D01*
G01X541435Y36580D02*
Y25310D01*
G01X543455Y11915D02*
X544553D01*
G01D02*
X545587Y10881D01*
G01X543455Y14514D02*
X546647Y11322D01*
G01X545587Y10881D02*
Y8106D01*
G01Y4280D02*
Y2907D01*
G01Y-1007D02*
Y-3628D01*
G01X546647Y11322D02*
Y-4068D01*
G01X545587Y-3628D02*
X544564Y-4651D01*
G01D02*
X543455D01*
G01X546647Y-4068D02*
X543455Y-7260D01*
G01X545612Y115948D02*
Y24949D01*
G01X546672Y116391D02*
Y31620D01*
G01X545612Y115948D02*
Y24949D01*
G01X546672Y29380D02*
Y24509D01*
G01X545612Y24949D02*
X541701Y21038D01*
G01X546672Y24509D02*
X546069Y23906D01*
G01X545612Y24949D02*
X541701Y21038D01*
G01X544486Y22323D02*
X542761Y20598D01*
G01X541701Y21038D02*
Y13668D01*
G01X542761Y20598D02*
Y19501D01*
G01X541461Y11194D02*
Y-4952D01*
G01X540401Y10753D02*
Y8220D01*
G01X541461Y11194D02*
Y-4952D01*
G01X540401Y4080D02*
Y3120D01*
G01X541461Y11194D02*
Y-4952D01*
G01X540401Y-1220D02*
Y-4509D01*
G01X541461Y-4952D02*
X540133Y-6280D01*
G01X541435Y36580D02*
Y25310D01*
G01X540375Y115388D02*
Y25753D01*
G01X543455Y14514D02*
X546647Y11322D01*
G01X543455Y11915D02*
X544553D01*
G01X543455Y14514D02*
X546647Y11322D01*
G01X544553Y11915D02*
X545587Y10881D01*
G01X546647Y11322D02*
Y-4068D01*
G01X545587Y10881D02*
Y8106D01*
G01X546647Y11322D02*
Y-4068D01*
G01X545587Y4280D02*
Y2907D01*
G01X546647Y11322D02*
Y-4068D01*
G01X545587Y-1007D02*
Y-3628D01*
G01X546647Y-4068D02*
X543455Y-7260D01*
G01X545587Y-3628D02*
X544564Y-4651D01*
G01X546647Y-4068D02*
X543455Y-7260D01*
G01X544564Y-4651D02*
X543455D01*
G01X546672Y116391D02*
Y31620D01*
G01Y29380D02*
Y24509D01*
G01X545612Y115948D02*
Y24949D01*
G01X546672Y24509D02*
X546069Y23906D01*
G01X544486Y22323D02*
X542761Y20598D01*
G01X545612Y24949D02*
X541701Y21038D01*
G01X542761Y20598D02*
Y19501D01*
G01X541701Y21038D02*
Y13668D01*
G01X575166Y14300D02*
X578272Y11194D01*
G01X575166Y11700D02*
X576265D01*
G01X575166Y14300D02*
X578272Y11194D01*
G01X576265Y11700D02*
X577212Y10753D01*
G01X578272Y11194D02*
Y-4952D01*
G01X577212Y10753D02*
Y8220D01*
G01X578272Y11194D02*
Y-4952D01*
G01X577212Y4080D02*
Y3120D01*
G01X578272Y11194D02*
Y-4952D01*
G01X577212Y-1220D02*
Y-4509D01*
G01X578272Y-4952D02*
X576944Y-6280D01*
G01X577212Y-4509D02*
X576501Y-5220D01*
G01X578272Y-4952D02*
X576944Y-6280D01*
G01D02*
X575962D01*
G01X576501Y-5220D02*
X575985D01*
G01X578246Y39226D02*
Y24562D01*
G01X577186Y94165D02*
Y25005D01*
G01X578246Y24562D02*
X574372Y20688D01*
G01X577186Y25005D02*
X573312Y21131D01*
G01X574372Y20688D02*
Y19620D01*
G01X573312Y21131D02*
Y13554D01*
G01X540401Y10753D02*
Y8220D01*
G01Y4080D02*
Y3120D01*
G01Y-1220D02*
Y-4509D01*
G01X541461Y11194D02*
Y-4952D01*
G01D02*
X540133Y-6280D01*
G01X540375Y115388D02*
Y25753D01*
G01Y115388D02*
Y25753D01*
G01Y115388D02*
Y25753D01*
G01Y115388D02*
Y25753D01*
G01X541435Y36580D02*
Y25310D01*
G01X541461Y11194D02*
Y-4952D01*
G01X540401Y10753D02*
Y8220D01*
G01X541461Y11194D02*
Y-4952D01*
G01X540401Y4080D02*
Y3120D01*
G01X541461Y11194D02*
Y-4952D01*
G01X540401Y-1220D02*
Y-4509D01*
G01X541461Y-4952D02*
X540133Y-6280D01*
G01X541435Y36580D02*
Y25310D01*
G01X540375Y115388D02*
Y25753D01*
G01X575166Y11700D02*
X576265D01*
G01D02*
X577212Y10753D01*
G01X575166Y14300D02*
X578272Y11194D01*
G01X577212Y10753D02*
Y8220D01*
G01Y4080D02*
Y3120D01*
G01Y-1220D02*
Y-4509D01*
G01X578272Y11194D02*
Y-4952D01*
G01X577212Y-4509D02*
X576501Y-5220D01*
G01D02*
X575985D01*
G01X578272Y-4952D02*
X576944Y-6280D01*
G01X576501Y-5220D02*
X575985D01*
G01X576944Y-6280D02*
X575962D01*
G01X577186Y94165D02*
Y25005D01*
G01Y94165D02*
Y25005D01*
G01Y94165D02*
Y25005D01*
G01Y94165D02*
Y25005D01*
G01X578246Y39226D02*
Y24562D01*
G01X577186Y25005D02*
X573312Y21131D01*
G01X578246Y24562D02*
X574372Y20688D01*
G01X573312Y21131D02*
Y13554D01*
G01X574372Y20688D02*
Y19620D01*
G01X580266Y11915D02*
X581364D01*
G01D02*
X582398Y10881D01*
G01X580266Y14514D02*
X583458Y11322D01*
G01X582398Y10881D02*
Y8106D01*
G01Y4280D02*
Y2907D01*
G01Y-1007D02*
Y-3628D01*
G01X583458Y11322D02*
Y-4068D01*
G01X582398Y-3628D02*
X581375Y-4651D01*
G01D02*
X580266D01*
G01X583458Y-4068D02*
X580266Y-7260D01*
G01X582286Y120106D02*
Y24505D01*
G01X583346Y120546D02*
Y26134D01*
G01X582286Y24505D02*
X579012Y21231D01*
G01X581046Y21762D02*
X580072Y20788D01*
G01X579012Y21231D02*
Y18719D01*
G01X580072Y20788D02*
Y19920D01*
G01X580266Y14514D02*
X583458Y11322D01*
G01X580266Y11915D02*
X581364D01*
G01X580266Y14514D02*
X583458Y11322D01*
G01X581364Y11915D02*
X582398Y10881D01*
G01X583458Y11322D02*
Y-4068D01*
G01X582398Y10881D02*
Y8106D01*
G01X583458Y11322D02*
Y-4068D01*
G01X582398Y4280D02*
Y2907D01*
G01X583458Y11322D02*
Y-4068D01*
G01X582398Y-1007D02*
Y-3628D01*
G01X583458Y-4068D02*
X580266Y-7260D01*
G01X582398Y-3628D02*
X581375Y-4651D01*
G01X583458Y-4068D02*
X580266Y-7260D01*
G01X581375Y-4651D02*
X580266D01*
G01X583346Y120546D02*
Y26134D01*
G01X582286Y120106D02*
Y24505D01*
G01X581046Y21762D02*
X580072Y20788D01*
G01X582286Y24505D02*
X579012Y21231D01*
G01X580072Y20788D02*
Y19920D01*
G01X579012Y21231D02*
Y18719D01*
G01X575166Y11700D02*
X576265D01*
G01D02*
X577212Y10753D01*
G01X575166Y14300D02*
X578272Y11194D01*
G01X577212Y10753D02*
Y8220D01*
G01Y4080D02*
Y3120D01*
G01Y-1220D02*
Y-4509D01*
G01X578272Y11194D02*
Y-4952D01*
G01X577212Y-4509D02*
X576501Y-5220D01*
G01D02*
X575985D01*
G01X578272Y-4952D02*
X576944Y-6280D01*
G01X576501Y-5220D02*
X575985D01*
G01X576944Y-6280D02*
X575962D01*
G01X577186Y94165D02*
Y25005D01*
G01Y94165D02*
Y25005D01*
G01Y94165D02*
Y25005D01*
G01Y94165D02*
Y25005D01*
G01X578246Y39226D02*
Y24562D01*
G01X577186Y25005D02*
X573312Y21131D01*
G01X578246Y24562D02*
X574372Y20688D01*
G01X573312Y21131D02*
Y13554D01*
G01X574372Y20688D02*
Y19620D01*
G01X543455Y11915D02*
X544553D01*
G01D02*
X545587Y10881D01*
G01X543455Y14514D02*
X546647Y11322D01*
G01X545587Y10881D02*
Y8106D01*
G01Y4280D02*
Y2907D01*
G01Y-1007D02*
Y-3628D01*
G01X546647Y11322D02*
Y-4068D01*
G01X545587Y-3628D02*
X544564Y-4651D01*
G01D02*
X543455D01*
G01X546647Y-4068D02*
X543455Y-7260D01*
G01X545612Y115948D02*
Y24949D01*
G01X546672Y116391D02*
Y31620D01*
G01X545612Y115948D02*
Y24949D01*
G01X546672Y29380D02*
Y24509D01*
G01X545612Y24949D02*
X541701Y21038D01*
G01X546672Y24509D02*
X546069Y23906D01*
G01X545612Y24949D02*
X541701Y21038D01*
G01X544486Y22323D02*
X542761Y20598D01*
G01X541701Y21038D02*
Y13668D01*
G01X542761Y20598D02*
Y19501D01*
G01X580266Y11915D02*
X581364D01*
G01D02*
X582398Y10881D01*
G01X580266Y14514D02*
X583458Y11322D01*
G01X582398Y10881D02*
Y8106D01*
G01Y4280D02*
Y2907D01*
G01Y-1007D02*
Y-3628D01*
G01X583458Y11322D02*
Y-4068D01*
G01X582398Y-3628D02*
X581375Y-4651D01*
G01D02*
X580266D01*
G01X583458Y-4068D02*
X580266Y-7260D01*
G01X582286Y120106D02*
Y24505D01*
G01X583346Y120546D02*
Y26134D01*
G01X582286Y24505D02*
X579012Y21231D01*
G01X581046Y21762D02*
X580072Y20788D01*
G01X579012Y21231D02*
Y18719D01*
G01X580072Y20788D02*
Y19920D01*
G01X575166Y14300D02*
X578272Y11194D01*
G01X575166Y11700D02*
X576265D01*
G01X575166Y14300D02*
X578272Y11194D01*
G01X576265Y11700D02*
X577212Y10753D01*
G01X578272Y11194D02*
Y-4952D01*
G01X577212Y10753D02*
Y8220D01*
G01X578272Y11194D02*
Y-4952D01*
G01X577212Y4080D02*
Y3120D01*
G01X578272Y11194D02*
Y-4952D01*
G01X577212Y-1220D02*
Y-4509D01*
G01X578272Y-4952D02*
X576944Y-6280D01*
G01X577212Y-4509D02*
X576501Y-5220D01*
G01X578272Y-4952D02*
X576944Y-6280D01*
G01D02*
X575962D01*
G01X576501Y-5220D02*
X575985D01*
G01X578246Y39226D02*
Y24562D01*
G01X577186Y94165D02*
Y25005D01*
G01X578246Y24562D02*
X574372Y20688D01*
G01X577186Y25005D02*
X573312Y21131D01*
G01X574372Y20688D02*
Y19620D01*
G01X573312Y21131D02*
Y13554D01*
G01X543455Y14514D02*
X546647Y11322D01*
G01X543455Y11915D02*
X544553D01*
G01X543455Y14514D02*
X546647Y11322D01*
G01X544553Y11915D02*
X545587Y10881D01*
G01X546647Y11322D02*
Y-4068D01*
G01X545587Y10881D02*
Y8106D01*
G01X546647Y11322D02*
Y-4068D01*
G01X545587Y4280D02*
Y2907D01*
G01X546647Y11322D02*
Y-4068D01*
G01X545587Y-1007D02*
Y-3628D01*
G01X546647Y-4068D02*
X543455Y-7260D01*
G01X545587Y-3628D02*
X544564Y-4651D01*
G01X546647Y-4068D02*
X543455Y-7260D01*
G01X544564Y-4651D02*
X543455D01*
G01X546672Y116391D02*
Y31620D01*
G01Y29380D02*
Y24509D01*
G01X545612Y115948D02*
Y24949D01*
G01X546672Y24509D02*
X546069Y23906D01*
G01X544486Y22323D02*
X542761Y20598D01*
G01X545612Y24949D02*
X541701Y21038D01*
G01X542761Y20598D02*
Y19501D01*
G01X541701Y21038D02*
Y13668D01*
G01X580266Y14514D02*
X583458Y11322D01*
G01X580266Y11915D02*
X581364D01*
G01X580266Y14514D02*
X583458Y11322D01*
G01X581364Y11915D02*
X582398Y10881D01*
G01X583458Y11322D02*
Y-4068D01*
G01X582398Y10881D02*
Y8106D01*
G01X583458Y11322D02*
Y-4068D01*
G01X582398Y4280D02*
Y2907D01*
G01X583458Y11322D02*
Y-4068D01*
G01X582398Y-1007D02*
Y-3628D01*
G01X583458Y-4068D02*
X580266Y-7260D01*
G01X582398Y-3628D02*
X581375Y-4651D01*
G01X583458Y-4068D02*
X580266Y-7260D01*
G01X581375Y-4651D02*
X580266D01*
G01X583346Y120546D02*
Y26134D01*
G01X582286Y120106D02*
Y24505D01*
G01X581046Y21762D02*
X580072Y20788D01*
G01X582286Y24505D02*
X579012Y21231D01*
G01X580072Y20788D02*
Y19920D01*
G01X579012Y21231D02*
Y18719D01*
G01X541435Y115828D02*
Y44820D01*
G01Y42580D02*
Y41820D01*
G01Y39580D02*
Y38820D01*
G01Y115828D02*
Y44820D01*
G01Y42580D02*
Y41820D01*
G01Y39580D02*
Y38820D01*
G01X579362Y94841D02*
X578246Y93725D01*
G01X578302Y95281D02*
X577186Y94165D01*
G01X578246Y93725D02*
Y48213D01*
G01Y46313D02*
Y44418D01*
G01Y42518D02*
Y41126D01*
G01X541435Y115828D02*
Y44820D01*
G01Y42580D02*
Y41820D01*
G01Y39580D02*
Y38820D01*
G01Y115828D02*
Y44820D01*
G01Y42580D02*
Y41820D01*
G01Y39580D02*
Y38820D01*
G01X578302Y95281D02*
X577186Y94165D01*
G01X579362Y94841D02*
X578246Y93725D01*
G01D02*
Y48213D01*
G01Y46313D02*
Y44418D01*
G01Y42518D02*
Y41126D01*
G01X578302Y95281D02*
X577186Y94165D01*
G01X579362Y94841D02*
X578246Y93725D01*
G01D02*
Y48213D01*
G01Y46313D02*
Y44418D01*
G01Y42518D02*
Y41126D01*
G01X579362Y94841D02*
X578246Y93725D01*
G01X578302Y95281D02*
X577186Y94165D01*
G01X578246Y93725D02*
Y48213D01*
G01Y46313D02*
Y44418D01*
G01Y42518D02*
Y41126D01*
G01X575972Y123520D02*
Y117202D01*
G01X574912Y123080D02*
Y116762D01*
G01X575972Y117202D02*
X576841Y116333D01*
G01D02*
X578460D01*
G01X574912Y116762D02*
X576401Y115273D01*
G01X576841Y116333D02*
X578460D01*
G01D02*
X579952Y114841D01*
G01X576401Y115273D02*
X578020D01*
G01X578460Y116333D02*
X579952Y114841D01*
G01X578020Y115273D02*
X578892Y114401D01*
G01X579952Y114841D02*
Y111465D01*
G01X578892Y114401D02*
Y111905D01*
G01X579952Y111465D02*
X578460Y109973D01*
G01X578892Y111905D02*
X578020Y111033D01*
G01X578460Y109973D02*
X576741D01*
G01X578020Y111033D02*
X576301D01*
G01X578460Y109973D02*
X576741D01*
G01D02*
X575872Y109104D01*
G01X576301Y111033D02*
X574812Y109544D01*
G01X575872Y109104D02*
Y106605D01*
G01X574812Y109544D02*
Y106162D01*
G01X575872Y106605D02*
X576744Y105733D01*
G01D02*
X577880D01*
G01X574812Y106162D02*
X576301Y104673D01*
G01X576744Y105733D02*
X577880D01*
G01D02*
X579472Y104141D01*
G01X576301Y104673D02*
X577440D01*
G01X577880Y105733D02*
X579472Y104141D01*
G01X577440Y104673D02*
X578412Y103701D01*
G01X579472Y104141D02*
Y102285D01*
G01X578412Y103701D02*
Y102725D01*
G01X579472Y102285D02*
X577361Y100174D01*
G01X578412Y102725D02*
X576301Y100614D01*
G01X577361Y100174D02*
Y98427D01*
G01X576301Y100614D02*
Y97987D01*
G01X577361Y98427D02*
X579362Y96426D01*
G01X576301Y97987D02*
X578302Y95986D01*
G01X579362Y96426D02*
Y94841D01*
G01X578302Y95986D02*
Y95281D01*
G01X574912Y123080D02*
Y116762D01*
G01X575972Y123520D02*
Y117202D01*
G01X574912Y116762D02*
X576401Y115273D01*
G01X575972Y117202D02*
X576841Y116333D01*
G01X574912Y116762D02*
X576401Y115273D01*
G01D02*
X578020D01*
G01X576841Y116333D02*
X578460D01*
G01X576401Y115273D02*
X578020D01*
G01D02*
X578892Y114401D01*
G01X578460Y116333D02*
X579952Y114841D01*
G01X578892Y114401D02*
Y111905D01*
G01X579952Y114841D02*
Y111465D01*
G01X578892Y111905D02*
X578020Y111033D01*
G01X579952Y111465D02*
X578460Y109973D01*
G01X578020Y111033D02*
X576301D01*
G01D02*
X574812Y109544D01*
G01X578460Y109973D02*
X576741D01*
G01X576301Y111033D02*
X574812Y109544D01*
G01X576741Y109973D02*
X575872Y109104D01*
G01X574812Y109544D02*
Y106162D01*
G01X575872Y109104D02*
Y106605D01*
G01X574812Y106162D02*
X576301Y104673D01*
G01X575872Y106605D02*
X576744Y105733D01*
G01X574812Y106162D02*
X576301Y104673D01*
G01D02*
X577440D01*
G01X576744Y105733D02*
X577880D01*
G01X576301Y104673D02*
X577440D01*
G01D02*
X578412Y103701D01*
G01X577880Y105733D02*
X579472Y104141D01*
G01X578412Y103701D02*
Y102725D01*
G01X579472Y104141D02*
Y102285D01*
G01X578412Y102725D02*
X576301Y100614D01*
G01X579472Y102285D02*
X577361Y100174D01*
G01X576301Y100614D02*
Y97987D01*
G01X577361Y100174D02*
Y98427D01*
G01X576301Y97987D02*
X578302Y95986D01*
G01X577361Y98427D02*
X579362Y96426D01*
G01X578302Y95986D02*
Y95281D01*
G01X579362Y96426D02*
Y94841D01*
G01X574912Y123080D02*
Y116762D01*
G01X575972Y123520D02*
Y117202D01*
G01X574912Y116762D02*
X576401Y115273D01*
G01X575972Y117202D02*
X576841Y116333D01*
G01X574912Y116762D02*
X576401Y115273D01*
G01D02*
X578020D01*
G01X576841Y116333D02*
X578460D01*
G01X576401Y115273D02*
X578020D01*
G01D02*
X578892Y114401D01*
G01X578460Y116333D02*
X579952Y114841D01*
G01X578892Y114401D02*
Y111905D01*
G01X579952Y114841D02*
Y111465D01*
G01X578892Y111905D02*
X578020Y111033D01*
G01X579952Y111465D02*
X578460Y109973D01*
G01X578020Y111033D02*
X576301D01*
G01D02*
X574812Y109544D01*
G01X578460Y109973D02*
X576741D01*
G01X576301Y111033D02*
X574812Y109544D01*
G01X576741Y109973D02*
X575872Y109104D01*
G01X574812Y109544D02*
Y106162D01*
G01X575872Y109104D02*
Y106605D01*
G01X574812Y106162D02*
X576301Y104673D01*
G01X575872Y106605D02*
X576744Y105733D01*
G01X574812Y106162D02*
X576301Y104673D01*
G01D02*
X577440D01*
G01X576744Y105733D02*
X577880D01*
G01X576301Y104673D02*
X577440D01*
G01D02*
X578412Y103701D01*
G01X577880Y105733D02*
X579472Y104141D01*
G01X578412Y103701D02*
Y102725D01*
G01X579472Y104141D02*
Y102285D01*
G01X578412Y102725D02*
X576301Y100614D01*
G01X579472Y102285D02*
X577361Y100174D01*
G01X576301Y100614D02*
Y97987D01*
G01X577361Y100174D02*
Y98427D01*
G01X576301Y97987D02*
X578302Y95986D01*
G01X577361Y98427D02*
X579362Y96426D01*
G01X578302Y95986D02*
Y95281D01*
G01X579362Y96426D02*
Y94841D01*
G01X575972Y123520D02*
Y117202D01*
G01X574912Y123080D02*
Y116762D01*
G01X575972Y117202D02*
X576841Y116333D01*
G01D02*
X578460D01*
G01X574912Y116762D02*
X576401Y115273D01*
G01X576841Y116333D02*
X578460D01*
G01D02*
X579952Y114841D01*
G01X576401Y115273D02*
X578020D01*
G01X578460Y116333D02*
X579952Y114841D01*
G01X578020Y115273D02*
X578892Y114401D01*
G01X579952Y114841D02*
Y111465D01*
G01X578892Y114401D02*
Y111905D01*
G01X579952Y111465D02*
X578460Y109973D01*
G01X578892Y111905D02*
X578020Y111033D01*
G01X578460Y109973D02*
X576741D01*
G01X578020Y111033D02*
X576301D01*
G01X578460Y109973D02*
X576741D01*
G01D02*
X575872Y109104D01*
G01X576301Y111033D02*
X574812Y109544D01*
G01X575872Y109104D02*
Y106605D01*
G01X574812Y109544D02*
Y106162D01*
G01X575872Y106605D02*
X576744Y105733D01*
G01D02*
X577880D01*
G01X574812Y106162D02*
X576301Y104673D01*
G01X576744Y105733D02*
X577880D01*
G01D02*
X579472Y104141D01*
G01X576301Y104673D02*
X577440D01*
G01X577880Y105733D02*
X579472Y104141D01*
G01X577440Y104673D02*
X578412Y103701D01*
G01X579472Y104141D02*
Y102285D01*
G01X578412Y103701D02*
Y102725D01*
G01X579472Y102285D02*
X577361Y100174D01*
G01X578412Y102725D02*
X576301Y100614D01*
G01X577361Y100174D02*
Y98427D01*
G01X576301Y100614D02*
Y97987D01*
G01X577361Y98427D02*
X579362Y96426D01*
G01X576301Y97987D02*
X578302Y95986D01*
G01X579362Y96426D02*
Y94841D01*
G01X578302Y95986D02*
Y95281D01*
G01X540375Y489860D02*
Y576310D01*
G01X541435Y489420D02*
Y587429D01*
G01X577186Y485566D02*
Y576325D01*
G01X578246Y485126D02*
Y587820D01*
G01X546535Y489937D02*
Y587829D01*
G01X545475Y490377D02*
Y507226D01*
G01X546535Y489937D02*
Y587829D01*
G01X545475Y509076D02*
Y519324D01*
G01X546535Y489937D02*
Y587829D01*
G01X545475Y521564D02*
Y522564D01*
G01X546535Y489937D02*
Y587829D01*
G01X545475Y524804D02*
Y525804D01*
G01X546535Y489937D02*
Y587829D01*
G01Y489937D02*
Y587829D01*
G01Y489937D02*
Y587829D01*
G01Y489937D02*
Y587829D01*
G01Y489937D02*
Y587829D01*
G01Y489937D02*
Y587829D01*
G01Y489937D02*
Y587829D01*
G01Y489937D02*
Y587829D01*
G01Y489937D02*
Y587829D01*
G01Y489937D02*
Y587829D01*
G01X583346Y484975D02*
Y588034D01*
G01X582286Y485415D02*
Y506891D01*
G01X583346Y484975D02*
Y588034D01*
G01X582286Y509131D02*
Y518933D01*
G01X583346Y484975D02*
Y588034D01*
G01X582286Y521173D02*
Y522173D01*
G01X583346Y484975D02*
Y588034D01*
G01X582286Y524413D02*
Y525413D01*
G01X583346Y484975D02*
Y588034D01*
G01Y484975D02*
Y588034D01*
G01Y484975D02*
Y588034D01*
G01Y484975D02*
Y588034D01*
G01Y484975D02*
Y588034D01*
G01Y484975D02*
Y588034D01*
G01Y484975D02*
Y588034D01*
G01Y484975D02*
Y588034D01*
G01Y484975D02*
Y588034D01*
G01Y484975D02*
Y588034D01*
G01X541435Y489420D02*
Y587429D01*
G01X540375Y489860D02*
Y576310D01*
G01X541435Y489420D02*
Y587429D01*
G01Y489420D02*
Y587429D01*
G01Y489420D02*
Y587429D01*
G01X578246Y485126D02*
Y587820D01*
G01X577186Y485566D02*
Y576325D01*
G01X578246Y485126D02*
Y587820D01*
G01Y485126D02*
Y587820D01*
G01Y485126D02*
Y587820D01*
G01X545475Y490377D02*
Y507226D01*
G01Y509076D02*
Y519324D01*
G01Y521564D02*
Y522564D01*
G01Y524804D02*
Y525804D01*
G01X546535Y489937D02*
Y587829D01*
G01X582286Y485415D02*
Y506891D01*
G01Y509131D02*
Y518933D01*
G01Y521173D02*
Y522173D01*
G01Y524413D02*
Y525413D01*
G01X583346Y484975D02*
Y588034D01*
G01X540375Y489860D02*
Y576310D01*
G01X541435Y489420D02*
Y587429D01*
G01Y489420D02*
Y587429D01*
G01X540375Y489860D02*
Y576310D01*
G01X541435Y489420D02*
Y587429D01*
G01Y489420D02*
Y587429D01*
G01Y489420D02*
Y587429D01*
G01X577186Y485566D02*
Y576325D01*
G01X578246Y485126D02*
Y587820D01*
G01X546535Y489937D02*
Y587829D01*
G01X545475Y490377D02*
Y507226D01*
G01X546535Y489937D02*
Y587829D01*
G01X545475Y509076D02*
Y519324D01*
G01X546535Y489937D02*
Y587829D01*
G01X545475Y521564D02*
Y522564D01*
G01X546535Y489937D02*
Y587829D01*
G01X545475Y524804D02*
Y525804D01*
G01X546535Y489937D02*
Y587829D01*
G01Y489937D02*
Y587829D01*
G01Y489937D02*
Y587829D01*
G01Y489937D02*
Y587829D01*
G01Y489937D02*
Y587829D01*
G01Y489937D02*
Y587829D01*
G01Y489937D02*
Y587829D01*
G01Y489937D02*
Y587829D01*
G01Y489937D02*
Y587829D01*
G01Y489937D02*
Y587829D01*
G01X583346Y484975D02*
Y588034D01*
G01X582286Y485415D02*
Y506891D01*
G01X583346Y484975D02*
Y588034D01*
G01X582286Y509131D02*
Y518933D01*
G01X583346Y484975D02*
Y588034D01*
G01X582286Y521173D02*
Y522173D01*
G01X583346Y484975D02*
Y588034D01*
G01X582286Y524413D02*
Y525413D01*
G01X583346Y484975D02*
Y588034D01*
G01Y484975D02*
Y588034D01*
G01Y484975D02*
Y588034D01*
G01Y484975D02*
Y588034D01*
G01Y484975D02*
Y588034D01*
G01Y484975D02*
Y588034D01*
G01Y484975D02*
Y588034D01*
G01Y484975D02*
Y588034D01*
G01Y484975D02*
Y588034D01*
G01Y484975D02*
Y588034D01*
G01X578246Y485126D02*
Y587820D01*
G01X577186Y485566D02*
Y576325D01*
G01X578246Y485126D02*
Y587820D01*
G01Y485126D02*
Y587820D01*
G01Y485126D02*
Y587820D01*
G01X545475Y490377D02*
Y507226D01*
G01Y509076D02*
Y519324D01*
G01Y521564D02*
Y522564D01*
G01Y524804D02*
Y525804D01*
G01X546535Y489937D02*
Y587829D01*
G01X582286Y485415D02*
Y506891D01*
G01Y509131D02*
Y518933D01*
G01Y521173D02*
Y522173D01*
G01Y524413D02*
Y525413D01*
G01X583346Y484975D02*
Y588034D01*
G01X540375Y578214D02*
Y579368D01*
G01Y581608D02*
Y582608D01*
G01Y584848D02*
Y586986D01*
G01X541435Y587429D02*
X539992Y588872D01*
G01X577186Y578089D02*
Y579285D01*
G01Y581525D02*
Y582637D01*
G01Y584653D02*
Y587380D01*
G01D02*
X576266Y588300D01*
G01X578246Y587820D02*
X575166Y590900D01*
G01X545475Y528044D02*
Y538014D01*
G01Y540254D02*
Y541254D01*
G01Y543494D02*
Y544494D01*
G01Y546734D02*
Y556955D01*
G01Y559195D02*
Y560195D01*
G01Y562435D02*
Y563435D01*
G01Y565675D02*
Y575841D01*
G01Y578081D02*
Y579081D01*
G01Y581321D02*
Y582321D01*
G01Y584561D02*
Y587386D01*
G01X546535Y587829D02*
X544992Y589372D01*
G01X545475Y587386D02*
X544347Y588514D01*
G01X582286Y527653D02*
Y538405D01*
G01Y540645D02*
Y541645D01*
G01Y543885D02*
Y544885D01*
G01Y547125D02*
Y557095D01*
G01Y559335D02*
Y560335D01*
G01Y562575D02*
Y563575D01*
G01Y565815D02*
Y576259D01*
G01Y578499D02*
Y579499D01*
G01Y581739D02*
Y582739D01*
G01Y584979D02*
Y587593D01*
G01X583346Y588034D02*
X580266Y591114D01*
G01X582286Y587593D02*
X581365Y588514D01*
G01X540375Y578214D02*
Y579368D01*
G01Y581608D02*
Y582608D01*
G01Y584848D02*
Y586986D01*
G01X541435Y587429D02*
X539992Y588872D01*
G01X577186Y578089D02*
Y579285D01*
G01Y581525D02*
Y582637D01*
G01Y584653D02*
Y587380D01*
G01X578246Y587820D02*
X575166Y590900D01*
G01X577186Y587380D02*
X576266Y588300D01*
G01X545475Y528044D02*
Y538014D01*
G01Y540254D02*
Y541254D01*
G01Y543494D02*
Y544494D01*
G01Y546734D02*
Y556955D01*
G01Y559195D02*
Y560195D01*
G01Y562435D02*
Y563435D01*
G01Y565675D02*
Y575841D01*
G01Y578081D02*
Y579081D01*
G01Y581321D02*
Y582321D01*
G01Y584561D02*
Y587386D01*
G01D02*
X544347Y588514D01*
G01X546535Y587829D02*
X544992Y589372D01*
G01X582286Y527653D02*
Y538405D01*
G01Y540645D02*
Y541645D01*
G01Y543885D02*
Y544885D01*
G01Y547125D02*
Y557095D01*
G01Y559335D02*
Y560335D01*
G01Y562575D02*
Y563575D01*
G01Y565815D02*
Y576259D01*
G01Y578499D02*
Y579499D01*
G01Y581739D02*
Y582739D01*
G01Y584979D02*
Y587593D01*
G01D02*
X581365Y588514D01*
G01X583346Y588034D02*
X580266Y591114D01*
G01X540375Y578214D02*
Y579368D01*
G01Y581608D02*
Y582608D01*
G01Y584848D02*
Y586986D01*
G01X541435Y587429D02*
X539992Y588872D01*
G01X540375Y578214D02*
Y579368D01*
G01Y581608D02*
Y582608D01*
G01Y584848D02*
Y586986D01*
G01X541435Y587429D02*
X539992Y588872D01*
G01X577186Y578089D02*
Y579285D01*
G01Y581525D02*
Y582637D01*
G01Y584653D02*
Y587380D01*
G01D02*
X576266Y588300D01*
G01X578246Y587820D02*
X575166Y590900D01*
G01X545475Y528044D02*
Y538014D01*
G01Y540254D02*
Y541254D01*
G01Y543494D02*
Y544494D01*
G01Y546734D02*
Y556955D01*
G01Y559195D02*
Y560195D01*
G01Y562435D02*
Y563435D01*
G01Y565675D02*
Y575841D01*
G01Y578081D02*
Y579081D01*
G01Y581321D02*
Y582321D01*
G01Y584561D02*
Y587386D01*
G01X546535Y587829D02*
X544992Y589372D01*
G01X545475Y587386D02*
X544347Y588514D01*
G01X582286Y527653D02*
Y538405D01*
G01Y540645D02*
Y541645D01*
G01Y543885D02*
Y544885D01*
G01Y547125D02*
Y557095D01*
G01Y559335D02*
Y560335D01*
G01Y562575D02*
Y563575D01*
G01Y565815D02*
Y576259D01*
G01Y578499D02*
Y579499D01*
G01Y581739D02*
Y582739D01*
G01Y584979D02*
Y587593D01*
G01X583346Y588034D02*
X580266Y591114D01*
G01X582286Y587593D02*
X581365Y588514D01*
G01X577186Y578089D02*
Y579285D01*
G01Y581525D02*
Y582637D01*
G01Y584653D02*
Y587380D01*
G01X578246Y587820D02*
X575166Y590900D01*
G01X577186Y587380D02*
X576266Y588300D01*
G01X545475Y528044D02*
Y538014D01*
G01Y540254D02*
Y541254D01*
G01Y543494D02*
Y544494D01*
G01Y546734D02*
Y556955D01*
G01Y559195D02*
Y560195D01*
G01Y562435D02*
Y563435D01*
G01Y565675D02*
Y575841D01*
G01Y578081D02*
Y579081D01*
G01Y581321D02*
Y582321D01*
G01Y584561D02*
Y587386D01*
G01D02*
X544347Y588514D01*
G01X546535Y587829D02*
X544992Y589372D01*
G01X582286Y527653D02*
Y538405D01*
G01Y540645D02*
Y541645D01*
G01Y543885D02*
Y544885D01*
G01Y547125D02*
Y557095D01*
G01Y559335D02*
Y560335D01*
G01Y562575D02*
Y563575D01*
G01Y565815D02*
Y576259D01*
G01Y578499D02*
Y579499D01*
G01Y581739D02*
Y582739D01*
G01Y584979D02*
Y587593D01*
G01D02*
X581365Y588514D01*
G01X583346Y588034D02*
X580266Y591114D01*
G01X573178Y590000D02*
Y608011D01*
G01X574238Y595890D02*
Y597260D01*
G01X573178Y590000D02*
Y608011D01*
G01X574238Y600940D02*
Y602360D01*
G01X542651Y595500D02*
X541980Y596171D01*
G01X541750Y594900D02*
X540920Y595730D01*
G01X541980Y596171D02*
Y597448D01*
G01Y600938D02*
Y601829D01*
G01X540920Y595730D02*
Y602270D01*
G01X541980Y601829D02*
X542751Y602600D01*
G01X540920Y602270D02*
X541750Y603100D01*
G01X579462Y595500D02*
X578791Y596171D01*
G01X578561Y594900D02*
X577731Y595730D01*
G01X578791Y596171D02*
Y597448D01*
G01Y600938D02*
Y601829D01*
G01X577731Y595730D02*
Y602270D01*
G01X578791Y601829D02*
X579562Y602600D01*
G01X577731Y602270D02*
X578561Y603100D01*
G01X574238Y595890D02*
Y597260D01*
G01Y600940D02*
Y602360D01*
G01X573178Y590000D02*
Y608011D01*
G01X541750Y594900D02*
X540920Y595730D01*
G01X542651Y595500D02*
X541980Y596171D01*
G01X540920Y595730D02*
Y602270D01*
G01X541980Y596171D02*
Y597448D01*
G01X540920Y595730D02*
Y602270D01*
G01X541980Y600938D02*
Y601829D01*
G01X540920Y602270D02*
X541750Y603100D01*
G01X541980Y601829D02*
X542751Y602600D01*
G01X578561Y594900D02*
X577731Y595730D01*
G01X579462Y595500D02*
X578791Y596171D01*
G01X577731Y595730D02*
Y602270D01*
G01X578791Y596171D02*
Y597448D01*
G01X577731Y595730D02*
Y602270D01*
G01X578791Y600938D02*
Y601829D01*
G01X577731Y602270D02*
X578561Y603100D01*
G01X578791Y601829D02*
X579562Y602600D01*
G01X573178Y590000D02*
Y608011D01*
G01X574238Y595890D02*
Y597260D01*
G01X573178Y590000D02*
Y608011D01*
G01X574238Y600940D02*
Y602360D01*
G01X542651Y595500D02*
X541980Y596171D01*
G01X541750Y594900D02*
X540920Y595730D01*
G01X541980Y596171D02*
Y597448D01*
G01Y600938D02*
Y601829D01*
G01X540920Y595730D02*
Y602270D01*
G01X541980Y601829D02*
X542751Y602600D01*
G01X540920Y602270D02*
X541750Y603100D01*
G01X579462Y595500D02*
X578791Y596171D01*
G01X578561Y594900D02*
X577731Y595730D01*
G01X578791Y596171D02*
Y597448D01*
G01Y600938D02*
Y601829D01*
G01X577731Y595730D02*
Y602270D01*
G01X578791Y601829D02*
X579562Y602600D01*
G01X577731Y602270D02*
X578561Y603100D01*
G01X574238Y595890D02*
Y597260D01*
G01Y600940D02*
Y602360D01*
G01X573178Y590000D02*
Y608011D01*
G01X541750Y594900D02*
X540920Y595730D01*
G01X542651Y595500D02*
X541980Y596171D01*
G01X540920Y595730D02*
Y602270D01*
G01X541980Y596171D02*
Y597448D01*
G01X540920Y595730D02*
Y602270D01*
G01X541980Y600938D02*
Y601829D01*
G01X540920Y602270D02*
X541750Y603100D01*
G01X541980Y601829D02*
X542751Y602600D01*
G01X578561Y594900D02*
X577731Y595730D01*
G01X579462Y595500D02*
X578791Y596171D01*
G01X577731Y595730D02*
Y602270D01*
G01X578791Y596171D02*
Y597448D01*
G01X577731Y595730D02*
Y602270D01*
G01X578791Y600938D02*
Y601829D01*
G01X577731Y602270D02*
X578561Y603100D01*
G01X578791Y601829D02*
X579562Y602600D01*
G01X777156Y-47440D02*
G02Y-50100I0J-1330D01*
G01Y-46380D02*
G02Y-51160I0J-2390D01*
G01Y-46380D02*
G02Y-51160I0J-2390D01*
G01Y-47440D02*
G02Y-50100I0J-1330D01*
G01X784534Y13554D02*
Y21131D01*
G01X785594Y19620D02*
Y20688D01*
G01X784534Y21131D02*
X788408Y25005D01*
G01X785594Y20688D02*
X789468Y24562D01*
G01X786388Y14300D02*
X789494Y11194D01*
G01X784534Y13554D02*
Y21131D01*
G01X785594Y19620D02*
Y20688D01*
G01X784534Y21131D02*
X788408Y25005D01*
G01X785594Y20688D02*
X789468Y24562D01*
G01X786388Y14300D02*
X789494Y11194D01*
G01X785594Y19620D02*
Y20688D01*
G01X784534Y13554D02*
Y21131D01*
G01X785594Y20688D02*
X789468Y24562D01*
G01X784534Y21131D02*
X788408Y25005D01*
G01X786388Y14300D02*
X789494Y11194D01*
G01X785594Y19620D02*
Y20688D01*
G01X784534Y13554D02*
Y21131D01*
G01X785594Y20688D02*
X789468Y24562D01*
G01X784534Y21131D02*
X788408Y25005D01*
G01X786388Y14300D02*
X789494Y11194D01*
G01X788408Y95960D02*
X785220Y99148D01*
G01X789468Y96403D02*
X786280Y99591D01*
G01X785220Y99148D02*
Y129088D01*
G01X786280Y99591D02*
Y110189D01*
G01X785220Y99148D02*
Y129088D01*
G01X786280Y112089D02*
Y113436D01*
G01X785220Y99148D02*
Y129088D01*
G01X786280Y115336D02*
Y117825D01*
G01X785220Y99148D02*
Y129088D01*
G01X786280Y119725D02*
Y122718D01*
G01X785220Y99148D02*
Y129088D01*
G01X786280Y124618D02*
Y128648D01*
G01X785220Y129088D02*
X786565Y130433D01*
G01X786280Y128648D02*
X787625Y129993D01*
G01X786565Y130433D02*
Y132435D01*
G01D02*
X785220Y133780D01*
G01X787625Y132875D02*
X786280Y134220D01*
G01X785220Y133780D02*
Y141747D01*
G01X786280Y134220D02*
Y141307D01*
G01X785220Y141747D02*
X786712Y143239D01*
G01X786280Y141307D02*
X787152Y142179D01*
G01X788408Y95960D02*
X785220Y99148D01*
G01X789468Y96403D02*
X786280Y99591D01*
G01X785220Y99148D02*
Y129088D01*
G01X786280Y99591D02*
Y110189D01*
G01X785220Y99148D02*
Y129088D01*
G01X786280Y112089D02*
Y113436D01*
G01X785220Y99148D02*
Y129088D01*
G01X786280Y115336D02*
Y117825D01*
G01X785220Y99148D02*
Y129088D01*
G01X786280Y119725D02*
Y122718D01*
G01X785220Y99148D02*
Y129088D01*
G01X786280Y124618D02*
Y128648D01*
G01X785220Y129088D02*
X786565Y130433D01*
G01X786280Y128648D02*
X787625Y129993D01*
G01X786565Y130433D02*
Y132435D01*
G01D02*
X785220Y133780D01*
G01X787625Y132875D02*
X786280Y134220D01*
G01X785220Y133780D02*
Y141747D01*
G01X786280Y134220D02*
Y141307D01*
G01X785220Y141747D02*
X786712Y143239D01*
G01X786280Y141307D02*
X787152Y142179D01*
G01X789468Y96403D02*
X786280Y99591D01*
G01X788408Y95960D02*
X785220Y99148D01*
G01X786280Y99591D02*
Y110189D01*
G01Y112089D02*
Y113436D01*
G01Y115336D02*
Y117825D01*
G01Y119725D02*
Y122718D01*
G01Y124618D02*
Y128648D01*
G01X785220Y99148D02*
Y129088D01*
G01X786280Y128648D02*
X787625Y129993D01*
G01X785220Y129088D02*
X786565Y130433D01*
G01D02*
Y132435D01*
G01X787625Y132875D02*
X786280Y134220D01*
G01X786565Y132435D02*
X785220Y133780D01*
G01X786280Y134220D02*
Y141307D01*
G01X785220Y133780D02*
Y141747D01*
G01X786280Y141307D02*
X787152Y142179D01*
G01X785220Y141747D02*
X786712Y143239D01*
G01X789468Y96403D02*
X786280Y99591D01*
G01X788408Y95960D02*
X785220Y99148D01*
G01X786280Y99591D02*
Y110189D01*
G01Y112089D02*
Y113436D01*
G01Y115336D02*
Y117825D01*
G01Y119725D02*
Y122718D01*
G01Y124618D02*
Y128648D01*
G01X785220Y99148D02*
Y129088D01*
G01X786280Y128648D02*
X787625Y129993D01*
G01X785220Y129088D02*
X786565Y130433D01*
G01D02*
Y132435D01*
G01X787625Y132875D02*
X786280Y134220D01*
G01X786565Y132435D02*
X785220Y133780D01*
G01X786280Y134220D02*
Y141307D01*
G01X785220Y133780D02*
Y141747D01*
G01X786280Y141307D02*
X787152Y142179D01*
G01X785220Y141747D02*
X786712Y143239D01*
G01X784400Y590000D02*
Y608011D01*
G01X785460Y595890D02*
Y597260D01*
G01X784400Y590000D02*
Y608011D01*
G01X785460Y600940D02*
Y602360D01*
G01X784400Y590000D02*
Y608011D01*
G01X785460Y595890D02*
Y597260D01*
G01X784400Y590000D02*
Y608011D01*
G01X785460Y600940D02*
Y602360D01*
G01Y595890D02*
Y597260D01*
G01Y600940D02*
Y602360D01*
G01X784400Y590000D02*
Y608011D01*
G01X785460Y595890D02*
Y597260D01*
G01Y600940D02*
Y602360D01*
G01X784400Y590000D02*
Y608011D01*
G01X788408Y25005D02*
Y78979D01*
G01X789468Y24562D02*
Y37780D01*
G01X788408Y25005D02*
Y78979D01*
G01Y25005D02*
Y78979D01*
G01Y25005D02*
Y78979D01*
G01Y25005D02*
Y78979D01*
G01X787487Y11700D02*
X788434Y10753D01*
G01D02*
Y8220D01*
G01Y4080D02*
Y3120D01*
G01Y-1220D02*
Y-4509D01*
G01X789494Y11194D02*
Y-4952D01*
G01X788434Y-4509D02*
X787723Y-5220D01*
G01X789494Y-4952D02*
X788166Y-6280D01*
G01X787723Y-5220D02*
X787207D01*
G01X788166Y-6280D02*
X787184D01*
G01X788408Y25005D02*
Y78979D01*
G01X789468Y24562D02*
Y37780D01*
G01X788408Y25005D02*
Y78979D01*
G01Y25005D02*
Y78979D01*
G01Y25005D02*
Y78979D01*
G01Y25005D02*
Y78979D01*
G01X787487Y11700D02*
X788434Y10753D01*
G01D02*
Y8220D01*
G01Y4080D02*
Y3120D01*
G01Y-1220D02*
Y-4509D01*
G01X789494Y11194D02*
Y-4952D01*
G01X788434Y-4509D02*
X787723Y-5220D01*
G01X789494Y-4952D02*
X788166Y-6280D01*
G01X787723Y-5220D02*
X787207D01*
G01X788166Y-6280D02*
X787184D01*
G01X789468Y24562D02*
Y37780D01*
G01X788408Y25005D02*
Y78979D01*
G01X787487Y11700D02*
X788434Y10753D01*
G01X789494Y11194D02*
Y-4952D01*
G01X788434Y10753D02*
Y8220D01*
G01X789494Y11194D02*
Y-4952D01*
G01X788434Y4080D02*
Y3120D01*
G01X789494Y11194D02*
Y-4952D01*
G01X788434Y-1220D02*
Y-4509D01*
G01X789494Y-4952D02*
X788166Y-6280D01*
G01X788434Y-4509D02*
X787723Y-5220D01*
G01X788166Y-6280D02*
X787184D01*
G01X787723Y-5220D02*
X787207D01*
G01X789468Y24562D02*
Y37780D01*
G01X788408Y25005D02*
Y78979D01*
G01X787487Y11700D02*
X788434Y10753D01*
G01X789494Y11194D02*
Y-4952D01*
G01X788434Y10753D02*
Y8220D01*
G01X789494Y11194D02*
Y-4952D01*
G01X788434Y4080D02*
Y3120D01*
G01X789494Y11194D02*
Y-4952D01*
G01X788434Y-1220D02*
Y-4509D01*
G01X789494Y-4952D02*
X788166Y-6280D01*
G01X788434Y-4509D02*
X787723Y-5220D01*
G01X788166Y-6280D02*
X787184D01*
G01X787723Y-5220D02*
X787207D01*
G01X790234Y18835D02*
Y21231D01*
G01X791294Y19920D02*
Y20788D01*
G01X790234Y21231D02*
X793508Y24505D01*
G01X791294Y20788D02*
X794568Y24062D01*
G01X793508Y24505D02*
Y97960D01*
G01X794568Y24062D02*
Y98403D01*
G01X791488Y11915D02*
X792586D01*
G01D02*
X793620Y10881D01*
G01X791488Y14514D02*
X794680Y11322D01*
G01X793620Y10881D02*
Y8106D01*
G01Y4280D02*
Y2907D01*
G01Y-1007D02*
Y-3628D01*
G01X794680Y11322D02*
Y-4068D01*
G01X793620Y-3628D02*
X792597Y-4651D01*
G01D02*
X791488D01*
G01X794680Y-4068D02*
X791488Y-7260D01*
G01X790234Y18835D02*
Y21231D01*
G01X791294Y19920D02*
Y20788D01*
G01X790234Y21231D02*
X793508Y24505D01*
G01X791294Y20788D02*
X794568Y24062D01*
G01X793508Y24505D02*
Y97960D01*
G01X794568Y24062D02*
Y98403D01*
G01X791488Y11915D02*
X792586D01*
G01D02*
X793620Y10881D01*
G01X791488Y14514D02*
X794680Y11322D01*
G01X793620Y10881D02*
Y8106D01*
G01Y4280D02*
Y2907D01*
G01Y-1007D02*
Y-3628D01*
G01X794680Y11322D02*
Y-4068D01*
G01X793620Y-3628D02*
X792597Y-4651D01*
G01D02*
X791488D01*
G01X794680Y-4068D02*
X791488Y-7260D01*
G01X825219Y101210D02*
Y25005D01*
G01Y101210D02*
Y25005D01*
G01Y101210D02*
Y25005D01*
G01Y101210D02*
Y25005D01*
G01X826279Y37180D02*
Y27122D01*
G01X825219Y25005D02*
X821345Y21131D01*
G01X826779Y25062D02*
X822405Y20688D01*
G01X821345Y21131D02*
Y13554D01*
G01X822405Y20688D02*
Y19620D01*
G01X824018Y-5220D02*
X824534D01*
G01X823995Y-6280D02*
X824977D01*
G01X824534Y-5220D02*
X825245Y-4509D01*
G01X824977Y-6280D02*
X826305Y-4952D01*
G01X825245Y-4509D02*
Y-1220D01*
G01Y3120D02*
Y4080D01*
G01Y8220D02*
Y10753D01*
G01X826305Y-4952D02*
Y11194D01*
G01X825245Y10753D02*
X824298Y11700D01*
G01X826305Y11194D02*
X823199Y14300D01*
G01X825219Y101210D02*
Y25005D01*
G01Y101210D02*
Y25005D01*
G01Y101210D02*
Y25005D01*
G01Y101210D02*
Y25005D01*
G01X826279Y37180D02*
Y27122D01*
G01X825219Y25005D02*
X821345Y21131D01*
G01X826779Y25062D02*
X822405Y20688D01*
G01X821345Y21131D02*
Y13554D01*
G01X822405Y20688D02*
Y19620D01*
G01X824018Y-5220D02*
X824534D01*
G01X823995Y-6280D02*
X824977D01*
G01X824534Y-5220D02*
X825245Y-4509D01*
G01X824977Y-6280D02*
X826305Y-4952D01*
G01X825245Y-4509D02*
Y-1220D01*
G01Y3120D02*
Y4080D01*
G01Y8220D02*
Y10753D01*
G01X826305Y-4952D02*
Y11194D01*
G01X825245Y10753D02*
X824298Y11700D01*
G01X826305Y11194D02*
X823199Y14300D01*
G01X827045Y18745D02*
Y21231D01*
G01X828105Y19920D02*
Y20788D01*
G01X827045Y21231D02*
X830319Y24505D01*
G01X828105Y20788D02*
X829079Y21762D01*
G01X830319Y24505D02*
Y102012D01*
G01X831379Y26134D02*
Y102452D01*
G01X828299Y-4651D02*
X829408D01*
G01D02*
X830431Y-3628D01*
G01X828299Y-7260D02*
X831491Y-4068D01*
G01X830431Y-3628D02*
Y-1007D01*
G01Y2907D02*
Y4280D01*
G01Y8106D02*
Y10881D01*
G01X831491Y-4068D02*
Y11322D01*
G01X830431Y10881D02*
X829397Y11915D01*
G01D02*
X828299D01*
G01X831491Y11322D02*
X828299Y14514D01*
G01X827045Y18745D02*
Y21231D01*
G01X828105Y19920D02*
Y20788D01*
G01X827045Y21231D02*
X830319Y24505D01*
G01X828105Y20788D02*
X829079Y21762D01*
G01X830319Y24505D02*
Y102012D01*
G01X831379Y26134D02*
Y102452D01*
G01X828299Y-4651D02*
X829408D01*
G01D02*
X830431Y-3628D01*
G01X828299Y-7260D02*
X831491Y-4068D01*
G01X830431Y-3628D02*
Y-1007D01*
G01Y2907D02*
Y4280D01*
G01Y8106D02*
Y10881D01*
G01X831491Y-4068D02*
Y11322D01*
G01X830431Y10881D02*
X829397Y11915D01*
G01D02*
X828299D01*
G01X831491Y11322D02*
X828299Y14514D01*
G01X791294Y19920D02*
Y20788D01*
G01X790234Y18835D02*
Y21231D01*
G01X791294Y20788D02*
X794568Y24062D01*
G01X790234Y21231D02*
X793508Y24505D01*
G01X794568Y24062D02*
Y98403D01*
G01X793508Y24505D02*
Y97960D01*
G01X791488Y14514D02*
X794680Y11322D01*
G01X791488Y11915D02*
X792586D01*
G01X791488Y14514D02*
X794680Y11322D01*
G01X792586Y11915D02*
X793620Y10881D01*
G01X794680Y11322D02*
Y-4068D01*
G01X793620Y10881D02*
Y8106D01*
G01X794680Y11322D02*
Y-4068D01*
G01X793620Y4280D02*
Y2907D01*
G01X794680Y11322D02*
Y-4068D01*
G01X793620Y-1007D02*
Y-3628D01*
G01X794680Y-4068D02*
X791488Y-7260D01*
G01X793620Y-3628D02*
X792597Y-4651D01*
G01X794680Y-4068D02*
X791488Y-7260D01*
G01X792597Y-4651D02*
X791488D01*
G01X791294Y19920D02*
Y20788D01*
G01X790234Y18835D02*
Y21231D01*
G01X791294Y20788D02*
X794568Y24062D01*
G01X790234Y21231D02*
X793508Y24505D01*
G01X794568Y24062D02*
Y98403D01*
G01X793508Y24505D02*
Y97960D01*
G01X791488Y14514D02*
X794680Y11322D01*
G01X791488Y11915D02*
X792586D01*
G01X791488Y14514D02*
X794680Y11322D01*
G01X792586Y11915D02*
X793620Y10881D01*
G01X794680Y11322D02*
Y-4068D01*
G01X793620Y10881D02*
Y8106D01*
G01X794680Y11322D02*
Y-4068D01*
G01X793620Y4280D02*
Y2907D01*
G01X794680Y11322D02*
Y-4068D01*
G01X793620Y-1007D02*
Y-3628D01*
G01X794680Y-4068D02*
X791488Y-7260D01*
G01X793620Y-3628D02*
X792597Y-4651D01*
G01X794680Y-4068D02*
X791488Y-7260D01*
G01X792597Y-4651D02*
X791488D01*
G01X826279Y37180D02*
Y27122D01*
G01X825219Y101210D02*
Y25005D01*
G01X826779Y25062D02*
X822405Y20688D01*
G01X825219Y25005D02*
X821345Y21131D01*
G01X822405Y20688D02*
Y19620D01*
G01X821345Y21131D02*
Y13554D01*
G01X823995Y-6280D02*
X824977D01*
G01X824018Y-5220D02*
X824534D01*
G01X824977Y-6280D02*
X826305Y-4952D01*
G01X824534Y-5220D02*
X825245Y-4509D01*
G01X826305Y-4952D02*
Y11194D01*
G01X825245Y-4509D02*
Y-1220D01*
G01X826305Y-4952D02*
Y11194D01*
G01X825245Y3120D02*
Y4080D01*
G01X826305Y-4952D02*
Y11194D01*
G01X825245Y8220D02*
Y10753D01*
G01X826305Y11194D02*
X823199Y14300D01*
G01X825245Y10753D02*
X824298Y11700D01*
G01X826279Y37180D02*
Y27122D01*
G01X825219Y101210D02*
Y25005D01*
G01X826779Y25062D02*
X822405Y20688D01*
G01X825219Y25005D02*
X821345Y21131D01*
G01X822405Y20688D02*
Y19620D01*
G01X821345Y21131D02*
Y13554D01*
G01X823995Y-6280D02*
X824977D01*
G01X824018Y-5220D02*
X824534D01*
G01X824977Y-6280D02*
X826305Y-4952D01*
G01X824534Y-5220D02*
X825245Y-4509D01*
G01X826305Y-4952D02*
Y11194D01*
G01X825245Y-4509D02*
Y-1220D01*
G01X826305Y-4952D02*
Y11194D01*
G01X825245Y3120D02*
Y4080D01*
G01X826305Y-4952D02*
Y11194D01*
G01X825245Y8220D02*
Y10753D01*
G01X826305Y11194D02*
X823199Y14300D01*
G01X825245Y10753D02*
X824298Y11700D01*
G01X828299Y-7260D02*
X831491Y-4068D01*
G01X828299Y-4651D02*
X829408D01*
G01X828299Y-7260D02*
X831491Y-4068D01*
G01X829408Y-4651D02*
X830431Y-3628D01*
G01X831491Y-4068D02*
Y11322D01*
G01X830431Y-3628D02*
Y-1007D01*
G01X831491Y-4068D02*
Y11322D01*
G01X830431Y2907D02*
Y4280D01*
G01X831491Y-4068D02*
Y11322D01*
G01X830431Y8106D02*
Y10881D01*
G01X831491Y11322D02*
X828299Y14514D01*
G01X830431Y10881D02*
X829397Y11915D01*
G01X831491Y11322D02*
X828299Y14514D01*
G01X829397Y11915D02*
X828299D01*
G01X828105Y19920D02*
Y20788D01*
G01X827045Y18745D02*
Y21231D01*
G01X828105Y20788D02*
X829079Y21762D01*
G01X827045Y21231D02*
X830319Y24505D01*
G01X831379Y26134D02*
Y102452D01*
G01X830319Y24505D02*
Y102012D01*
G01X828299Y-7260D02*
X831491Y-4068D01*
G01X828299Y-4651D02*
X829408D01*
G01X828299Y-7260D02*
X831491Y-4068D01*
G01X829408Y-4651D02*
X830431Y-3628D01*
G01X831491Y-4068D02*
Y11322D01*
G01X830431Y-3628D02*
Y-1007D01*
G01X831491Y-4068D02*
Y11322D01*
G01X830431Y2907D02*
Y4280D01*
G01X831491Y-4068D02*
Y11322D01*
G01X830431Y8106D02*
Y10881D01*
G01X831491Y11322D02*
X828299Y14514D01*
G01X830431Y10881D02*
X829397Y11915D01*
G01X831491Y11322D02*
X828299Y14514D01*
G01X829397Y11915D02*
X828299D01*
G01X828105Y19920D02*
Y20788D01*
G01X827045Y18745D02*
Y21231D01*
G01X828105Y20788D02*
X829079Y21762D01*
G01X827045Y21231D02*
X830319Y24505D01*
G01X831379Y26134D02*
Y102452D01*
G01X830319Y24505D02*
Y102012D01*
G01X789468Y40020D02*
Y40780D01*
G01Y43020D02*
Y43780D01*
G01Y46020D02*
Y55680D01*
G01Y57920D02*
Y78536D01*
G01X788408Y78979D02*
X789320Y79891D01*
G01X789468Y78536D02*
X790380Y79448D01*
G01X789320Y79891D02*
Y82497D01*
G01X790380Y79448D02*
Y82940D01*
G01X789320Y82497D02*
X788408Y83409D01*
G01X790380Y82940D02*
X789468Y83852D01*
G01X788408Y83409D02*
Y95960D01*
G01X789468Y83852D02*
Y96403D01*
G01Y40020D02*
Y40780D01*
G01Y43020D02*
Y43780D01*
G01Y46020D02*
Y55680D01*
G01Y57920D02*
Y78536D01*
G01X788408Y78979D02*
X789320Y79891D01*
G01X789468Y78536D02*
X790380Y79448D01*
G01X789320Y79891D02*
Y82497D01*
G01X790380Y79448D02*
Y82940D01*
G01X789320Y82497D02*
X788408Y83409D01*
G01X790380Y82940D02*
X789468Y83852D01*
G01X788408Y83409D02*
Y95960D01*
G01X789468Y83852D02*
Y96403D01*
G01Y40020D02*
Y40780D01*
G01Y43020D02*
Y43780D01*
G01Y46020D02*
Y55680D01*
G01Y57920D02*
Y78536D01*
G01D02*
X790380Y79448D01*
G01X788408Y78979D02*
X789320Y79891D01*
G01X790380Y79448D02*
Y82940D01*
G01X789320Y79891D02*
Y82497D01*
G01X790380Y82940D02*
X789468Y83852D01*
G01X789320Y82497D02*
X788408Y83409D01*
G01X789468Y83852D02*
Y96403D01*
G01X788408Y83409D02*
Y95960D01*
G01X789468Y40020D02*
Y40780D01*
G01Y43020D02*
Y43780D01*
G01Y46020D02*
Y55680D01*
G01Y57920D02*
Y78536D01*
G01D02*
X790380Y79448D01*
G01X788408Y78979D02*
X789320Y79891D01*
G01X790380Y79448D02*
Y82940D01*
G01X789320Y79891D02*
Y82497D01*
G01X790380Y82940D02*
X789468Y83852D01*
G01X789320Y82497D02*
X788408Y83409D01*
G01X789468Y83852D02*
Y96403D01*
G01X788408Y83409D02*
Y95960D01*
G01X826279Y101653D02*
Y45420D01*
G01Y43180D02*
Y42420D01*
G01Y40180D02*
Y39420D01*
G01Y101653D02*
Y45420D01*
G01Y43180D02*
Y42420D01*
G01Y40180D02*
Y39420D01*
G01Y101653D02*
Y45420D01*
G01Y43180D02*
Y42420D01*
G01Y40180D02*
Y39420D01*
G01Y101653D02*
Y45420D01*
G01Y43180D02*
Y42420D01*
G01Y40180D02*
Y39420D01*
G01X787625Y129993D02*
Y132875D01*
G01X786712Y143239D02*
X787911D01*
G01X787152Y142179D02*
X788351D01*
G01X787911Y143239D02*
X789031Y144359D01*
G01X788351Y142179D02*
X790095Y143923D01*
G01X789031Y144359D02*
Y146231D01*
G01X790095Y143923D02*
Y146667D01*
G01X789031Y146231D02*
X786914Y148348D01*
G01X790095Y146667D02*
X787974Y148788D01*
G01X786914Y148348D02*
Y152804D01*
G01X787974Y148788D02*
Y152364D01*
G01X786914Y152804D02*
X788042Y153932D01*
G01X787974Y152364D02*
X788482Y152872D01*
G01X788042Y153932D02*
X794674D01*
G01X788482Y152872D02*
X795114D01*
G01X794674Y153932D02*
X796616Y155874D01*
G01X795114Y152872D02*
X797676Y155434D01*
G01X796616Y155874D02*
Y160868D01*
G01X797676Y155434D02*
Y160428D01*
G01X787625Y129993D02*
Y132875D01*
G01X786712Y143239D02*
X787911D01*
G01X787152Y142179D02*
X788351D01*
G01X787911Y143239D02*
X789031Y144359D01*
G01X788351Y142179D02*
X790095Y143923D01*
G01X789031Y144359D02*
Y146231D01*
G01X790095Y143923D02*
Y146667D01*
G01X789031Y146231D02*
X786914Y148348D01*
G01X790095Y146667D02*
X787974Y148788D01*
G01X786914Y148348D02*
Y152804D01*
G01X787974Y148788D02*
Y152364D01*
G01X786914Y152804D02*
X788042Y153932D01*
G01X787974Y152364D02*
X788482Y152872D01*
G01X788042Y153932D02*
X794674D01*
G01X788482Y152872D02*
X795114D01*
G01X794674Y153932D02*
X796616Y155874D01*
G01X795114Y152872D02*
X797676Y155434D01*
G01X796616Y155874D02*
Y160868D01*
G01X797676Y155434D02*
Y160428D01*
G01X787625Y129993D02*
Y132875D01*
G01X787152Y142179D02*
X788351D01*
G01X786712Y143239D02*
X787911D01*
G01X788351Y142179D02*
X790095Y143923D01*
G01X787911Y143239D02*
X789031Y144359D01*
G01X790095Y143923D02*
Y146667D01*
G01X789031Y144359D02*
Y146231D01*
G01X790095Y146667D02*
X787974Y148788D01*
G01X789031Y146231D02*
X786914Y148348D01*
G01X787974Y148788D02*
Y152364D01*
G01X786914Y148348D02*
Y152804D01*
G01X787974Y152364D02*
X788482Y152872D01*
G01X786914Y152804D02*
X788042Y153932D01*
G01X788482Y152872D02*
X795114D01*
G01X788042Y153932D02*
X794674D01*
G01X795114Y152872D02*
X797676Y155434D01*
G01X794674Y153932D02*
X796616Y155874D01*
G01X797676Y155434D02*
Y160428D01*
G01X796616Y155874D02*
Y160868D01*
G01X787625Y129993D02*
Y132875D01*
G01X787152Y142179D02*
X788351D01*
G01X786712Y143239D02*
X787911D01*
G01X788351Y142179D02*
X790095Y143923D01*
G01X787911Y143239D02*
X789031Y144359D01*
G01X790095Y143923D02*
Y146667D01*
G01X789031Y144359D02*
Y146231D01*
G01X790095Y146667D02*
X787974Y148788D01*
G01X789031Y146231D02*
X786914Y148348D01*
G01X787974Y148788D02*
Y152364D01*
G01X786914Y148348D02*
Y152804D01*
G01X787974Y152364D02*
X788482Y152872D01*
G01X786914Y152804D02*
X788042Y153932D01*
G01X788482Y152872D02*
X795114D01*
G01X788042Y153932D02*
X794674D01*
G01X795114Y152872D02*
X797676Y155434D01*
G01X794674Y153932D02*
X796616Y155874D01*
G01X797676Y155434D02*
Y160428D01*
G01X796616Y155874D02*
Y160868D01*
G01X793508Y97960D02*
X789020Y102448D01*
G01X794568Y98403D02*
X790080Y102891D01*
G01X789020Y102448D02*
Y127382D01*
G01X790080Y102891D02*
Y126939D01*
G01X789020Y127382D02*
X790509Y128871D01*
G01X790080Y126939D02*
X790952Y127811D01*
G01X790509Y128871D02*
X794664D01*
G01X790952Y127811D02*
X795104D01*
G01X794664Y128871D02*
X795536Y129743D01*
G01X795104Y127811D02*
X796596Y129303D01*
G01X795536Y129743D02*
Y132139D01*
G01X796596Y129303D02*
Y132579D01*
G01X795536Y132139D02*
X794564Y133111D01*
G01X796596Y132579D02*
X795004Y134171D01*
G01X794564Y133111D02*
X791261D01*
G01X795004Y134171D02*
X791701D01*
G01X791261Y133111D02*
X789218Y135154D01*
G01X791701Y134171D02*
X790278Y135594D01*
G01X789218Y135154D02*
Y137961D01*
G01X790278Y135594D02*
Y137521D01*
G01X789218Y137961D02*
X790737Y139480D01*
G01X790278Y137521D02*
X791177Y138420D01*
G01X790737Y139480D02*
X792897D01*
G01X791177Y138420D02*
X793337D01*
G01X792897Y139480D02*
X793508Y140091D01*
G01X793337Y138420D02*
X794568Y139651D01*
G01X793508Y140091D02*
Y148332D01*
G01X794568Y139651D02*
Y147892D01*
G01X793508Y148332D02*
X807919Y162743D01*
G01X794568Y147892D02*
X808979Y162303D01*
G01X793508Y97960D02*
X789020Y102448D01*
G01X794568Y98403D02*
X790080Y102891D01*
G01X789020Y102448D02*
Y127382D01*
G01X790080Y102891D02*
Y126939D01*
G01X789020Y127382D02*
X790509Y128871D01*
G01X790080Y126939D02*
X790952Y127811D01*
G01X790509Y128871D02*
X794664D01*
G01X790952Y127811D02*
X795104D01*
G01X794664Y128871D02*
X795536Y129743D01*
G01X795104Y127811D02*
X796596Y129303D01*
G01X795536Y129743D02*
Y132139D01*
G01X796596Y129303D02*
Y132579D01*
G01X795536Y132139D02*
X794564Y133111D01*
G01X796596Y132579D02*
X795004Y134171D01*
G01X794564Y133111D02*
X791261D01*
G01X795004Y134171D02*
X791701D01*
G01X791261Y133111D02*
X789218Y135154D01*
G01X791701Y134171D02*
X790278Y135594D01*
G01X789218Y135154D02*
Y137961D01*
G01X790278Y135594D02*
Y137521D01*
G01X789218Y137961D02*
X790737Y139480D01*
G01X790278Y137521D02*
X791177Y138420D01*
G01X790737Y139480D02*
X792897D01*
G01X791177Y138420D02*
X793337D01*
G01X792897Y139480D02*
X793508Y140091D01*
G01X793337Y138420D02*
X794568Y139651D01*
G01X793508Y140091D02*
Y148332D01*
G01X794568Y139651D02*
Y147892D01*
G01X793508Y148332D02*
X807919Y162743D01*
G01X794568Y147892D02*
X808979Y162303D01*
G01X840592Y161260D02*
X821920Y142588D01*
G01X841032Y160200D02*
X822980Y142148D01*
G01X821920Y142588D02*
Y140480D01*
G01X822980Y142148D02*
Y140920D01*
G01X821920Y140480D02*
X823312Y139088D01*
G01X822980Y140920D02*
X823752Y140148D01*
G01X821920Y140480D02*
X823312Y139088D01*
G01D02*
X825008D01*
G01X823752Y140148D02*
X825448D01*
G01X823312Y139088D02*
X825008D01*
G01D02*
X825508Y138588D01*
G01X825448Y140148D02*
X826568Y139028D01*
G01X825508Y138588D02*
Y135348D01*
G01X826568Y139028D02*
Y134908D01*
G01X825508Y135348D02*
X825008Y134848D01*
G01D02*
X823509D01*
G01X826568Y134908D02*
X825448Y133788D01*
G01X825008Y134848D02*
X823509D01*
G01X825448Y133788D02*
X823952D01*
G01X823509Y134848D02*
X822020Y133359D01*
G01X823952Y133788D02*
X823080Y132916D01*
G01X822020Y133359D02*
Y104409D01*
G01X823080Y132916D02*
Y104852D01*
G01X822020Y104409D02*
X825219Y101210D01*
G01X823080Y104852D02*
X826279Y101653D01*
G01X840592Y161260D02*
X821920Y142588D01*
G01X841032Y160200D02*
X822980Y142148D01*
G01X821920Y142588D02*
Y140480D01*
G01X822980Y142148D02*
Y140920D01*
G01X821920Y140480D02*
X823312Y139088D01*
G01X822980Y140920D02*
X823752Y140148D01*
G01X821920Y140480D02*
X823312Y139088D01*
G01D02*
X825008D01*
G01X823752Y140148D02*
X825448D01*
G01X823312Y139088D02*
X825008D01*
G01D02*
X825508Y138588D01*
G01X825448Y140148D02*
X826568Y139028D01*
G01X825508Y138588D02*
Y135348D01*
G01X826568Y139028D02*
Y134908D01*
G01X825508Y135348D02*
X825008Y134848D01*
G01D02*
X823509D01*
G01X826568Y134908D02*
X825448Y133788D01*
G01X825008Y134848D02*
X823509D01*
G01X825448Y133788D02*
X823952D01*
G01X823509Y134848D02*
X822020Y133359D01*
G01X823952Y133788D02*
X823080Y132916D01*
G01X822020Y133359D02*
Y104409D01*
G01X823080Y132916D02*
Y104852D01*
G01X822020Y104409D02*
X825219Y101210D01*
G01X823080Y104852D02*
X826279Y101653D01*
G01X830319Y102012D02*
X825820Y106511D01*
G01X831379Y102452D02*
X826880Y106951D01*
G01X825820Y106511D02*
Y119885D01*
G01X826880Y106951D02*
Y119442D01*
G01X825820Y119885D02*
X827309Y121374D01*
G01X826880Y119442D02*
X827752Y120314D01*
G01X827309Y121374D02*
X828551D01*
G01X827752Y120314D02*
X828991D01*
G01X828551Y121374D02*
X829520Y122343D01*
G01X828991Y120314D02*
X830580Y121903D01*
G01X829520Y122343D02*
Y124785D01*
G01X830580Y121903D02*
Y125225D01*
G01X829520Y124785D02*
X828691Y125614D01*
G01X830580Y125225D02*
X829131Y126674D01*
G01X828691Y125614D02*
X827512D01*
G01D02*
X826020Y127106D01*
G01X829131Y126674D02*
X827952D01*
G01X827512Y125614D02*
X826020Y127106D01*
G01X827952Y126674D02*
X827080Y127546D01*
G01X826020Y127106D02*
Y130159D01*
G01X827080Y127546D02*
Y129719D01*
G01X826020Y130159D02*
X829820Y133959D01*
G01X827080Y129719D02*
X830880Y133519D01*
G01X829820Y133959D02*
Y143719D01*
G01X830880Y133519D02*
Y143279D01*
G01X829820Y143719D02*
X841561Y155460D01*
G01X830880Y143279D02*
X842001Y154400D01*
G01X841561Y155460D02*
X845861D01*
G01X842001Y154400D02*
X846301D01*
G01X845861Y155460D02*
X849802Y159401D01*
G01X846301Y154400D02*
X850862Y158961D01*
G01X830319Y102012D02*
X825820Y106511D01*
G01X831379Y102452D02*
X826880Y106951D01*
G01X825820Y106511D02*
Y119885D01*
G01X826880Y106951D02*
Y119442D01*
G01X825820Y119885D02*
X827309Y121374D01*
G01X826880Y119442D02*
X827752Y120314D01*
G01X827309Y121374D02*
X828551D01*
G01X827752Y120314D02*
X828991D01*
G01X828551Y121374D02*
X829520Y122343D01*
G01X828991Y120314D02*
X830580Y121903D01*
G01X829520Y122343D02*
Y124785D01*
G01X830580Y121903D02*
Y125225D01*
G01X829520Y124785D02*
X828691Y125614D01*
G01X830580Y125225D02*
X829131Y126674D01*
G01X828691Y125614D02*
X827512D01*
G01D02*
X826020Y127106D01*
G01X829131Y126674D02*
X827952D01*
G01X827512Y125614D02*
X826020Y127106D01*
G01X827952Y126674D02*
X827080Y127546D01*
G01X826020Y127106D02*
Y130159D01*
G01X827080Y127546D02*
Y129719D01*
G01X826020Y130159D02*
X829820Y133959D01*
G01X827080Y129719D02*
X830880Y133519D01*
G01X829820Y133959D02*
Y143719D01*
G01X830880Y133519D02*
Y143279D01*
G01X829820Y143719D02*
X841561Y155460D01*
G01X830880Y143279D02*
X842001Y154400D01*
G01X841561Y155460D02*
X845861D01*
G01X842001Y154400D02*
X846301D01*
G01X845861Y155460D02*
X849802Y159401D01*
G01X846301Y154400D02*
X850862Y158961D01*
G01X794568Y98403D02*
X790080Y102891D01*
G01X793508Y97960D02*
X789020Y102448D01*
G01X790080Y102891D02*
Y126939D01*
G01X789020Y102448D02*
Y127382D01*
G01X790080Y126939D02*
X790952Y127811D01*
G01X789020Y127382D02*
X790509Y128871D01*
G01X790952Y127811D02*
X795104D01*
G01X790509Y128871D02*
X794664D01*
G01X795104Y127811D02*
X796596Y129303D01*
G01X794664Y128871D02*
X795536Y129743D01*
G01X796596Y129303D02*
Y132579D01*
G01X795536Y129743D02*
Y132139D01*
G01X796596Y132579D02*
X795004Y134171D01*
G01X795536Y132139D02*
X794564Y133111D01*
G01X795004Y134171D02*
X791701D01*
G01X794564Y133111D02*
X791261D01*
G01X791701Y134171D02*
X790278Y135594D01*
G01X791261Y133111D02*
X789218Y135154D01*
G01X790278Y135594D02*
Y137521D01*
G01X789218Y135154D02*
Y137961D01*
G01X790278Y137521D02*
X791177Y138420D01*
G01X789218Y137961D02*
X790737Y139480D01*
G01X791177Y138420D02*
X793337D01*
G01X790737Y139480D02*
X792897D01*
G01X793337Y138420D02*
X794568Y139651D01*
G01X792897Y139480D02*
X793508Y140091D01*
G01X794568Y139651D02*
Y147892D01*
G01X793508Y140091D02*
Y148332D01*
G01X794568Y147892D02*
X808979Y162303D01*
G01X793508Y148332D02*
X807919Y162743D01*
G01X794568Y98403D02*
X790080Y102891D01*
G01X793508Y97960D02*
X789020Y102448D01*
G01X790080Y102891D02*
Y126939D01*
G01X789020Y102448D02*
Y127382D01*
G01X790080Y126939D02*
X790952Y127811D01*
G01X789020Y127382D02*
X790509Y128871D01*
G01X790952Y127811D02*
X795104D01*
G01X790509Y128871D02*
X794664D01*
G01X795104Y127811D02*
X796596Y129303D01*
G01X794664Y128871D02*
X795536Y129743D01*
G01X796596Y129303D02*
Y132579D01*
G01X795536Y129743D02*
Y132139D01*
G01X796596Y132579D02*
X795004Y134171D01*
G01X795536Y132139D02*
X794564Y133111D01*
G01X795004Y134171D02*
X791701D01*
G01X794564Y133111D02*
X791261D01*
G01X791701Y134171D02*
X790278Y135594D01*
G01X791261Y133111D02*
X789218Y135154D01*
G01X790278Y135594D02*
Y137521D01*
G01X789218Y135154D02*
Y137961D01*
G01X790278Y137521D02*
X791177Y138420D01*
G01X789218Y137961D02*
X790737Y139480D01*
G01X791177Y138420D02*
X793337D01*
G01X790737Y139480D02*
X792897D01*
G01X793337Y138420D02*
X794568Y139651D01*
G01X792897Y139480D02*
X793508Y140091D01*
G01X794568Y139651D02*
Y147892D01*
G01X793508Y140091D02*
Y148332D01*
G01X794568Y147892D02*
X808979Y162303D01*
G01X793508Y148332D02*
X807919Y162743D01*
G01X841032Y160200D02*
X822980Y142148D01*
G01X840592Y161260D02*
X821920Y142588D01*
G01X822980Y142148D02*
Y140920D01*
G01X821920Y142588D02*
Y140480D01*
G01X822980Y140920D02*
X823752Y140148D01*
G01D02*
X825448D01*
G01X821920Y140480D02*
X823312Y139088D01*
G01X823752Y140148D02*
X825448D01*
G01D02*
X826568Y139028D01*
G01X823312Y139088D02*
X825008D01*
G01X825448Y140148D02*
X826568Y139028D01*
G01X825008Y139088D02*
X825508Y138588D01*
G01X826568Y139028D02*
Y134908D01*
G01X825508Y138588D02*
Y135348D01*
G01X826568Y134908D02*
X825448Y133788D01*
G01X825508Y135348D02*
X825008Y134848D01*
G01X826568Y134908D02*
X825448Y133788D01*
G01D02*
X823952D01*
G01X825008Y134848D02*
X823509D01*
G01X823952Y133788D02*
X823080Y132916D01*
G01X823509Y134848D02*
X822020Y133359D01*
G01X823080Y132916D02*
Y104852D01*
G01X822020Y133359D02*
Y104409D01*
G01X823080Y104852D02*
X826279Y101653D01*
G01X822020Y104409D02*
X825219Y101210D01*
G01X841032Y160200D02*
X822980Y142148D01*
G01X840592Y161260D02*
X821920Y142588D01*
G01X822980Y142148D02*
Y140920D01*
G01X821920Y142588D02*
Y140480D01*
G01X822980Y140920D02*
X823752Y140148D01*
G01D02*
X825448D01*
G01X821920Y140480D02*
X823312Y139088D01*
G01X823752Y140148D02*
X825448D01*
G01D02*
X826568Y139028D01*
G01X823312Y139088D02*
X825008D01*
G01X825448Y140148D02*
X826568Y139028D01*
G01X825008Y139088D02*
X825508Y138588D01*
G01X826568Y139028D02*
Y134908D01*
G01X825508Y138588D02*
Y135348D01*
G01X826568Y134908D02*
X825448Y133788D01*
G01X825508Y135348D02*
X825008Y134848D01*
G01X826568Y134908D02*
X825448Y133788D01*
G01D02*
X823952D01*
G01X825008Y134848D02*
X823509D01*
G01X823952Y133788D02*
X823080Y132916D01*
G01X823509Y134848D02*
X822020Y133359D01*
G01X823080Y132916D02*
Y104852D01*
G01X822020Y133359D02*
Y104409D01*
G01X823080Y104852D02*
X826279Y101653D01*
G01X822020Y104409D02*
X825219Y101210D01*
G01X831379Y102452D02*
X826880Y106951D01*
G01X830319Y102012D02*
X825820Y106511D01*
G01X826880Y106951D02*
Y119442D01*
G01X825820Y106511D02*
Y119885D01*
G01X826880Y119442D02*
X827752Y120314D01*
G01X825820Y119885D02*
X827309Y121374D01*
G01X827752Y120314D02*
X828991D01*
G01X827309Y121374D02*
X828551D01*
G01X828991Y120314D02*
X830580Y121903D01*
G01X828551Y121374D02*
X829520Y122343D01*
G01X830580Y121903D02*
Y125225D01*
G01X829520Y122343D02*
Y124785D01*
G01X830580Y125225D02*
X829131Y126674D01*
G01X829520Y124785D02*
X828691Y125614D01*
G01X829131Y126674D02*
X827952D01*
G01X828691Y125614D02*
X827512D01*
G01X829131Y126674D02*
X827952D01*
G01D02*
X827080Y127546D01*
G01X827512Y125614D02*
X826020Y127106D01*
G01X827080Y127546D02*
Y129719D01*
G01X826020Y127106D02*
Y130159D01*
G01X827080Y129719D02*
X830880Y133519D01*
G01X826020Y130159D02*
X829820Y133959D01*
G01X830880Y133519D02*
Y143279D01*
G01X829820Y133959D02*
Y143719D01*
G01X830880Y143279D02*
X842001Y154400D01*
G01X829820Y143719D02*
X841561Y155460D01*
G01X842001Y154400D02*
X846301D01*
G01X841561Y155460D02*
X845861D01*
G01X846301Y154400D02*
X850862Y158961D01*
G01X845861Y155460D02*
X849802Y159401D01*
G01X831379Y102452D02*
X826880Y106951D01*
G01X830319Y102012D02*
X825820Y106511D01*
G01X826880Y106951D02*
Y119442D01*
G01X825820Y106511D02*
Y119885D01*
G01X826880Y119442D02*
X827752Y120314D01*
G01X825820Y119885D02*
X827309Y121374D01*
G01X827752Y120314D02*
X828991D01*
G01X827309Y121374D02*
X828551D01*
G01X828991Y120314D02*
X830580Y121903D01*
G01X828551Y121374D02*
X829520Y122343D01*
G01X830580Y121903D02*
Y125225D01*
G01X829520Y122343D02*
Y124785D01*
G01X830580Y125225D02*
X829131Y126674D01*
G01X829520Y124785D02*
X828691Y125614D01*
G01X829131Y126674D02*
X827952D01*
G01X828691Y125614D02*
X827512D01*
G01X829131Y126674D02*
X827952D01*
G01D02*
X827080Y127546D01*
G01X827512Y125614D02*
X826020Y127106D01*
G01X827080Y127546D02*
Y129719D01*
G01X826020Y127106D02*
Y130159D01*
G01X827080Y129719D02*
X830880Y133519D01*
G01X826020Y130159D02*
X829820Y133959D01*
G01X830880Y133519D02*
Y143279D01*
G01X829820Y133959D02*
Y143719D01*
G01X830880Y143279D02*
X842001Y154400D01*
G01X829820Y143719D02*
X841561Y155460D01*
G01X842001Y154400D02*
X846301D01*
G01X841561Y155460D02*
X845861D01*
G01X846301Y154400D02*
X850862Y158961D01*
G01X845861Y155460D02*
X849802Y159401D01*
G01X796616Y160868D02*
X798234Y162486D01*
G01X797676Y160428D02*
X798674Y161426D01*
G01X798234Y162486D02*
X802585D01*
G01X798674Y161426D02*
X803025D01*
G01X802585Y162486D02*
X804124Y164025D01*
G01X803025Y161426D02*
X805184Y163585D01*
G01X804124Y164025D02*
Y170538D01*
G01X805184Y163585D02*
Y170098D01*
G01X804124Y170538D02*
X890026Y256440D01*
G01X805184Y170098D02*
X879677Y244591D01*
G01X804124Y170538D02*
X890026Y256440D01*
G01X804124Y170538D02*
X890026Y256440D01*
G01X804124Y170538D02*
X890026Y256440D01*
G01X804124Y170538D02*
X890026Y256440D01*
G01X804124Y170538D02*
X890026Y256440D01*
G01X804124Y170538D02*
X890026Y256440D01*
G01X804124Y170538D02*
X890026Y256440D01*
G01X804124Y170538D02*
X890026Y256440D01*
G01X804124Y170538D02*
X890026Y256440D01*
G01X804124Y170538D02*
X890026Y256440D01*
G01X796616Y160868D02*
X798234Y162486D01*
G01X797676Y160428D02*
X798674Y161426D01*
G01X798234Y162486D02*
X802585D01*
G01X798674Y161426D02*
X803025D01*
G01X802585Y162486D02*
X804124Y164025D01*
G01X803025Y161426D02*
X805184Y163585D01*
G01X804124Y164025D02*
Y170538D01*
G01X805184Y163585D02*
Y170098D01*
G01X804124Y170538D02*
X890026Y256440D01*
G01X805184Y170098D02*
X879677Y244591D01*
G01X804124Y170538D02*
X890026Y256440D01*
G01X804124Y170538D02*
X890026Y256440D01*
G01X804124Y170538D02*
X890026Y256440D01*
G01X804124Y170538D02*
X890026Y256440D01*
G01X804124Y170538D02*
X890026Y256440D01*
G01X804124Y170538D02*
X890026Y256440D01*
G01X804124Y170538D02*
X890026Y256440D01*
G01X804124Y170538D02*
X890026Y256440D01*
G01X804124Y170538D02*
X890026Y256440D01*
G01X804124Y170538D02*
X890026Y256440D01*
G01X797676Y160428D02*
X798674Y161426D01*
G01X796616Y160868D02*
X798234Y162486D01*
G01X798674Y161426D02*
X803025D01*
G01X798234Y162486D02*
X802585D01*
G01X803025Y161426D02*
X805184Y163585D01*
G01X802585Y162486D02*
X804124Y164025D01*
G01X805184Y163585D02*
Y170098D01*
G01X804124Y164025D02*
Y170538D01*
G01X805184Y170098D02*
X879677Y244591D01*
G01X804124Y170538D02*
X890026Y256440D01*
G01X797676Y160428D02*
X798674Y161426D01*
G01X796616Y160868D02*
X798234Y162486D01*
G01X798674Y161426D02*
X803025D01*
G01X798234Y162486D02*
X802585D01*
G01X803025Y161426D02*
X805184Y163585D01*
G01X802585Y162486D02*
X804124Y164025D01*
G01X805184Y163585D02*
Y170098D01*
G01X804124Y164025D02*
Y170538D01*
G01X805184Y170098D02*
X879677Y244591D01*
G01X804124Y170538D02*
X890026Y256440D01*
G01X807919Y162743D02*
Y168891D01*
G01X808979Y162303D02*
Y168451D01*
G01X807919Y168891D02*
X891568Y252540D01*
G01X808979Y168451D02*
X882301Y241773D01*
G01X807919Y168891D02*
X891568Y252540D01*
G01X807919Y168891D02*
X891568Y252540D01*
G01X807919Y168891D02*
X891568Y252540D01*
G01X807919Y168891D02*
X891568Y252540D01*
G01X807919Y168891D02*
X891568Y252540D01*
G01X807919Y168891D02*
X891568Y252540D01*
G01X807919Y168891D02*
X891568Y252540D01*
G01X807919Y168891D02*
X891568Y252540D01*
G01X807919Y162743D02*
Y168891D01*
G01X808979Y162303D02*
Y168451D01*
G01X807919Y168891D02*
X891568Y252540D01*
G01X808979Y168451D02*
X882301Y241773D01*
G01X807919Y168891D02*
X891568Y252540D01*
G01X807919Y168891D02*
X891568Y252540D01*
G01X807919Y168891D02*
X891568Y252540D01*
G01X807919Y168891D02*
X891568Y252540D01*
G01X807919Y168891D02*
X891568Y252540D01*
G01X807919Y168891D02*
X891568Y252540D01*
G01X807919Y168891D02*
X891568Y252540D01*
G01X807919Y168891D02*
X891568Y252540D01*
G01X853804Y170676D02*
X844388Y161260D01*
G01X854864Y170236D02*
X844828Y160200D01*
G01X844388Y161260D02*
X840592D01*
G01X844828Y160200D02*
X841032D01*
G01X853804Y170676D02*
X844388Y161260D01*
G01X854864Y170236D02*
X844828Y160200D01*
G01X844388Y161260D02*
X840592D01*
G01X844828Y160200D02*
X841032D01*
G01X808979Y162303D02*
Y168451D01*
G01X807919Y162743D02*
Y168891D01*
G01X808979Y168451D02*
X882301Y241773D01*
G01X807919Y168891D02*
X891568Y252540D01*
G01X808979Y162303D02*
Y168451D01*
G01X807919Y162743D02*
Y168891D01*
G01X808979Y168451D02*
X882301Y241773D01*
G01X807919Y168891D02*
X891568Y252540D01*
G01X854864Y170236D02*
X844828Y160200D01*
G01X853804Y170676D02*
X844388Y161260D01*
G01X844828Y160200D02*
X841032D01*
G01X844388Y161260D02*
X840592D01*
G01X854864Y170236D02*
X844828Y160200D01*
G01X853804Y170676D02*
X844388Y161260D01*
G01X844828Y160200D02*
X841032D01*
G01X844388Y161260D02*
X840592D01*
G01X856840Y390837D02*
X841437Y406240D01*
G01X857900Y391277D02*
X841877Y407300D01*
G01X856840Y390837D02*
X841437Y406240D01*
G01X857900Y391277D02*
X841877Y407300D01*
G01X857900Y391277D02*
X841877Y407300D01*
G01X856840Y390837D02*
X841437Y406240D01*
G01X857900Y391277D02*
X841877Y407300D01*
G01X856840Y390837D02*
X841437Y406240D01*
G01D02*
X826360D01*
G01X841877Y407300D02*
X826800D01*
G01X826360Y406240D02*
X808440Y424160D01*
G01X826800Y407300D02*
X809500Y424600D01*
G01X808440Y424160D02*
Y426160D01*
G01X809500Y424600D02*
Y426600D01*
G01X808440Y426160D02*
X793320Y441280D01*
G01X809500Y426600D02*
X794380Y441720D01*
G01X793320Y441280D02*
Y454023D01*
G01X794380Y441720D02*
Y454463D01*
G01X793320Y454023D02*
X792451Y454892D01*
G01X794380Y454463D02*
X792891Y455952D01*
G01X792451Y454892D02*
X789480D01*
G01X792891Y455952D02*
X789920D01*
G01X789480Y454892D02*
X788360Y456012D01*
G01X789920Y455952D02*
X789420Y456452D01*
G01X788360Y456012D02*
Y459332D01*
G01X789420Y456452D02*
Y458892D01*
G01X788360Y459332D02*
X789480Y460452D01*
G01X789420Y458892D02*
X789920Y459392D01*
G01X789480Y460452D02*
X792451D01*
G01X789920Y459392D02*
X792891D01*
G01X792451Y460452D02*
X793320Y461321D01*
G01X792891Y459392D02*
X794380Y460881D01*
G01X793320Y461321D02*
Y464448D01*
G01X794380Y460881D02*
Y464891D01*
G01X793320Y464448D02*
X792658Y465110D01*
G01X841437Y406240D02*
X826360D01*
G01X841877Y407300D02*
X826800D01*
G01X826360Y406240D02*
X808440Y424160D01*
G01X826800Y407300D02*
X809500Y424600D01*
G01X808440Y424160D02*
Y426160D01*
G01X809500Y424600D02*
Y426600D01*
G01X808440Y426160D02*
X793320Y441280D01*
G01X809500Y426600D02*
X794380Y441720D01*
G01X793320Y441280D02*
Y454023D01*
G01X794380Y441720D02*
Y454463D01*
G01X793320Y454023D02*
X792451Y454892D01*
G01X794380Y454463D02*
X792891Y455952D01*
G01X792451Y454892D02*
X789480D01*
G01X792891Y455952D02*
X789920D01*
G01X789480Y454892D02*
X788360Y456012D01*
G01X789920Y455952D02*
X789420Y456452D01*
G01X788360Y456012D02*
Y459332D01*
G01X789420Y456452D02*
Y458892D01*
G01X788360Y459332D02*
X789480Y460452D01*
G01X789420Y458892D02*
X789920Y459392D01*
G01X789480Y460452D02*
X792451D01*
G01X789920Y459392D02*
X792891D01*
G01X792451Y460452D02*
X793320Y461321D01*
G01X792891Y459392D02*
X794380Y460881D01*
G01X793320Y461321D02*
Y464448D01*
G01X794380Y460881D02*
Y464891D01*
G01X793320Y464448D02*
X792658Y465110D01*
G01X841877Y407300D02*
X826800D01*
G01X841437Y406240D02*
X826360D01*
G01X826800Y407300D02*
X809500Y424600D01*
G01X826360Y406240D02*
X808440Y424160D01*
G01X809500Y424600D02*
Y426600D01*
G01X808440Y424160D02*
Y426160D01*
G01X809500Y426600D02*
X794380Y441720D01*
G01X808440Y426160D02*
X793320Y441280D01*
G01X794380Y441720D02*
Y454463D01*
G01X793320Y441280D02*
Y454023D01*
G01X794380Y454463D02*
X792891Y455952D01*
G01X793320Y454023D02*
X792451Y454892D01*
G01X792891Y455952D02*
X789920D01*
G01X792451Y454892D02*
X789480D01*
G01X789920Y455952D02*
X789420Y456452D01*
G01X789480Y454892D02*
X788360Y456012D01*
G01X789420Y456452D02*
Y458892D01*
G01X788360Y456012D02*
Y459332D01*
G01X789420Y458892D02*
X789920Y459392D01*
G01X788360Y459332D02*
X789480Y460452D01*
G01X789920Y459392D02*
X792891D01*
G01X789480Y460452D02*
X792451D01*
G01X792891Y459392D02*
X794380Y460881D01*
G01X792451Y460452D02*
X793320Y461321D01*
G01X794380Y460881D02*
Y464891D01*
G01X793320Y461321D02*
Y464448D01*
G01D02*
X792658Y465110D01*
G01X841877Y407300D02*
X826800D01*
G01X841437Y406240D02*
X826360D01*
G01X826800Y407300D02*
X809500Y424600D01*
G01X826360Y406240D02*
X808440Y424160D01*
G01X809500Y424600D02*
Y426600D01*
G01X808440Y424160D02*
Y426160D01*
G01X809500Y426600D02*
X794380Y441720D01*
G01X808440Y426160D02*
X793320Y441280D01*
G01X794380Y441720D02*
Y454463D01*
G01X793320Y441280D02*
Y454023D01*
G01X794380Y454463D02*
X792891Y455952D01*
G01X793320Y454023D02*
X792451Y454892D01*
G01X792891Y455952D02*
X789920D01*
G01X792451Y454892D02*
X789480D01*
G01X789920Y455952D02*
X789420Y456452D01*
G01X789480Y454892D02*
X788360Y456012D01*
G01X789420Y456452D02*
Y458892D01*
G01X788360Y456012D02*
Y459332D01*
G01X789420Y458892D02*
X789920Y459392D01*
G01X788360Y459332D02*
X789480Y460452D01*
G01X789920Y459392D02*
X792891D01*
G01X789480Y460452D02*
X792451D01*
G01X792891Y459392D02*
X794380Y460881D01*
G01X792451Y460452D02*
X793320Y461321D01*
G01X794380Y460881D02*
Y464891D01*
G01X793320Y461321D02*
Y464448D01*
G01D02*
X792658Y465110D01*
G01X861360Y393231D02*
X843691Y410900D01*
G01X860300Y392791D02*
X843251Y409840D01*
G01X843691Y410900D02*
X827400D01*
G01X843251Y409840D02*
X826960D01*
G01X827400Y410900D02*
X812500Y425800D01*
G01X826960Y409840D02*
X811440Y425360D01*
G01X812500Y425800D02*
Y427800D01*
G01X811440Y425360D02*
Y427360D01*
G01X812500Y427800D02*
X798280Y442020D01*
G01X811440Y427360D02*
X797220Y441580D01*
G01X798280Y442020D02*
Y468520D01*
G01X797220Y441580D02*
Y468080D01*
G01X891340Y398431D02*
X825221Y464550D01*
G01X892400Y398871D02*
X826279Y464992D01*
G01X825219Y464550D02*
Y487759D01*
G01X896400Y400271D02*
X846554Y450117D01*
G01X895340Y399831D02*
X845496Y449675D01*
G01X846554Y450117D02*
Y451345D01*
G01X845494Y449675D02*
Y451784D01*
G01X846554Y451345D02*
X849415Y454207D01*
G01X845494Y451784D02*
X848355Y454646D01*
G01D02*
Y455872D01*
G01X849415Y456315D02*
X847589Y458141D01*
G01X848355Y455872D02*
X847146Y457081D01*
G01X847589Y458141D02*
X845479D01*
G01X847146Y457081D02*
X845922D01*
G01X845479Y458141D02*
X842618Y455279D01*
G01X845922Y457081D02*
X843061Y454219D01*
G01X842618Y455279D02*
X841392D01*
G01X843061Y454219D02*
X840949D01*
G01X841392Y455279D02*
X840187Y456484D01*
G01X840949Y454219D02*
X839127Y456041D01*
G01X840187Y456484D02*
Y457712D01*
G01X839127Y456041D02*
Y458151D01*
G01X840187Y457712D02*
X843048Y460574D01*
G01X839127Y458151D02*
X841988Y461013D01*
G01X843048Y460574D02*
Y462682D01*
G01X841988Y461013D02*
Y462242D01*
G01X843048Y462682D02*
X841222Y464508D01*
G01X841988Y462242D02*
X840782Y463448D01*
G01X841222Y464508D02*
X839113D01*
G01X840782Y463448D02*
X839553D01*
G01X839113Y464508D02*
X836782Y462177D01*
G01D02*
X835025D01*
G01X839553Y463448D02*
X837222Y461117D01*
G01X836782Y462177D02*
X835025D01*
G01X837222Y461117D02*
X834582D01*
G01X835025Y462177D02*
X833880Y463322D01*
G01X834582Y461117D02*
X832820Y462879D01*
G01X833880Y463322D02*
Y469249D01*
G01X832820Y462879D02*
Y468806D01*
G01X860300Y392791D02*
X843251Y409840D01*
G01X861360Y393231D02*
X843691Y410900D01*
G01X843251Y409840D02*
X826960D01*
G01X843691Y410900D02*
X827400D01*
G01X826960Y409840D02*
X811440Y425360D01*
G01X827400Y410900D02*
X812500Y425800D01*
G01X811440Y425360D02*
Y427360D01*
G01X812500Y425800D02*
Y427800D01*
G01X811440Y427360D02*
X797220Y441580D01*
G01X812500Y427800D02*
X798280Y442020D01*
G01X797220Y441580D02*
Y468080D01*
G01X798280Y442020D02*
Y468520D01*
G01X892400Y398871D02*
X826279Y464992D01*
G01X891340Y398431D02*
X825221Y464550D01*
G01X825219D02*
Y487759D01*
G01X895340Y399831D02*
X845496Y449675D01*
G01X896400Y400271D02*
X846554Y450117D01*
G01X845494Y449675D02*
Y451784D01*
G01X846554Y450117D02*
Y451345D01*
G01X845494Y451784D02*
X848355Y454646D01*
G01X846554Y451345D02*
X849415Y454207D01*
G01X848355Y454646D02*
Y455872D01*
G01D02*
X847146Y457081D01*
G01X849415Y456315D02*
X847589Y458141D01*
G01X847146Y457081D02*
X845922D01*
G01X847589Y458141D02*
X845479D01*
G01X845922Y457081D02*
X843061Y454219D01*
G01X845479Y458141D02*
X842618Y455279D01*
G01X843061Y454219D02*
X840949D01*
G01X842618Y455279D02*
X841392D01*
G01X840949Y454219D02*
X839127Y456041D01*
G01X841392Y455279D02*
X840187Y456484D01*
G01X839127Y456041D02*
Y458151D01*
G01X840187Y456484D02*
Y457712D01*
G01X839127Y458151D02*
X841988Y461013D01*
G01X840187Y457712D02*
X843048Y460574D01*
G01X841988Y461013D02*
Y462242D01*
G01X843048Y460574D02*
Y462682D01*
G01X841988Y462242D02*
X840782Y463448D01*
G01X843048Y462682D02*
X841222Y464508D01*
G01X840782Y463448D02*
X839553D01*
G01X841222Y464508D02*
X839113D01*
G01X839553Y463448D02*
X837222Y461117D01*
G01X839113Y464508D02*
X836782Y462177D01*
G01X839553Y463448D02*
X837222Y461117D01*
G01D02*
X834582D01*
G01X836782Y462177D02*
X835025D01*
G01X834582Y461117D02*
X832820Y462879D01*
G01X835025Y462177D02*
X833880Y463322D01*
G01X832820Y462879D02*
Y468806D01*
G01X833880Y463322D02*
Y469249D01*
G01X861360Y393231D02*
X843691Y410900D01*
G01X860300Y392791D02*
X843251Y409840D01*
G01X843691Y410900D02*
X827400D01*
G01X843251Y409840D02*
X826960D01*
G01X827400Y410900D02*
X812500Y425800D01*
G01X826960Y409840D02*
X811440Y425360D01*
G01X812500Y425800D02*
Y427800D01*
G01X811440Y425360D02*
Y427360D01*
G01X812500Y427800D02*
X798280Y442020D01*
G01X811440Y427360D02*
X797220Y441580D01*
G01X798280Y442020D02*
Y468520D01*
G01X797220Y441580D02*
Y468080D01*
G01X891340Y398431D02*
X825221Y464550D01*
G01X892400Y398871D02*
X826279Y464992D01*
G01X825219Y464550D02*
Y487759D01*
G01X896400Y400271D02*
X846554Y450117D01*
G01X895340Y399831D02*
X845496Y449675D01*
G01X846554Y450117D02*
Y451345D01*
G01X845494Y449675D02*
Y451784D01*
G01X846554Y451345D02*
X849415Y454207D01*
G01X845494Y451784D02*
X848355Y454646D01*
G01D02*
Y455872D01*
G01X849415Y456315D02*
X847589Y458141D01*
G01X848355Y455872D02*
X847146Y457081D01*
G01X847589Y458141D02*
X845479D01*
G01X847146Y457081D02*
X845922D01*
G01X845479Y458141D02*
X842618Y455279D01*
G01X845922Y457081D02*
X843061Y454219D01*
G01X842618Y455279D02*
X841392D01*
G01X843061Y454219D02*
X840949D01*
G01X841392Y455279D02*
X840187Y456484D01*
G01X840949Y454219D02*
X839127Y456041D01*
G01X840187Y456484D02*
Y457712D01*
G01X839127Y456041D02*
Y458151D01*
G01X840187Y457712D02*
X843048Y460574D01*
G01X839127Y458151D02*
X841988Y461013D01*
G01X843048Y460574D02*
Y462682D01*
G01X841988Y461013D02*
Y462242D01*
G01X843048Y462682D02*
X841222Y464508D01*
G01X841988Y462242D02*
X840782Y463448D01*
G01X841222Y464508D02*
X839113D01*
G01X840782Y463448D02*
X839553D01*
G01X839113Y464508D02*
X836782Y462177D01*
G01D02*
X835025D01*
G01X839553Y463448D02*
X837222Y461117D01*
G01X836782Y462177D02*
X835025D01*
G01X837222Y461117D02*
X834582D01*
G01X835025Y462177D02*
X833880Y463322D01*
G01X834582Y461117D02*
X832820Y462879D01*
G01X833880Y463322D02*
Y469249D01*
G01X832820Y462879D02*
Y468806D01*
G01X860300Y392791D02*
X843251Y409840D01*
G01X861360Y393231D02*
X843691Y410900D01*
G01X843251Y409840D02*
X826960D01*
G01X843691Y410900D02*
X827400D01*
G01X826960Y409840D02*
X811440Y425360D01*
G01X827400Y410900D02*
X812500Y425800D01*
G01X811440Y425360D02*
Y427360D01*
G01X812500Y425800D02*
Y427800D01*
G01X811440Y427360D02*
X797220Y441580D01*
G01X812500Y427800D02*
X798280Y442020D01*
G01X797220Y441580D02*
Y468080D01*
G01X798280Y442020D02*
Y468520D01*
G01X892400Y398871D02*
X826279Y464992D01*
G01X891340Y398431D02*
X825221Y464550D01*
G01X825219D02*
Y487759D01*
G01X895340Y399831D02*
X845496Y449675D01*
G01X896400Y400271D02*
X846554Y450117D01*
G01X845494Y449675D02*
Y451784D01*
G01X846554Y450117D02*
Y451345D01*
G01X845494Y451784D02*
X848355Y454646D01*
G01X846554Y451345D02*
X849415Y454207D01*
G01X848355Y454646D02*
Y455872D01*
G01D02*
X847146Y457081D01*
G01X849415Y456315D02*
X847589Y458141D01*
G01X847146Y457081D02*
X845922D01*
G01X847589Y458141D02*
X845479D01*
G01X845922Y457081D02*
X843061Y454219D01*
G01X845479Y458141D02*
X842618Y455279D01*
G01X843061Y454219D02*
X840949D01*
G01X842618Y455279D02*
X841392D01*
G01X840949Y454219D02*
X839127Y456041D01*
G01X841392Y455279D02*
X840187Y456484D01*
G01X839127Y456041D02*
Y458151D01*
G01X840187Y456484D02*
Y457712D01*
G01X839127Y458151D02*
X841988Y461013D01*
G01X840187Y457712D02*
X843048Y460574D01*
G01X841988Y461013D02*
Y462242D01*
G01X843048Y460574D02*
Y462682D01*
G01X841988Y462242D02*
X840782Y463448D01*
G01X843048Y462682D02*
X841222Y464508D01*
G01X840782Y463448D02*
X839553D01*
G01X841222Y464508D02*
X839113D01*
G01X839553Y463448D02*
X837222Y461117D01*
G01X839113Y464508D02*
X836782Y462177D01*
G01X839553Y463448D02*
X837222Y461117D01*
G01D02*
X834582D01*
G01X836782Y462177D02*
X835025D01*
G01X834582Y461117D02*
X832820Y462879D01*
G01X835025Y462177D02*
X833880Y463322D01*
G01X832820Y462879D02*
Y468806D01*
G01X833880Y463322D02*
Y469249D01*
G01X794380Y464891D02*
X793101Y466170D01*
G01X792658Y465110D02*
X788519D01*
G01X793101Y466170D02*
X788962D01*
G01X788519Y465110D02*
X786920Y466709D01*
G01X788962Y466170D02*
X787980Y467152D01*
G01X786920Y466709D02*
Y497592D01*
G01X787980Y467152D02*
Y497149D01*
G01X786920Y497592D02*
X788408Y499080D01*
G01X787980Y497149D02*
X789468Y498637D01*
G01X788408Y499080D02*
Y587261D01*
G01X789468Y498637D02*
Y579170D01*
G01X788408Y499080D02*
Y587261D01*
G01Y499080D02*
Y587261D01*
G01X794380Y464891D02*
X793101Y466170D01*
G01X792658Y465110D02*
X788519D01*
G01X793101Y466170D02*
X788962D01*
G01X788519Y465110D02*
X786920Y466709D01*
G01X788962Y466170D02*
X787980Y467152D01*
G01X786920Y466709D02*
Y497592D01*
G01X787980Y467152D02*
Y497149D01*
G01X786920Y497592D02*
X788408Y499080D01*
G01X787980Y497149D02*
X789468Y498637D01*
G01X788408Y499080D02*
Y587261D01*
G01X789468Y498637D02*
Y579170D01*
G01X788408Y499080D02*
Y587261D01*
G01Y499080D02*
Y587261D01*
G01X794380Y464891D02*
X793101Y466170D01*
G01D02*
X788962D01*
G01X792658Y465110D02*
X788519D01*
G01X788962Y466170D02*
X787980Y467152D01*
G01X788519Y465110D02*
X786920Y466709D01*
G01X787980Y467152D02*
Y497149D01*
G01X786920Y466709D02*
Y497592D01*
G01X787980Y497149D02*
X789468Y498637D01*
G01X786920Y497592D02*
X788408Y499080D01*
G01X789468Y498637D02*
Y579170D01*
G01X788408Y499080D02*
Y587261D01*
G01X794380Y464891D02*
X793101Y466170D01*
G01D02*
X788962D01*
G01X792658Y465110D02*
X788519D01*
G01X788962Y466170D02*
X787980Y467152D01*
G01X788519Y465110D02*
X786920Y466709D01*
G01X787980Y467152D02*
Y497149D01*
G01X786920Y466709D02*
Y497592D01*
G01X787980Y497149D02*
X789468Y498637D01*
G01X786920Y497592D02*
X788408Y499080D01*
G01X789468Y498637D02*
Y579170D01*
G01X788408Y499080D02*
Y587261D01*
G01X798280Y468520D02*
X796791Y470009D01*
G01X797220Y468080D02*
X796351Y468949D01*
G01X796791Y470009D02*
X793826D01*
G01X796351Y468949D02*
X793386D01*
G01X793826Y470009D02*
X792924Y470911D01*
G01X793386Y468949D02*
X791864Y470471D01*
G01X792924Y470911D02*
Y472613D01*
G01X791864Y470471D02*
Y473053D01*
G01X792924Y472613D02*
X793760Y473449D01*
G01X791864Y473053D02*
X793320Y474509D01*
G01X793760Y473449D02*
X796788D01*
G01X793320Y474509D02*
X796348D01*
G01X796788Y473449D02*
X798280Y474941D01*
G01X796348Y474509D02*
X797220Y475381D01*
G01X798280Y474941D02*
Y477517D01*
G01X797220Y475381D02*
Y477077D01*
G01X798280Y477517D02*
X796788Y479009D01*
G01X797220Y477077D02*
X796348Y477949D01*
G01X796788Y479009D02*
X793008D01*
G01X796348Y477949D02*
X792568D01*
G01X793008Y479009D02*
X792139Y479878D01*
G01X792568Y477949D02*
X791079Y479438D01*
G01X792139Y479878D02*
Y481580D01*
G01X791079Y479438D02*
Y482020D01*
G01X792139Y481580D02*
X793008Y482449D01*
G01X791079Y482020D02*
X792568Y483509D01*
G01X793008Y482449D02*
X796788D01*
G01X792568Y483509D02*
X796348D01*
G01X796788Y482449D02*
X798280Y483941D01*
G01X796348Y483509D02*
X797220Y484381D01*
G01X798280Y483941D02*
Y486520D01*
G01X797220Y484381D02*
Y486077D01*
G01X798280Y486520D02*
X796791Y488009D01*
G01X797220Y486077D02*
X796348Y486949D01*
G01X796791Y488009D02*
X792652D01*
G01X796348Y486949D02*
X792209D01*
G01X792652Y488009D02*
X791780Y488881D01*
G01X792209Y486949D02*
X790720Y488438D01*
G01X791780Y488881D02*
Y490580D01*
G01X790720Y488438D02*
Y491020D01*
G01X791780Y490580D02*
X792649Y491449D01*
G01X790720Y491020D02*
X792209Y492509D01*
G01X792649Y491449D02*
X796608D01*
G01X792209Y492509D02*
X796168D01*
G01X796608Y491449D02*
X798100Y492941D01*
G01X796168Y492509D02*
X797040Y493381D01*
G01X798100Y492941D02*
Y495628D01*
G01X797040Y493381D02*
Y495188D01*
G01X798100Y495628D02*
X794568Y499160D01*
G01X797040Y495188D02*
X793508Y498720D01*
G01X794568Y499160D02*
Y588070D01*
G01X793508Y498720D02*
Y538169D01*
G01X794568Y499160D02*
Y588070D01*
G01Y499160D02*
Y588070D01*
G01Y499160D02*
Y588070D01*
G01Y499160D02*
Y588070D01*
G01Y499160D02*
Y588070D01*
G01Y499160D02*
Y588070D01*
G01Y499160D02*
Y588070D01*
G01Y499160D02*
Y588070D01*
G01Y499160D02*
Y588070D01*
G01X826279Y464992D02*
Y487319D01*
G01X825219Y487759D02*
X826711Y489251D01*
G01X826279Y487319D02*
X827151Y488191D01*
G01X826711Y489251D02*
X828490D01*
G01X827151Y488191D02*
X828933D01*
G01X828490Y489251D02*
X829362Y490123D01*
G01X828933Y488191D02*
X830422Y489680D01*
G01X829362Y490123D02*
Y491822D01*
G01X830422Y489680D02*
Y492262D01*
G01X829362Y491822D02*
X828493Y492691D01*
G01X830422Y492262D02*
X828933Y493751D01*
G01X828493Y492691D02*
X826711D01*
G01X828933Y493751D02*
X827151D01*
G01X826711Y492691D02*
X825219Y494183D01*
G01X827151Y493751D02*
X826279Y494623D01*
G01X825219Y494183D02*
Y496759D01*
G01X826279Y494623D02*
Y496319D01*
G01X825219Y496759D02*
X826711Y498251D01*
G01X826279Y496319D02*
X827151Y497191D01*
G01X826711Y498251D02*
X828529D01*
G01X827151Y497191D02*
X828969D01*
G01X828529Y498251D02*
X829446Y499168D01*
G01X828969Y497191D02*
X830506Y498728D01*
G01X829446Y499168D02*
Y500870D01*
G01X830506Y498728D02*
Y501310D01*
G01X829446Y500870D02*
X828625Y501691D01*
G01X830506Y501310D02*
X829065Y502751D01*
G01X828625Y501691D02*
X826711D01*
G01X829065Y502751D02*
X827151D01*
G01X826711Y501691D02*
X825219Y503183D01*
G01X827151Y502751D02*
X826279Y503623D01*
G01X825219Y503183D02*
Y587409D01*
G01X826279Y503623D02*
Y579416D01*
G01X825219Y503183D02*
Y587409D01*
G01Y503183D02*
Y587409D01*
G01X833880Y469249D02*
X832391Y470738D01*
G01X832820Y468806D02*
X831948Y469678D01*
G01X832391Y470738D02*
X831752D01*
G01X831948Y469678D02*
X831309D01*
G01X831752Y470738D02*
X830980Y471510D01*
G01X831309Y469678D02*
X829920Y471067D01*
G01X830980Y471510D02*
Y473406D01*
G01X829920Y471067D02*
Y473849D01*
G01X830980Y473406D02*
X831752Y474178D01*
G01X829920Y473849D02*
X831309Y475238D01*
G01X831752Y474178D02*
X832391D01*
G01X831309Y475238D02*
X831948D01*
G01X832391Y474178D02*
X833880Y475667D01*
G01X831948Y475238D02*
X832820Y476110D01*
G01X833880Y475667D02*
Y478249D01*
G01X832820Y476110D02*
Y477806D01*
G01X833880Y478249D02*
X832391Y479738D01*
G01X832820Y477806D02*
X831948Y478678D01*
G01X832391Y479738D02*
X831752D01*
G01X831948Y478678D02*
X831309D01*
G01X831752Y479738D02*
X830880Y480610D01*
G01X831309Y478678D02*
X829820Y480167D01*
G01X830880Y480610D02*
Y482306D01*
G01X829820Y480167D02*
Y482749D01*
G01X830880Y482306D02*
X831752Y483178D01*
G01X829820Y482749D02*
X831309Y484238D01*
G01X831752Y483178D02*
X832391D01*
G01X831309Y484238D02*
X831948D01*
G01X832391Y483178D02*
X833880Y484667D01*
G01X831948Y484238D02*
X832820Y485110D01*
G01X833880Y484667D02*
Y505551D01*
G01X832820Y485110D02*
Y505108D01*
G01X833880Y505551D02*
X831379Y508052D01*
G01X832820Y505108D02*
X830319Y507609D01*
G01X831379Y508052D02*
Y588035D01*
G01X830319Y507609D02*
Y578633D01*
G01X831379Y508052D02*
Y588035D01*
G01Y508052D02*
Y588035D01*
G01X797220Y468080D02*
X796351Y468949D01*
G01X798280Y468520D02*
X796791Y470009D01*
G01X796351Y468949D02*
X793386D01*
G01X796791Y470009D02*
X793826D01*
G01X793386Y468949D02*
X791864Y470471D01*
G01X793826Y470009D02*
X792924Y470911D01*
G01X791864Y470471D02*
Y473053D01*
G01X792924Y470911D02*
Y472613D01*
G01X791864Y473053D02*
X793320Y474509D01*
G01X792924Y472613D02*
X793760Y473449D01*
G01X793320Y474509D02*
X796348D01*
G01X793760Y473449D02*
X796788D01*
G01X796348Y474509D02*
X797220Y475381D01*
G01X796788Y473449D02*
X798280Y474941D01*
G01X797220Y475381D02*
Y477077D01*
G01X798280Y474941D02*
Y477517D01*
G01X797220Y477077D02*
X796348Y477949D01*
G01X798280Y477517D02*
X796788Y479009D01*
G01X796348Y477949D02*
X792568D01*
G01X796788Y479009D02*
X793008D01*
G01X792568Y477949D02*
X791079Y479438D01*
G01X793008Y479009D02*
X792139Y479878D01*
G01X791079Y479438D02*
Y482020D01*
G01X792139Y479878D02*
Y481580D01*
G01X791079Y482020D02*
X792568Y483509D01*
G01X792139Y481580D02*
X793008Y482449D01*
G01X792568Y483509D02*
X796348D01*
G01X793008Y482449D02*
X796788D01*
G01X796348Y483509D02*
X797220Y484381D01*
G01X796788Y482449D02*
X798280Y483941D01*
G01X797220Y484381D02*
Y486077D01*
G01X798280Y483941D02*
Y486520D01*
G01X797220Y486077D02*
X796348Y486949D01*
G01X798280Y486520D02*
X796791Y488009D01*
G01X796348Y486949D02*
X792209D01*
G01X796791Y488009D02*
X792652D01*
G01X792209Y486949D02*
X790720Y488438D01*
G01X792652Y488009D02*
X791780Y488881D01*
G01X790720Y488438D02*
Y491020D01*
G01X791780Y488881D02*
Y490580D01*
G01X790720Y491020D02*
X792209Y492509D01*
G01X791780Y490580D02*
X792649Y491449D01*
G01X792209Y492509D02*
X796168D01*
G01X792649Y491449D02*
X796608D01*
G01X796168Y492509D02*
X797040Y493381D01*
G01X796608Y491449D02*
X798100Y492941D01*
G01X797040Y493381D02*
Y495188D01*
G01X798100Y492941D02*
Y495628D01*
G01X797040Y495188D02*
X793508Y498720D01*
G01X798100Y495628D02*
X794568Y499160D01*
G01X793508Y498720D02*
Y538169D01*
G01X794568Y499160D02*
Y588070D01*
G01X826279Y464992D02*
Y487319D01*
G01D02*
X827151Y488191D01*
G01X825219Y487759D02*
X826711Y489251D01*
G01X827151Y488191D02*
X828933D01*
G01X826711Y489251D02*
X828490D01*
G01X828933Y488191D02*
X830422Y489680D01*
G01X828490Y489251D02*
X829362Y490123D01*
G01X830422Y489680D02*
Y492262D01*
G01X829362Y490123D02*
Y491822D01*
G01X830422Y492262D02*
X828933Y493751D01*
G01X829362Y491822D02*
X828493Y492691D01*
G01X828933Y493751D02*
X827151D01*
G01X828493Y492691D02*
X826711D01*
G01X827151Y493751D02*
X826279Y494623D01*
G01X826711Y492691D02*
X825219Y494183D01*
G01X826279Y494623D02*
Y496319D01*
G01X825219Y494183D02*
Y496759D01*
G01X826279Y496319D02*
X827151Y497191D01*
G01X825219Y496759D02*
X826711Y498251D01*
G01X827151Y497191D02*
X828969D01*
G01X826711Y498251D02*
X828529D01*
G01X828969Y497191D02*
X830506Y498728D01*
G01X828529Y498251D02*
X829446Y499168D01*
G01X830506Y498728D02*
Y501310D01*
G01X829446Y499168D02*
Y500870D01*
G01X830506Y501310D02*
X829065Y502751D01*
G01X829446Y500870D02*
X828625Y501691D01*
G01X829065Y502751D02*
X827151D01*
G01X828625Y501691D02*
X826711D01*
G01X827151Y502751D02*
X826279Y503623D01*
G01X826711Y501691D02*
X825219Y503183D01*
G01X826279Y503623D02*
Y579416D01*
G01X825219Y503183D02*
Y587409D01*
G01X832820Y468806D02*
X831948Y469678D01*
G01X833880Y469249D02*
X832391Y470738D01*
G01X831948Y469678D02*
X831309D01*
G01X832391Y470738D02*
X831752D01*
G01X831309Y469678D02*
X829920Y471067D01*
G01X831752Y470738D02*
X830980Y471510D01*
G01X829920Y471067D02*
Y473849D01*
G01X830980Y471510D02*
Y473406D01*
G01X829920Y473849D02*
X831309Y475238D01*
G01X830980Y473406D02*
X831752Y474178D01*
G01X831309Y475238D02*
X831948D01*
G01X831752Y474178D02*
X832391D01*
G01X831948Y475238D02*
X832820Y476110D01*
G01X832391Y474178D02*
X833880Y475667D01*
G01X832820Y476110D02*
Y477806D01*
G01X833880Y475667D02*
Y478249D01*
G01X832820Y477806D02*
X831948Y478678D01*
G01X833880Y478249D02*
X832391Y479738D01*
G01X831948Y478678D02*
X831309D01*
G01X832391Y479738D02*
X831752D01*
G01X831309Y478678D02*
X829820Y480167D01*
G01X831752Y479738D02*
X830880Y480610D01*
G01X829820Y480167D02*
Y482749D01*
G01X830880Y480610D02*
Y482306D01*
G01X829820Y482749D02*
X831309Y484238D01*
G01X830880Y482306D02*
X831752Y483178D01*
G01X831309Y484238D02*
X831948D01*
G01X831752Y483178D02*
X832391D01*
G01X831948Y484238D02*
X832820Y485110D01*
G01X832391Y483178D02*
X833880Y484667D01*
G01X832820Y485110D02*
Y505108D01*
G01X833880Y484667D02*
Y505551D01*
G01X832820Y505108D02*
X830319Y507609D01*
G01X833880Y505551D02*
X831379Y508052D01*
G01X830319Y507609D02*
Y578633D01*
G01X831379Y508052D02*
Y588035D01*
G01X798280Y468520D02*
X796791Y470009D01*
G01X797220Y468080D02*
X796351Y468949D01*
G01X796791Y470009D02*
X793826D01*
G01X796351Y468949D02*
X793386D01*
G01X793826Y470009D02*
X792924Y470911D01*
G01X793386Y468949D02*
X791864Y470471D01*
G01X792924Y470911D02*
Y472613D01*
G01X791864Y470471D02*
Y473053D01*
G01X792924Y472613D02*
X793760Y473449D01*
G01X791864Y473053D02*
X793320Y474509D01*
G01X793760Y473449D02*
X796788D01*
G01X793320Y474509D02*
X796348D01*
G01X796788Y473449D02*
X798280Y474941D01*
G01X796348Y474509D02*
X797220Y475381D01*
G01X798280Y474941D02*
Y477517D01*
G01X797220Y475381D02*
Y477077D01*
G01X798280Y477517D02*
X796788Y479009D01*
G01X797220Y477077D02*
X796348Y477949D01*
G01X796788Y479009D02*
X793008D01*
G01X796348Y477949D02*
X792568D01*
G01X793008Y479009D02*
X792139Y479878D01*
G01X792568Y477949D02*
X791079Y479438D01*
G01X792139Y479878D02*
Y481580D01*
G01X791079Y479438D02*
Y482020D01*
G01X792139Y481580D02*
X793008Y482449D01*
G01X791079Y482020D02*
X792568Y483509D01*
G01X793008Y482449D02*
X796788D01*
G01X792568Y483509D02*
X796348D01*
G01X796788Y482449D02*
X798280Y483941D01*
G01X796348Y483509D02*
X797220Y484381D01*
G01X798280Y483941D02*
Y486520D01*
G01X797220Y484381D02*
Y486077D01*
G01X798280Y486520D02*
X796791Y488009D01*
G01X797220Y486077D02*
X796348Y486949D01*
G01X796791Y488009D02*
X792652D01*
G01X796348Y486949D02*
X792209D01*
G01X792652Y488009D02*
X791780Y488881D01*
G01X792209Y486949D02*
X790720Y488438D01*
G01X791780Y488881D02*
Y490580D01*
G01X790720Y488438D02*
Y491020D01*
G01X791780Y490580D02*
X792649Y491449D01*
G01X790720Y491020D02*
X792209Y492509D01*
G01X792649Y491449D02*
X796608D01*
G01X792209Y492509D02*
X796168D01*
G01X796608Y491449D02*
X798100Y492941D01*
G01X796168Y492509D02*
X797040Y493381D01*
G01X798100Y492941D02*
Y495628D01*
G01X797040Y493381D02*
Y495188D01*
G01X798100Y495628D02*
X794568Y499160D01*
G01X797040Y495188D02*
X793508Y498720D01*
G01X794568Y499160D02*
Y588070D01*
G01X793508Y498720D02*
Y538169D01*
G01X794568Y499160D02*
Y588070D01*
G01Y499160D02*
Y588070D01*
G01Y499160D02*
Y588070D01*
G01Y499160D02*
Y588070D01*
G01Y499160D02*
Y588070D01*
G01Y499160D02*
Y588070D01*
G01Y499160D02*
Y588070D01*
G01Y499160D02*
Y588070D01*
G01Y499160D02*
Y588070D01*
G01X826279Y464992D02*
Y487319D01*
G01X825219Y487759D02*
X826711Y489251D01*
G01X826279Y487319D02*
X827151Y488191D01*
G01X826711Y489251D02*
X828490D01*
G01X827151Y488191D02*
X828933D01*
G01X828490Y489251D02*
X829362Y490123D01*
G01X828933Y488191D02*
X830422Y489680D01*
G01X829362Y490123D02*
Y491822D01*
G01X830422Y489680D02*
Y492262D01*
G01X829362Y491822D02*
X828493Y492691D01*
G01X830422Y492262D02*
X828933Y493751D01*
G01X828493Y492691D02*
X826711D01*
G01X828933Y493751D02*
X827151D01*
G01X826711Y492691D02*
X825219Y494183D01*
G01X827151Y493751D02*
X826279Y494623D01*
G01X825219Y494183D02*
Y496759D01*
G01X826279Y494623D02*
Y496319D01*
G01X825219Y496759D02*
X826711Y498251D01*
G01X826279Y496319D02*
X827151Y497191D01*
G01X826711Y498251D02*
X828529D01*
G01X827151Y497191D02*
X828969D01*
G01X828529Y498251D02*
X829446Y499168D01*
G01X828969Y497191D02*
X830506Y498728D01*
G01X829446Y499168D02*
Y500870D01*
G01X830506Y498728D02*
Y501310D01*
G01X829446Y500870D02*
X828625Y501691D01*
G01X830506Y501310D02*
X829065Y502751D01*
G01X828625Y501691D02*
X826711D01*
G01X829065Y502751D02*
X827151D01*
G01X826711Y501691D02*
X825219Y503183D01*
G01X827151Y502751D02*
X826279Y503623D01*
G01X825219Y503183D02*
Y587409D01*
G01X826279Y503623D02*
Y579416D01*
G01X825219Y503183D02*
Y587409D01*
G01Y503183D02*
Y587409D01*
G01X833880Y469249D02*
X832391Y470738D01*
G01X832820Y468806D02*
X831948Y469678D01*
G01X832391Y470738D02*
X831752D01*
G01X831948Y469678D02*
X831309D01*
G01X831752Y470738D02*
X830980Y471510D01*
G01X831309Y469678D02*
X829920Y471067D01*
G01X830980Y471510D02*
Y473406D01*
G01X829920Y471067D02*
Y473849D01*
G01X830980Y473406D02*
X831752Y474178D01*
G01X829920Y473849D02*
X831309Y475238D01*
G01X831752Y474178D02*
X832391D01*
G01X831309Y475238D02*
X831948D01*
G01X832391Y474178D02*
X833880Y475667D01*
G01X831948Y475238D02*
X832820Y476110D01*
G01X833880Y475667D02*
Y478249D01*
G01X832820Y476110D02*
Y477806D01*
G01X833880Y478249D02*
X832391Y479738D01*
G01X832820Y477806D02*
X831948Y478678D01*
G01X832391Y479738D02*
X831752D01*
G01X831948Y478678D02*
X831309D01*
G01X831752Y479738D02*
X830880Y480610D01*
G01X831309Y478678D02*
X829820Y480167D01*
G01X830880Y480610D02*
Y482306D01*
G01X829820Y480167D02*
Y482749D01*
G01X830880Y482306D02*
X831752Y483178D01*
G01X829820Y482749D02*
X831309Y484238D01*
G01X831752Y483178D02*
X832391D01*
G01X831309Y484238D02*
X831948D01*
G01X832391Y483178D02*
X833880Y484667D01*
G01X831948Y484238D02*
X832820Y485110D01*
G01X833880Y484667D02*
Y505551D01*
G01X832820Y485110D02*
Y505108D01*
G01X833880Y505551D02*
X831379Y508052D01*
G01X832820Y505108D02*
X830319Y507609D01*
G01X831379Y508052D02*
Y588035D01*
G01X830319Y507609D02*
Y578633D01*
G01X831379Y508052D02*
Y588035D01*
G01Y508052D02*
Y588035D01*
G01X797220Y468080D02*
X796351Y468949D01*
G01X798280Y468520D02*
X796791Y470009D01*
G01X796351Y468949D02*
X793386D01*
G01X796791Y470009D02*
X793826D01*
G01X793386Y468949D02*
X791864Y470471D01*
G01X793826Y470009D02*
X792924Y470911D01*
G01X791864Y470471D02*
Y473053D01*
G01X792924Y470911D02*
Y472613D01*
G01X791864Y473053D02*
X793320Y474509D01*
G01X792924Y472613D02*
X793760Y473449D01*
G01X793320Y474509D02*
X796348D01*
G01X793760Y473449D02*
X796788D01*
G01X796348Y474509D02*
X797220Y475381D01*
G01X796788Y473449D02*
X798280Y474941D01*
G01X797220Y475381D02*
Y477077D01*
G01X798280Y474941D02*
Y477517D01*
G01X797220Y477077D02*
X796348Y477949D01*
G01X798280Y477517D02*
X796788Y479009D01*
G01X796348Y477949D02*
X792568D01*
G01X796788Y479009D02*
X793008D01*
G01X792568Y477949D02*
X791079Y479438D01*
G01X793008Y479009D02*
X792139Y479878D01*
G01X791079Y479438D02*
Y482020D01*
G01X792139Y479878D02*
Y481580D01*
G01X791079Y482020D02*
X792568Y483509D01*
G01X792139Y481580D02*
X793008Y482449D01*
G01X792568Y483509D02*
X796348D01*
G01X793008Y482449D02*
X796788D01*
G01X796348Y483509D02*
X797220Y484381D01*
G01X796788Y482449D02*
X798280Y483941D01*
G01X797220Y484381D02*
Y486077D01*
G01X798280Y483941D02*
Y486520D01*
G01X797220Y486077D02*
X796348Y486949D01*
G01X798280Y486520D02*
X796791Y488009D01*
G01X796348Y486949D02*
X792209D01*
G01X796791Y488009D02*
X792652D01*
G01X792209Y486949D02*
X790720Y488438D01*
G01X792652Y488009D02*
X791780Y488881D01*
G01X790720Y488438D02*
Y491020D01*
G01X791780Y488881D02*
Y490580D01*
G01X790720Y491020D02*
X792209Y492509D01*
G01X791780Y490580D02*
X792649Y491449D01*
G01X792209Y492509D02*
X796168D01*
G01X792649Y491449D02*
X796608D01*
G01X796168Y492509D02*
X797040Y493381D01*
G01X796608Y491449D02*
X798100Y492941D01*
G01X797040Y493381D02*
Y495188D01*
G01X798100Y492941D02*
Y495628D01*
G01X797040Y495188D02*
X793508Y498720D01*
G01X798100Y495628D02*
X794568Y499160D01*
G01X793508Y498720D02*
Y538169D01*
G01X794568Y499160D02*
Y588070D01*
G01X826279Y464992D02*
Y487319D01*
G01D02*
X827151Y488191D01*
G01X825219Y487759D02*
X826711Y489251D01*
G01X827151Y488191D02*
X828933D01*
G01X826711Y489251D02*
X828490D01*
G01X828933Y488191D02*
X830422Y489680D01*
G01X828490Y489251D02*
X829362Y490123D01*
G01X830422Y489680D02*
Y492262D01*
G01X829362Y490123D02*
Y491822D01*
G01X830422Y492262D02*
X828933Y493751D01*
G01X829362Y491822D02*
X828493Y492691D01*
G01X828933Y493751D02*
X827151D01*
G01X828493Y492691D02*
X826711D01*
G01X827151Y493751D02*
X826279Y494623D01*
G01X826711Y492691D02*
X825219Y494183D01*
G01X826279Y494623D02*
Y496319D01*
G01X825219Y494183D02*
Y496759D01*
G01X826279Y496319D02*
X827151Y497191D01*
G01X825219Y496759D02*
X826711Y498251D01*
G01X827151Y497191D02*
X828969D01*
G01X826711Y498251D02*
X828529D01*
G01X828969Y497191D02*
X830506Y498728D01*
G01X828529Y498251D02*
X829446Y499168D01*
G01X830506Y498728D02*
Y501310D01*
G01X829446Y499168D02*
Y500870D01*
G01X830506Y501310D02*
X829065Y502751D01*
G01X829446Y500870D02*
X828625Y501691D01*
G01X829065Y502751D02*
X827151D01*
G01X828625Y501691D02*
X826711D01*
G01X827151Y502751D02*
X826279Y503623D01*
G01X826711Y501691D02*
X825219Y503183D01*
G01X826279Y503623D02*
Y579416D01*
G01X825219Y503183D02*
Y587409D01*
G01X832820Y468806D02*
X831948Y469678D01*
G01X833880Y469249D02*
X832391Y470738D01*
G01X831948Y469678D02*
X831309D01*
G01X832391Y470738D02*
X831752D01*
G01X831309Y469678D02*
X829920Y471067D01*
G01X831752Y470738D02*
X830980Y471510D01*
G01X829920Y471067D02*
Y473849D01*
G01X830980Y471510D02*
Y473406D01*
G01X829920Y473849D02*
X831309Y475238D01*
G01X830980Y473406D02*
X831752Y474178D01*
G01X831309Y475238D02*
X831948D01*
G01X831752Y474178D02*
X832391D01*
G01X831948Y475238D02*
X832820Y476110D01*
G01X832391Y474178D02*
X833880Y475667D01*
G01X832820Y476110D02*
Y477806D01*
G01X833880Y475667D02*
Y478249D01*
G01X832820Y477806D02*
X831948Y478678D01*
G01X833880Y478249D02*
X832391Y479738D01*
G01X831948Y478678D02*
X831309D01*
G01X832391Y479738D02*
X831752D01*
G01X831309Y478678D02*
X829820Y480167D01*
G01X831752Y479738D02*
X830880Y480610D01*
G01X829820Y480167D02*
Y482749D01*
G01X830880Y480610D02*
Y482306D01*
G01X829820Y482749D02*
X831309Y484238D01*
G01X830880Y482306D02*
X831752Y483178D01*
G01X831309Y484238D02*
X831948D01*
G01X831752Y483178D02*
X832391D01*
G01X831948Y484238D02*
X832820Y485110D01*
G01X832391Y483178D02*
X833880Y484667D01*
G01X832820Y485110D02*
Y505108D01*
G01X833880Y484667D02*
Y505551D01*
G01X832820Y505108D02*
X830319Y507609D01*
G01X833880Y505551D02*
X831379Y508052D01*
G01X830319Y507609D02*
Y578633D01*
G01X831379Y508052D02*
Y588035D01*
G01X789468Y581410D02*
Y582410D01*
G01Y584650D02*
Y587872D01*
G01Y581410D02*
Y582410D01*
G01Y584650D02*
Y587872D01*
G01Y581410D02*
Y582410D01*
G01Y584650D02*
Y587872D01*
G01Y581410D02*
Y582410D01*
G01Y584650D02*
Y587872D01*
G01X793508Y540115D02*
Y541377D01*
G01Y543387D02*
Y544502D01*
G01Y546742D02*
Y557139D01*
G01Y559379D02*
Y560379D01*
G01Y562619D02*
Y563619D01*
G01Y565859D02*
Y576356D01*
G01Y578596D02*
Y579596D01*
G01Y581836D02*
Y582836D01*
G01Y585076D02*
Y587459D01*
G01X826279Y581656D02*
Y582656D01*
G01Y584896D02*
Y587849D01*
G01X825219Y587409D02*
X824328Y588300D01*
G01X826279Y587849D02*
X823228Y590900D01*
G01X830319Y580707D02*
Y581874D01*
G01Y583946D02*
Y587595D01*
G01X831379Y588035D02*
X828300Y591114D01*
G01X830319Y587595D02*
X829400Y588514D01*
G01X831379Y588035D02*
X828300Y591114D01*
G01X793508Y540115D02*
Y541377D01*
G01Y543387D02*
Y544502D01*
G01Y546742D02*
Y557139D01*
G01Y559379D02*
Y560379D01*
G01Y562619D02*
Y563619D01*
G01Y565859D02*
Y576356D01*
G01Y578596D02*
Y579596D01*
G01Y581836D02*
Y582836D01*
G01Y585076D02*
Y587459D01*
G01X826279Y581656D02*
Y582656D01*
G01Y584896D02*
Y587849D01*
G01D02*
X823228Y590900D01*
G01X825219Y587409D02*
X824328Y588300D01*
G01X830319Y580707D02*
Y581874D01*
G01Y583946D02*
Y587595D01*
G01D02*
X829400Y588514D01*
G01X831379Y588035D02*
X828300Y591114D01*
G01X793508Y540115D02*
Y541377D01*
G01Y543387D02*
Y544502D01*
G01Y546742D02*
Y557139D01*
G01Y559379D02*
Y560379D01*
G01Y562619D02*
Y563619D01*
G01Y565859D02*
Y576356D01*
G01Y578596D02*
Y579596D01*
G01Y581836D02*
Y582836D01*
G01Y585076D02*
Y587459D01*
G01X826279Y581656D02*
Y582656D01*
G01Y584896D02*
Y587849D01*
G01X825219Y587409D02*
X824328Y588300D01*
G01X826279Y587849D02*
X823228Y590900D01*
G01X830319Y580707D02*
Y581874D01*
G01Y583946D02*
Y587595D01*
G01X831379Y588035D02*
X828300Y591114D01*
G01X830319Y587595D02*
X829400Y588514D01*
G01X831379Y588035D02*
X828300Y591114D01*
G01X793508Y540115D02*
Y541377D01*
G01Y543387D02*
Y544502D01*
G01Y546742D02*
Y557139D01*
G01Y559379D02*
Y560379D01*
G01Y562619D02*
Y563619D01*
G01Y565859D02*
Y576356D01*
G01Y578596D02*
Y579596D01*
G01Y581836D02*
Y582836D01*
G01Y585076D02*
Y587459D01*
G01X826279Y581656D02*
Y582656D01*
G01Y584896D02*
Y587849D01*
G01D02*
X823228Y590900D01*
G01X825219Y587409D02*
X824328Y588300D01*
G01X830319Y580707D02*
Y581874D01*
G01Y583946D02*
Y587595D01*
G01D02*
X829400Y588514D01*
G01X831379Y588035D02*
X828300Y591114D01*
G01X790684Y595500D02*
X790013Y596171D01*
G01X789783Y594900D02*
X788953Y595730D01*
G01X790013Y596171D02*
Y597448D01*
G01Y600938D02*
Y601829D01*
G01X788953Y595730D02*
Y602270D01*
G01X790013Y601829D02*
X790784Y602600D01*
G01X788953Y602270D02*
X789783Y603100D01*
G01X821211Y590000D02*
Y608011D01*
G01X822271Y595890D02*
Y597260D01*
G01X821211Y590000D02*
Y608011D01*
G01X822271Y600940D02*
Y602360D01*
G01X827495Y595500D02*
X826824Y596171D01*
G01X826594Y594900D02*
X825764Y595730D01*
G01X826824Y596171D02*
Y597448D01*
G01Y600938D02*
Y601829D01*
G01X825764Y595730D02*
Y602270D01*
G01X826824Y601829D02*
X827595Y602600D01*
G01X825764Y602270D02*
X826594Y603100D01*
G01X829400Y588514D02*
X828299D01*
G01X789783Y594900D02*
X788953Y595730D01*
G01X790684Y595500D02*
X790013Y596171D01*
G01X788953Y595730D02*
Y602270D01*
G01X790013Y596171D02*
Y597448D01*
G01X788953Y595730D02*
Y602270D01*
G01X790013Y600938D02*
Y601829D01*
G01X788953Y602270D02*
X789783Y603100D01*
G01X790013Y601829D02*
X790784Y602600D01*
G01X822271Y595890D02*
Y597260D01*
G01Y600940D02*
Y602360D01*
G01X821211Y590000D02*
Y608011D01*
G01X826594Y594900D02*
X825764Y595730D01*
G01X827495Y595500D02*
X826824Y596171D01*
G01X825764Y595730D02*
Y602270D01*
G01X826824Y596171D02*
Y597448D01*
G01X825764Y595730D02*
Y602270D01*
G01X826824Y600938D02*
Y601829D01*
G01X825764Y602270D02*
X826594Y603100D01*
G01X826824Y601829D02*
X827595Y602600D01*
G01X829400Y588514D02*
X828299D01*
G01X790684Y595500D02*
X790013Y596171D01*
G01X789783Y594900D02*
X788953Y595730D01*
G01X790013Y596171D02*
Y597448D01*
G01Y600938D02*
Y601829D01*
G01X788953Y595730D02*
Y602270D01*
G01X790013Y601829D02*
X790784Y602600D01*
G01X788953Y602270D02*
X789783Y603100D01*
G01X821211Y590000D02*
Y608011D01*
G01X822271Y595890D02*
Y597260D01*
G01X821211Y590000D02*
Y608011D01*
G01X822271Y600940D02*
Y602360D01*
G01X827495Y595500D02*
X826824Y596171D01*
G01X826594Y594900D02*
X825764Y595730D01*
G01X826824Y596171D02*
Y597448D01*
G01Y600938D02*
Y601829D01*
G01X825764Y595730D02*
Y602270D01*
G01X826824Y601829D02*
X827595Y602600D01*
G01X825764Y602270D02*
X826594Y603100D01*
G01X829400Y588514D02*
X828299D01*
G01X789783Y594900D02*
X788953Y595730D01*
G01X790684Y595500D02*
X790013Y596171D01*
G01X788953Y595730D02*
Y602270D01*
G01X790013Y596171D02*
Y597448D01*
G01X788953Y595730D02*
Y602270D01*
G01X790013Y600938D02*
Y601829D01*
G01X788953Y602270D02*
X789783Y603100D01*
G01X790013Y601829D02*
X790784Y602600D01*
G01X822271Y595890D02*
Y597260D01*
G01Y600940D02*
Y602360D01*
G01X821211Y590000D02*
Y608011D01*
G01X826594Y594900D02*
X825764Y595730D01*
G01X827495Y595500D02*
X826824Y596171D01*
G01X825764Y595730D02*
Y602270D01*
G01X826824Y596171D02*
Y597448D01*
G01X825764Y595730D02*
Y602270D01*
G01X826824Y600938D02*
Y601829D01*
G01X825764Y602270D02*
X826594Y603100D01*
G01X826824Y601829D02*
X827595Y602600D01*
G01X829400Y588514D02*
X828299D01*
G01X858156Y13554D02*
Y21131D01*
G01X859216Y19620D02*
Y20688D01*
G01X858156Y21131D02*
X862030Y25005D01*
G01X859216Y20688D02*
X863090Y24562D01*
G01X862030Y25005D02*
Y97753D01*
G01X863090Y24562D02*
Y36780D01*
G01X862030Y25005D02*
Y97753D01*
G01Y25005D02*
Y97753D01*
G01Y25005D02*
Y97753D01*
G01Y25005D02*
Y97753D01*
G01X861109Y11700D02*
X862056Y10753D01*
G01X860010Y14300D02*
X863116Y11194D01*
G01X862056Y10753D02*
Y8220D01*
G01Y4080D02*
Y3120D01*
G01Y-1220D02*
Y-4509D01*
G01X863116Y11194D02*
Y-4952D01*
G01X862056Y-4509D02*
X861345Y-5220D01*
G01D02*
X860829D01*
G01X863116Y-4952D02*
X861788Y-6280D01*
G01X861345Y-5220D02*
X860829D01*
G01X861788Y-6280D02*
X860806D01*
G01X858156Y13554D02*
Y21131D01*
G01X859216Y19620D02*
Y20688D01*
G01X858156Y21131D02*
X862030Y25005D01*
G01X859216Y20688D02*
X863090Y24562D01*
G01X862030Y25005D02*
Y97753D01*
G01X863090Y24562D02*
Y36780D01*
G01X862030Y25005D02*
Y97753D01*
G01Y25005D02*
Y97753D01*
G01Y25005D02*
Y97753D01*
G01Y25005D02*
Y97753D01*
G01X861109Y11700D02*
X862056Y10753D01*
G01X860010Y14300D02*
X863116Y11194D01*
G01X862056Y10753D02*
Y8220D01*
G01Y4080D02*
Y3120D01*
G01Y-1220D02*
Y-4509D01*
G01X863116Y11194D02*
Y-4952D01*
G01X862056Y-4509D02*
X861345Y-5220D01*
G01D02*
X860829D01*
G01X863116Y-4952D02*
X861788Y-6280D01*
G01X861345Y-5220D02*
X860829D01*
G01X861788Y-6280D02*
X860806D01*
G01X894967Y13554D02*
Y21531D01*
G01X896027Y19620D02*
Y21088D01*
G01X894967Y21531D02*
X898841Y25405D01*
G01X896027Y21088D02*
X899901Y24962D01*
G01X898841Y25405D02*
Y115009D01*
G01X899901Y24962D02*
Y36780D01*
G01X898841Y25405D02*
Y115009D01*
G01Y25405D02*
Y115009D01*
G01Y25405D02*
Y115009D01*
G01Y25405D02*
Y115009D01*
G01X896821Y11700D02*
X897920D01*
G01D02*
X898867Y10753D01*
G01X896821Y14300D02*
X899927Y11194D01*
G01X898867Y10753D02*
Y8220D01*
G01Y4080D02*
Y3120D01*
G01Y-1220D02*
Y-4509D01*
G01X899927Y11194D02*
Y-4952D01*
G01X898867Y-4509D02*
X898156Y-5220D01*
G01D02*
X897640D01*
G01X899927Y-4952D02*
X898599Y-6280D01*
G01X898156Y-5220D02*
X897640D01*
G01X898599Y-6280D02*
X897617D01*
G01X894967Y13554D02*
Y21531D01*
G01X896027Y19620D02*
Y21088D01*
G01X894967Y21531D02*
X898841Y25405D01*
G01X896027Y21088D02*
X899901Y24962D01*
G01X898841Y25405D02*
Y115009D01*
G01X899901Y24962D02*
Y36780D01*
G01X898841Y25405D02*
Y115009D01*
G01Y25405D02*
Y115009D01*
G01Y25405D02*
Y115009D01*
G01Y25405D02*
Y115009D01*
G01X896821Y11700D02*
X897920D01*
G01D02*
X898867Y10753D01*
G01X896821Y14300D02*
X899927Y11194D01*
G01X898867Y10753D02*
Y8220D01*
G01Y4080D02*
Y3120D01*
G01Y-1220D02*
Y-4509D01*
G01X899927Y11194D02*
Y-4952D01*
G01X898867Y-4509D02*
X898156Y-5220D01*
G01D02*
X897640D01*
G01X899927Y-4952D02*
X898599Y-6280D01*
G01X898156Y-5220D02*
X897640D01*
G01X898599Y-6280D02*
X897617D01*
G01X863856Y18755D02*
Y21231D01*
G01X864916Y19920D02*
Y20788D01*
G01X863856Y21231D02*
X867130Y24505D01*
G01X864916Y20788D02*
X865890Y21762D01*
G01X867130Y24505D02*
Y132337D01*
G01X868190Y26134D02*
Y131897D01*
G01X867242Y10881D02*
X866208Y11915D01*
G01D02*
X865110D01*
G01Y14514D02*
X868302Y11322D01*
G01X867242Y-3628D02*
Y-1007D01*
G01Y2907D02*
Y4280D01*
G01Y8106D02*
Y10881D01*
G01X868302Y11322D02*
Y-4068D01*
G01X865110Y-4651D02*
X866219D01*
G01D02*
X867242Y-3628D01*
G01X868302Y-4068D02*
X865110Y-7260D01*
G01X863856Y18755D02*
Y21231D01*
G01X864916Y19920D02*
Y20788D01*
G01X863856Y21231D02*
X867130Y24505D01*
G01X864916Y20788D02*
X865890Y21762D01*
G01X867130Y24505D02*
Y132337D01*
G01X868190Y26134D02*
Y131897D01*
G01X867242Y10881D02*
X866208Y11915D01*
G01D02*
X865110D01*
G01Y14514D02*
X868302Y11322D01*
G01X867242Y-3628D02*
Y-1007D01*
G01Y2907D02*
Y4280D01*
G01Y8106D02*
Y10881D01*
G01X868302Y11322D02*
Y-4068D01*
G01X865110Y-4651D02*
X866219D01*
G01D02*
X867242Y-3628D01*
G01X868302Y-4068D02*
X865110Y-7260D01*
G01X900667Y18567D02*
Y21231D01*
G01X901727Y19920D02*
Y20788D01*
G01X900667Y21231D02*
X903941Y24505D01*
G01X901727Y20788D02*
X902701Y21762D01*
G01X900667Y21231D02*
X903941Y24505D01*
G01X904285Y23346D02*
X905001Y24062D01*
G01X903941Y24505D02*
Y114709D01*
G01X905001Y24062D02*
Y32500D01*
G01X903941Y24505D02*
Y114709D01*
G01Y24505D02*
Y114709D01*
G01Y24505D02*
Y114709D01*
G01X904053Y10881D02*
X903019Y11915D01*
G01D02*
X901921D01*
G01Y14514D02*
X905113Y11322D01*
G01X904053Y-3628D02*
Y-1007D01*
G01Y2907D02*
Y4280D01*
G01Y8106D02*
Y10881D01*
G01X905113Y11322D02*
Y-4068D01*
G01X901921Y-4651D02*
X903030D01*
G01D02*
X904053Y-3628D01*
G01X905113Y-4068D02*
X901921Y-7260D01*
G01X900667Y18567D02*
Y21231D01*
G01X901727Y19920D02*
Y20788D01*
G01X900667Y21231D02*
X903941Y24505D01*
G01X901727Y20788D02*
X902701Y21762D01*
G01X900667Y21231D02*
X903941Y24505D01*
G01X904285Y23346D02*
X905001Y24062D01*
G01X903941Y24505D02*
Y114709D01*
G01X905001Y24062D02*
Y32500D01*
G01X903941Y24505D02*
Y114709D01*
G01Y24505D02*
Y114709D01*
G01Y24505D02*
Y114709D01*
G01X904053Y10881D02*
X903019Y11915D01*
G01D02*
X901921D01*
G01Y14514D02*
X905113Y11322D01*
G01X904053Y-3628D02*
Y-1007D01*
G01Y2907D02*
Y4280D01*
G01Y8106D02*
Y10881D01*
G01X905113Y11322D02*
Y-4068D01*
G01X901921Y-4651D02*
X903030D01*
G01D02*
X904053Y-3628D01*
G01X905113Y-4068D02*
X901921Y-7260D01*
G01X859216Y19620D02*
Y20688D01*
G01X858156Y13554D02*
Y21131D01*
G01X859216Y20688D02*
X863090Y24562D01*
G01X858156Y21131D02*
X862030Y25005D01*
G01X863090Y24562D02*
Y36780D01*
G01X862030Y25005D02*
Y97753D01*
G01X860010Y14300D02*
X863116Y11194D01*
G01X861109Y11700D02*
X862056Y10753D01*
G01X863116Y11194D02*
Y-4952D01*
G01X862056Y10753D02*
Y8220D01*
G01X863116Y11194D02*
Y-4952D01*
G01X862056Y4080D02*
Y3120D01*
G01X863116Y11194D02*
Y-4952D01*
G01X862056Y-1220D02*
Y-4509D01*
G01X863116Y-4952D02*
X861788Y-6280D01*
G01X862056Y-4509D02*
X861345Y-5220D01*
G01X863116Y-4952D02*
X861788Y-6280D01*
G01D02*
X860806D01*
G01X861345Y-5220D02*
X860829D01*
G01X859216Y19620D02*
Y20688D01*
G01X858156Y13554D02*
Y21131D01*
G01X859216Y20688D02*
X863090Y24562D01*
G01X858156Y21131D02*
X862030Y25005D01*
G01X863090Y24562D02*
Y36780D01*
G01X862030Y25005D02*
Y97753D01*
G01X860010Y14300D02*
X863116Y11194D01*
G01X861109Y11700D02*
X862056Y10753D01*
G01X863116Y11194D02*
Y-4952D01*
G01X862056Y10753D02*
Y8220D01*
G01X863116Y11194D02*
Y-4952D01*
G01X862056Y4080D02*
Y3120D01*
G01X863116Y11194D02*
Y-4952D01*
G01X862056Y-1220D02*
Y-4509D01*
G01X863116Y-4952D02*
X861788Y-6280D01*
G01X862056Y-4509D02*
X861345Y-5220D01*
G01X863116Y-4952D02*
X861788Y-6280D01*
G01D02*
X860806D01*
G01X861345Y-5220D02*
X860829D01*
G01X896027Y19620D02*
Y21088D01*
G01X894967Y13554D02*
Y21531D01*
G01X896027Y21088D02*
X899901Y24962D01*
G01X894967Y21531D02*
X898841Y25405D01*
G01X899901Y24962D02*
Y36780D01*
G01X898841Y25405D02*
Y115009D01*
G01X896821Y14300D02*
X899927Y11194D01*
G01X896821Y11700D02*
X897920D01*
G01X896821Y14300D02*
X899927Y11194D01*
G01X897920Y11700D02*
X898867Y10753D01*
G01X899927Y11194D02*
Y-4952D01*
G01X898867Y10753D02*
Y8220D01*
G01X899927Y11194D02*
Y-4952D01*
G01X898867Y4080D02*
Y3120D01*
G01X899927Y11194D02*
Y-4952D01*
G01X898867Y-1220D02*
Y-4509D01*
G01X899927Y-4952D02*
X898599Y-6280D01*
G01X898867Y-4509D02*
X898156Y-5220D01*
G01X899927Y-4952D02*
X898599Y-6280D01*
G01D02*
X897617D01*
G01X898156Y-5220D02*
X897640D01*
G01X896027Y19620D02*
Y21088D01*
G01X894967Y13554D02*
Y21531D01*
G01X896027Y21088D02*
X899901Y24962D01*
G01X894967Y21531D02*
X898841Y25405D01*
G01X899901Y24962D02*
Y36780D01*
G01X898841Y25405D02*
Y115009D01*
G01X896821Y14300D02*
X899927Y11194D01*
G01X896821Y11700D02*
X897920D01*
G01X896821Y14300D02*
X899927Y11194D01*
G01X897920Y11700D02*
X898867Y10753D01*
G01X899927Y11194D02*
Y-4952D01*
G01X898867Y10753D02*
Y8220D01*
G01X899927Y11194D02*
Y-4952D01*
G01X898867Y4080D02*
Y3120D01*
G01X899927Y11194D02*
Y-4952D01*
G01X898867Y-1220D02*
Y-4509D01*
G01X899927Y-4952D02*
X898599Y-6280D01*
G01X898867Y-4509D02*
X898156Y-5220D01*
G01X899927Y-4952D02*
X898599Y-6280D01*
G01D02*
X897617D01*
G01X898156Y-5220D02*
X897640D01*
G01X864916Y19920D02*
Y20788D01*
G01X863856Y18755D02*
Y21231D01*
G01X864916Y20788D02*
X865890Y21762D01*
G01X863856Y21231D02*
X867130Y24505D01*
G01X868190Y26134D02*
Y131897D01*
G01X867130Y24505D02*
Y132337D01*
G01X868302Y-4068D02*
X865110Y-7260D01*
G01Y-4651D02*
X866219D01*
G01X868302Y-4068D02*
X865110Y-7260D01*
G01X866219Y-4651D02*
X867242Y-3628D01*
G01X868302Y11322D02*
Y-4068D01*
G01X867242Y-3628D02*
Y-1007D01*
G01X868302Y11322D02*
Y-4068D01*
G01X867242Y2907D02*
Y4280D01*
G01X868302Y11322D02*
Y-4068D01*
G01X867242Y8106D02*
Y10881D01*
G01X865110Y14514D02*
X868302Y11322D01*
G01X867242Y10881D02*
X866208Y11915D01*
G01X865110Y14514D02*
X868302Y11322D01*
G01X866208Y11915D02*
X865110D01*
G01X864916Y19920D02*
Y20788D01*
G01X863856Y18755D02*
Y21231D01*
G01X864916Y20788D02*
X865890Y21762D01*
G01X863856Y21231D02*
X867130Y24505D01*
G01X868190Y26134D02*
Y131897D01*
G01X867130Y24505D02*
Y132337D01*
G01X868302Y-4068D02*
X865110Y-7260D01*
G01Y-4651D02*
X866219D01*
G01X868302Y-4068D02*
X865110Y-7260D01*
G01X866219Y-4651D02*
X867242Y-3628D01*
G01X868302Y11322D02*
Y-4068D01*
G01X867242Y-3628D02*
Y-1007D01*
G01X868302Y11322D02*
Y-4068D01*
G01X867242Y2907D02*
Y4280D01*
G01X868302Y11322D02*
Y-4068D01*
G01X867242Y8106D02*
Y10881D01*
G01X865110Y14514D02*
X868302Y11322D01*
G01X867242Y10881D02*
X866208Y11915D01*
G01X865110Y14514D02*
X868302Y11322D01*
G01X866208Y11915D02*
X865110D01*
G01X901727Y19920D02*
Y20788D01*
G01X900667Y18567D02*
Y21231D01*
G01X901727Y20788D02*
X902701Y21762D01*
G01X904285Y23346D02*
X905001Y24062D01*
G01X900667Y21231D02*
X903941Y24505D01*
G01X905001Y24062D02*
Y32500D01*
G01X903941Y24505D02*
Y114709D01*
G01X905113Y-4068D02*
X901921Y-7260D01*
G01Y-4651D02*
X903030D01*
G01X905113Y-4068D02*
X901921Y-7260D01*
G01X903030Y-4651D02*
X904053Y-3628D01*
G01X905113Y11322D02*
Y-4068D01*
G01X904053Y-3628D02*
Y-1007D01*
G01X905113Y11322D02*
Y-4068D01*
G01X904053Y2907D02*
Y4280D01*
G01X905113Y11322D02*
Y-4068D01*
G01X904053Y8106D02*
Y10881D01*
G01X901921Y14514D02*
X905113Y11322D01*
G01X904053Y10881D02*
X903019Y11915D01*
G01X901921Y14514D02*
X905113Y11322D01*
G01X903019Y11915D02*
X901921D01*
G01X901727Y19920D02*
Y20788D01*
G01X900667Y18567D02*
Y21231D01*
G01X901727Y20788D02*
X902701Y21762D01*
G01X904285Y23346D02*
X905001Y24062D01*
G01X900667Y21231D02*
X903941Y24505D01*
G01X905001Y24062D02*
Y32500D01*
G01X903941Y24505D02*
Y114709D01*
G01X905113Y-4068D02*
X901921Y-7260D01*
G01Y-4651D02*
X903030D01*
G01X905113Y-4068D02*
X901921Y-7260D01*
G01X903030Y-4651D02*
X904053Y-3628D01*
G01X905113Y11322D02*
Y-4068D01*
G01X904053Y-3628D02*
Y-1007D01*
G01X905113Y11322D02*
Y-4068D01*
G01X904053Y2907D02*
Y4280D01*
G01X905113Y11322D02*
Y-4068D01*
G01X904053Y8106D02*
Y10881D01*
G01X901921Y14514D02*
X905113Y11322D01*
G01X904053Y10881D02*
X903019Y11915D01*
G01X901921Y14514D02*
X905113Y11322D01*
G01X903019Y11915D02*
X901921D01*
G01X863090Y39020D02*
Y39780D01*
G01Y42020D02*
Y42780D01*
G01Y45020D02*
Y55980D01*
G01Y58220D02*
Y98193D01*
G01Y39020D02*
Y39780D01*
G01Y42020D02*
Y42780D01*
G01Y45020D02*
Y55980D01*
G01Y58220D02*
Y98193D01*
G01X899901Y39020D02*
Y39780D01*
G01Y42020D02*
Y42780D01*
G01Y45020D02*
Y55880D01*
G01Y58120D02*
Y114569D01*
G01Y39020D02*
Y39780D01*
G01Y42020D02*
Y42780D01*
G01Y45020D02*
Y55880D01*
G01Y58120D02*
Y114569D01*
G01X905001Y34500D02*
Y36980D01*
G01Y39220D02*
Y39980D01*
G01Y42220D02*
Y114269D01*
G01Y34500D02*
Y36980D01*
G01Y39220D02*
Y39980D01*
G01Y42220D02*
Y114269D01*
G01X863090Y39020D02*
Y39780D01*
G01Y42020D02*
Y42780D01*
G01Y45020D02*
Y55980D01*
G01Y58220D02*
Y98193D01*
G01Y39020D02*
Y39780D01*
G01Y42020D02*
Y42780D01*
G01Y45020D02*
Y55980D01*
G01Y58220D02*
Y98193D01*
G01X899901Y39020D02*
Y39780D01*
G01Y42020D02*
Y42780D01*
G01Y45020D02*
Y55880D01*
G01Y58120D02*
Y114569D01*
G01Y39020D02*
Y39780D01*
G01Y42020D02*
Y42780D01*
G01Y45020D02*
Y55880D01*
G01Y58120D02*
Y114569D01*
G01X905001Y34500D02*
Y36980D01*
G01Y39220D02*
Y39980D01*
G01Y42220D02*
Y114269D01*
G01Y34500D02*
Y36980D01*
G01Y39220D02*
Y39980D01*
G01Y42220D02*
Y114269D01*
G01X862030Y97753D02*
X859620Y100163D01*
G01X863090Y98193D02*
X860680Y100603D01*
G01X859620Y100163D02*
Y103565D01*
G01X860680Y100603D02*
Y103125D01*
G01X859620Y103565D02*
X861817Y105762D01*
G01X860680Y103125D02*
X862257Y104702D01*
G01X861817Y105762D02*
X862448D01*
G01X862257Y104702D02*
X862888D01*
G01X862448Y105762D02*
X863320Y106634D01*
G01X862888Y104702D02*
X864380Y106194D01*
G01X863320Y106634D02*
Y134012D01*
G01X864380Y106194D02*
Y133572D01*
G01X863320Y134012D02*
X911538Y182230D01*
G01X864380Y133572D02*
X893377Y162569D01*
G01X863320Y134012D02*
X911538Y182230D01*
G01X863320Y134012D02*
X911538Y182230D01*
G01X863320Y134012D02*
X911538Y182230D01*
G01X863320Y134012D02*
X911538Y182230D01*
G01X863320Y134012D02*
X911538Y182230D01*
G01X863320Y134012D02*
X911538Y182230D01*
G01X863320Y134012D02*
X911538Y182230D01*
G01X863320Y134012D02*
X911538Y182230D01*
G01X863320Y134012D02*
X911538Y182230D01*
G01X862030Y97753D02*
X859620Y100163D01*
G01X863090Y98193D02*
X860680Y100603D01*
G01X859620Y100163D02*
Y103565D01*
G01X860680Y100603D02*
Y103125D01*
G01X859620Y103565D02*
X861817Y105762D01*
G01X860680Y103125D02*
X862257Y104702D01*
G01X861817Y105762D02*
X862448D01*
G01X862257Y104702D02*
X862888D01*
G01X862448Y105762D02*
X863320Y106634D01*
G01X862888Y104702D02*
X864380Y106194D01*
G01X863320Y106634D02*
Y134012D01*
G01X864380Y106194D02*
Y133572D01*
G01X863320Y134012D02*
X911538Y182230D01*
G01X864380Y133572D02*
X893377Y162569D01*
G01X863320Y134012D02*
X911538Y182230D01*
G01X863320Y134012D02*
X911538Y182230D01*
G01X863320Y134012D02*
X911538Y182230D01*
G01X863320Y134012D02*
X911538Y182230D01*
G01X863320Y134012D02*
X911538Y182230D01*
G01X863320Y134012D02*
X911538Y182230D01*
G01X863320Y134012D02*
X911538Y182230D01*
G01X863320Y134012D02*
X911538Y182230D01*
G01X863320Y134012D02*
X911538Y182230D01*
G01X898841Y115009D02*
X906082Y122250D01*
G01X899901Y114569D02*
X907142Y121810D01*
G01X906082Y122250D02*
Y123482D01*
G01X907142Y121810D02*
Y123922D01*
G01X906082Y123482D02*
X903665Y125899D01*
G01X907142Y123922D02*
X904725Y126339D01*
G01X903665Y125899D02*
Y127819D01*
G01X904725Y126339D02*
Y127379D01*
G01X903665Y127819D02*
X906185Y130339D01*
G01X904725Y127379D02*
X906625Y129279D01*
G01X903665Y127819D02*
X906185Y130339D01*
G01D02*
X908225D01*
G01X906625Y129279D02*
X907785D01*
G01X908225Y130339D02*
X910582Y127982D01*
G01X907785Y129279D02*
X910142Y126922D01*
G01X898841Y115009D02*
X906082Y122250D01*
G01X899901Y114569D02*
X907142Y121810D01*
G01X906082Y122250D02*
Y123482D01*
G01X907142Y121810D02*
Y123922D01*
G01X906082Y123482D02*
X903665Y125899D01*
G01X907142Y123922D02*
X904725Y126339D01*
G01X903665Y125899D02*
Y127819D01*
G01X904725Y126339D02*
Y127379D01*
G01X903665Y127819D02*
X906185Y130339D01*
G01X904725Y127379D02*
X906625Y129279D01*
G01X903665Y127819D02*
X906185Y130339D01*
G01D02*
X908225D01*
G01X906625Y129279D02*
X907785D01*
G01X908225Y130339D02*
X910582Y127982D01*
G01X907785Y129279D02*
X910142Y126922D01*
G01X867130Y132337D02*
X915072Y180279D01*
G01X868190Y131897D02*
X916132Y179839D01*
G01X867130Y132337D02*
X915072Y180279D01*
G01X868190Y131897D02*
X916132Y179839D01*
G01X903941Y114709D02*
X926983Y137751D01*
G01X905001Y114269D02*
X928043Y137311D01*
G01X903941Y114709D02*
X926983Y137751D01*
G01X905001Y114269D02*
X928043Y137311D01*
G01X863090Y98193D02*
X860680Y100603D01*
G01X862030Y97753D02*
X859620Y100163D01*
G01X860680Y100603D02*
Y103125D01*
G01X859620Y100163D02*
Y103565D01*
G01X860680Y103125D02*
X862257Y104702D01*
G01X859620Y103565D02*
X861817Y105762D01*
G01X862257Y104702D02*
X862888D01*
G01X861817Y105762D02*
X862448D01*
G01X862888Y104702D02*
X864380Y106194D01*
G01X862448Y105762D02*
X863320Y106634D01*
G01X864380Y106194D02*
Y133572D01*
G01X863320Y106634D02*
Y134012D01*
G01X864380Y133572D02*
X893377Y162569D01*
G01X863320Y134012D02*
X911538Y182230D01*
G01X863090Y98193D02*
X860680Y100603D01*
G01X862030Y97753D02*
X859620Y100163D01*
G01X860680Y100603D02*
Y103125D01*
G01X859620Y100163D02*
Y103565D01*
G01X860680Y103125D02*
X862257Y104702D01*
G01X859620Y103565D02*
X861817Y105762D01*
G01X862257Y104702D02*
X862888D01*
G01X861817Y105762D02*
X862448D01*
G01X862888Y104702D02*
X864380Y106194D01*
G01X862448Y105762D02*
X863320Y106634D01*
G01X864380Y106194D02*
Y133572D01*
G01X863320Y106634D02*
Y134012D01*
G01X864380Y133572D02*
X893377Y162569D01*
G01X863320Y134012D02*
X911538Y182230D01*
G01X899901Y114569D02*
X907142Y121810D01*
G01X898841Y115009D02*
X906082Y122250D01*
G01X907142Y121810D02*
Y123922D01*
G01X906082Y122250D02*
Y123482D01*
G01X907142Y123922D02*
X904725Y126339D01*
G01X906082Y123482D02*
X903665Y125899D01*
G01X904725Y126339D02*
Y127379D01*
G01X903665Y125899D02*
Y127819D01*
G01X904725Y127379D02*
X906625Y129279D01*
G01D02*
X907785D01*
G01X903665Y127819D02*
X906185Y130339D01*
G01X906625Y129279D02*
X907785D01*
G01X906185Y130339D02*
X908225D01*
G01X907785Y129279D02*
X910142Y126922D01*
G01X908225Y130339D02*
X910582Y127982D01*
G01X899901Y114569D02*
X907142Y121810D01*
G01X898841Y115009D02*
X906082Y122250D01*
G01X907142Y121810D02*
Y123922D01*
G01X906082Y122250D02*
Y123482D01*
G01X907142Y123922D02*
X904725Y126339D01*
G01X906082Y123482D02*
X903665Y125899D01*
G01X904725Y126339D02*
Y127379D01*
G01X903665Y125899D02*
Y127819D01*
G01X904725Y127379D02*
X906625Y129279D01*
G01D02*
X907785D01*
G01X903665Y127819D02*
X906185Y130339D01*
G01X906625Y129279D02*
X907785D01*
G01X906185Y130339D02*
X908225D01*
G01X907785Y129279D02*
X910142Y126922D01*
G01X908225Y130339D02*
X910582Y127982D01*
G01X868190Y131897D02*
X916132Y179839D01*
G01X867130Y132337D02*
X915072Y180279D01*
G01X868190Y131897D02*
X916132Y179839D01*
G01X867130Y132337D02*
X915072Y180279D01*
G01X905001Y114269D02*
X928043Y137311D01*
G01X903941Y114709D02*
X926983Y137751D01*
G01X905001Y114269D02*
X928043Y137311D01*
G01X903941Y114709D02*
X926983Y137751D01*
G01X904572Y225240D02*
X853804Y174472D01*
G01X904572Y225240D02*
X853804Y174472D01*
G01X904572Y225240D02*
X853804Y174472D01*
G01X899784Y218952D02*
X898859Y218027D01*
G01X904572Y225240D02*
X853804Y174472D01*
G01X897514Y216682D02*
X896801Y215969D01*
G01X904572Y225240D02*
X853804Y174472D01*
G01X895457Y214625D02*
X894584Y213752D01*
G01X904572Y225240D02*
X853804Y174472D01*
G01X893239Y212407D02*
X892343Y211511D01*
G01X904572Y225240D02*
X853804Y174472D01*
G01X890999Y210167D02*
X890292Y209460D01*
G01X904572Y225240D02*
X853804Y174472D01*
G01X888948Y208116D02*
X888241Y207409D01*
G01X904572Y225240D02*
X853804Y174472D01*
G01X886897Y206065D02*
X886171Y205339D01*
G01X904572Y225240D02*
X853804Y174472D01*
G01X884826Y203994D02*
X884113Y203281D01*
G01X904572Y225240D02*
X853804Y174472D01*
G01X882769Y201937D02*
X881689Y200857D01*
G01X904572Y225240D02*
X853804Y174472D01*
G01X880345Y199513D02*
X879014Y198182D01*
G01X904572Y225240D02*
X853804Y174472D01*
G01X877670Y196838D02*
X876614Y195782D01*
G01X904572Y225240D02*
X853804Y174472D01*
G01X875269Y194437D02*
X874442Y193610D01*
G01X904572Y225240D02*
X853804Y174472D01*
G01X873097Y192265D02*
X872156Y191324D01*
G01X904572Y225240D02*
X853804Y174472D01*
G01X870812Y189980D02*
X869756Y188924D01*
G01X904572Y225240D02*
X853804Y174472D01*
G01X868411Y187579D02*
X867538Y186706D01*
G01X904572Y225240D02*
X853804Y174472D01*
G01X866193Y185361D02*
X854864Y174032D01*
G01X853804Y174472D02*
Y170676D01*
G01X854864Y174032D02*
Y170236D01*
G01X904572Y225240D02*
X853804Y174472D01*
G01X904572Y225240D02*
X853804Y174472D01*
G01X904572Y225240D02*
X853804Y174472D01*
G01X899784Y218952D02*
X898859Y218027D01*
G01X904572Y225240D02*
X853804Y174472D01*
G01X897514Y216682D02*
X896801Y215969D01*
G01X904572Y225240D02*
X853804Y174472D01*
G01X895457Y214625D02*
X894584Y213752D01*
G01X904572Y225240D02*
X853804Y174472D01*
G01X893239Y212407D02*
X892343Y211511D01*
G01X904572Y225240D02*
X853804Y174472D01*
G01X890999Y210167D02*
X890292Y209460D01*
G01X904572Y225240D02*
X853804Y174472D01*
G01X888948Y208116D02*
X888241Y207409D01*
G01X904572Y225240D02*
X853804Y174472D01*
G01X886897Y206065D02*
X886171Y205339D01*
G01X904572Y225240D02*
X853804Y174472D01*
G01X884826Y203994D02*
X884113Y203281D01*
G01X904572Y225240D02*
X853804Y174472D01*
G01X882769Y201937D02*
X881689Y200857D01*
G01X904572Y225240D02*
X853804Y174472D01*
G01X880345Y199513D02*
X879014Y198182D01*
G01X904572Y225240D02*
X853804Y174472D01*
G01X877670Y196838D02*
X876614Y195782D01*
G01X904572Y225240D02*
X853804Y174472D01*
G01X875269Y194437D02*
X874442Y193610D01*
G01X904572Y225240D02*
X853804Y174472D01*
G01X873097Y192265D02*
X872156Y191324D01*
G01X904572Y225240D02*
X853804Y174472D01*
G01X870812Y189980D02*
X869756Y188924D01*
G01X904572Y225240D02*
X853804Y174472D01*
G01X868411Y187579D02*
X867538Y186706D01*
G01X904572Y225240D02*
X853804Y174472D01*
G01X866193Y185361D02*
X854864Y174032D01*
G01X853804Y174472D02*
Y170676D01*
G01X854864Y174032D02*
Y170236D01*
G01X849802Y159401D02*
Y160961D01*
G01X850862Y158961D02*
Y160521D01*
G01X849802Y160961D02*
X860318Y171477D01*
G01X850862Y160521D02*
X861378Y171037D01*
G01X860318Y171477D02*
Y175386D01*
G01X861378Y171037D02*
Y174946D01*
G01X860318Y175386D02*
X906160Y221228D01*
G01X861378Y174946D02*
X891341Y204909D01*
G01X860318Y175386D02*
X906160Y221228D01*
G01X892685Y206253D02*
X893398Y206966D01*
G01X860318Y175386D02*
X906160Y221228D01*
G01X894743Y208311D02*
X895456Y209024D01*
G01X860318Y175386D02*
X906160Y221228D01*
G01X896800Y210368D02*
X898382Y211950D01*
G01X860318Y175386D02*
X906160Y221228D01*
G01X899727Y213295D02*
X901148Y214716D01*
G01X860318Y175386D02*
X906160Y221228D01*
G01X902493Y216061D02*
X906600Y220168D01*
G01X849802Y159401D02*
Y160961D01*
G01X850862Y158961D02*
Y160521D01*
G01X849802Y160961D02*
X860318Y171477D01*
G01X850862Y160521D02*
X861378Y171037D01*
G01X860318Y171477D02*
Y175386D01*
G01X861378Y171037D02*
Y174946D01*
G01X860318Y175386D02*
X906160Y221228D01*
G01X861378Y174946D02*
X891341Y204909D01*
G01X860318Y175386D02*
X906160Y221228D01*
G01X892685Y206253D02*
X893398Y206966D01*
G01X860318Y175386D02*
X906160Y221228D01*
G01X894743Y208311D02*
X895456Y209024D01*
G01X860318Y175386D02*
X906160Y221228D01*
G01X896800Y210368D02*
X898382Y211950D01*
G01X860318Y175386D02*
X906160Y221228D01*
G01X899727Y213295D02*
X901148Y214716D01*
G01X860318Y175386D02*
X906160Y221228D01*
G01X902493Y216061D02*
X906600Y220168D01*
G01X899784Y218952D02*
X898859Y218027D01*
G01X897514Y216682D02*
X896801Y215969D01*
G01X895457Y214625D02*
X894584Y213752D01*
G01X893239Y212407D02*
X892343Y211511D01*
G01X890999Y210167D02*
X890292Y209460D01*
G01X888948Y208116D02*
X888241Y207409D01*
G01X886897Y206065D02*
X886171Y205339D01*
G01X884826Y203994D02*
X884113Y203281D01*
G01X882769Y201937D02*
X881689Y200857D01*
G01X880345Y199513D02*
X879014Y198182D01*
G01X877670Y196838D02*
X876614Y195782D01*
G01X875269Y194437D02*
X874442Y193610D01*
G01X873097Y192265D02*
X872156Y191324D01*
G01X870812Y189980D02*
X869756Y188924D01*
G01X868411Y187579D02*
X867538Y186706D01*
G01X866193Y185361D02*
X854864Y174032D01*
G01X904572Y225240D02*
X853804Y174472D01*
G01X854864Y174032D02*
Y170236D01*
G01X853804Y174472D02*
Y170676D01*
G01X899784Y218952D02*
X898859Y218027D01*
G01X897514Y216682D02*
X896801Y215969D01*
G01X895457Y214625D02*
X894584Y213752D01*
G01X893239Y212407D02*
X892343Y211511D01*
G01X890999Y210167D02*
X890292Y209460D01*
G01X888948Y208116D02*
X888241Y207409D01*
G01X886897Y206065D02*
X886171Y205339D01*
G01X884826Y203994D02*
X884113Y203281D01*
G01X882769Y201937D02*
X881689Y200857D01*
G01X880345Y199513D02*
X879014Y198182D01*
G01X877670Y196838D02*
X876614Y195782D01*
G01X875269Y194437D02*
X874442Y193610D01*
G01X873097Y192265D02*
X872156Y191324D01*
G01X870812Y189980D02*
X869756Y188924D01*
G01X868411Y187579D02*
X867538Y186706D01*
G01X866193Y185361D02*
X854864Y174032D01*
G01X904572Y225240D02*
X853804Y174472D01*
G01X854864Y174032D02*
Y170236D01*
G01X853804Y174472D02*
Y170676D01*
G01X850862Y158961D02*
Y160521D01*
G01X849802Y159401D02*
Y160961D01*
G01X850862Y160521D02*
X861378Y171037D01*
G01X849802Y160961D02*
X860318Y171477D01*
G01X861378Y171037D02*
Y174946D01*
G01X860318Y171477D02*
Y175386D01*
G01X861378Y174946D02*
X891341Y204909D01*
G01X892685Y206253D02*
X893398Y206966D01*
G01X894743Y208311D02*
X895456Y209024D01*
G01X896800Y210368D02*
X898382Y211950D01*
G01X899727Y213295D02*
X901148Y214716D01*
G01X902493Y216061D02*
X906600Y220168D01*
G01X860318Y175386D02*
X906160Y221228D01*
G01X850862Y158961D02*
Y160521D01*
G01X849802Y159401D02*
Y160961D01*
G01X850862Y160521D02*
X861378Y171037D01*
G01X849802Y160961D02*
X860318Y171477D01*
G01X861378Y171037D02*
Y174946D01*
G01X860318Y171477D02*
Y175386D01*
G01X861378Y174946D02*
X891341Y204909D01*
G01X892685Y206253D02*
X893398Y206966D01*
G01X894743Y208311D02*
X895456Y209024D01*
G01X896800Y210368D02*
X898382Y211950D01*
G01X899727Y213295D02*
X901148Y214716D01*
G01X902493Y216061D02*
X906600Y220168D01*
G01X860318Y175386D02*
X906160Y221228D01*
G01X894721Y163913D02*
X895633Y164825D01*
G01X896977Y166169D02*
X897684Y166876D01*
G01X899028Y168220D02*
X899735Y168927D01*
G01X901079Y170271D02*
X901786Y170978D01*
G01X903130Y172322D02*
X903837Y173029D01*
G01X905181Y174373D02*
X905888Y175080D01*
G01X907232Y176424D02*
X907939Y177131D01*
G01X909284Y178476D02*
X910477Y179669D01*
G01X894721Y163913D02*
X895633Y164825D01*
G01X896977Y166169D02*
X897684Y166876D01*
G01X899028Y168220D02*
X899735Y168927D01*
G01X901079Y170271D02*
X901786Y170978D01*
G01X903130Y172322D02*
X903837Y173029D01*
G01X905181Y174373D02*
X905888Y175080D01*
G01X907232Y176424D02*
X907939Y177131D01*
G01X909284Y178476D02*
X910477Y179669D01*
G01X894721Y163913D02*
X895633Y164825D01*
G01X896977Y166169D02*
X897684Y166876D01*
G01X899028Y168220D02*
X899735Y168927D01*
G01X901079Y170271D02*
X901786Y170978D01*
G01X903130Y172322D02*
X903837Y173029D01*
G01X905181Y174373D02*
X905888Y175080D01*
G01X907232Y176424D02*
X907939Y177131D01*
G01X909284Y178476D02*
X910477Y179669D01*
G01X894721Y163913D02*
X895633Y164825D01*
G01X896977Y166169D02*
X897684Y166876D01*
G01X899028Y168220D02*
X899735Y168927D01*
G01X901079Y170271D02*
X901786Y170978D01*
G01X903130Y172322D02*
X903837Y173029D01*
G01X905181Y174373D02*
X905888Y175080D01*
G01X907232Y176424D02*
X907939Y177131D01*
G01X909284Y178476D02*
X910477Y179669D01*
G01X879677Y244591D02*
X880313D01*
G01X881021Y245935D02*
X881728Y246642D01*
G01D02*
X882365D01*
G01X883073Y247987D02*
X883786Y248700D01*
G01D02*
X884423D01*
G01X885131Y250045D02*
X886141Y251055D01*
G01D02*
X886778D01*
G01X887486Y252400D02*
X888415Y253329D01*
G01D02*
X889051D01*
G01X889759Y254673D02*
X890466Y255380D01*
G01X890026Y256440D02*
X908400D01*
G01X890466Y255380D02*
X892572D01*
G01X890026Y256440D02*
X908400D01*
G01X894472Y255380D02*
X895681D01*
G01X890026Y256440D02*
X908400D01*
G01X897581Y255380D02*
X898908D01*
G01X890026Y256440D02*
X908400D01*
G01X900808Y255380D02*
X901808D01*
G01X890026Y256440D02*
X908400D01*
G01X903708Y255380D02*
X905500D01*
G01X890026Y256440D02*
X908400D01*
G01X907400Y255380D02*
X908400D01*
G01X879677Y244591D02*
X880313D01*
G01X881021Y245935D02*
X881728Y246642D01*
G01D02*
X882365D01*
G01X883073Y247987D02*
X883786Y248700D01*
G01D02*
X884423D01*
G01X885131Y250045D02*
X886141Y251055D01*
G01D02*
X886778D01*
G01X887486Y252400D02*
X888415Y253329D01*
G01D02*
X889051D01*
G01X889759Y254673D02*
X890466Y255380D01*
G01X890026Y256440D02*
X908400D01*
G01X890466Y255380D02*
X892572D01*
G01X890026Y256440D02*
X908400D01*
G01X894472Y255380D02*
X895681D01*
G01X890026Y256440D02*
X908400D01*
G01X897581Y255380D02*
X898908D01*
G01X890026Y256440D02*
X908400D01*
G01X900808Y255380D02*
X901808D01*
G01X890026Y256440D02*
X908400D01*
G01X903708Y255380D02*
X905500D01*
G01X890026Y256440D02*
X908400D01*
G01X907400Y255380D02*
X908400D01*
G01X879677Y244591D02*
X880313D01*
G01X881021Y245935D02*
X881728Y246642D01*
G01D02*
X882365D01*
G01X883073Y247987D02*
X883786Y248700D01*
G01D02*
X884423D01*
G01X885131Y250045D02*
X886141Y251055D01*
G01D02*
X886778D01*
G01X887486Y252400D02*
X888415Y253329D01*
G01D02*
X889051D01*
G01X889759Y254673D02*
X890466Y255380D01*
G01D02*
X892572D01*
G01X894472D02*
X895681D01*
G01X897581D02*
X898908D01*
G01X900808D02*
X901808D01*
G01X903708D02*
X905500D01*
G01X907400D02*
X908400D01*
G01X890026Y256440D02*
X908400D01*
G01X879677Y244591D02*
X880313D01*
G01X881021Y245935D02*
X881728Y246642D01*
G01D02*
X882365D01*
G01X883073Y247987D02*
X883786Y248700D01*
G01D02*
X884423D01*
G01X885131Y250045D02*
X886141Y251055D01*
G01D02*
X886778D01*
G01X887486Y252400D02*
X888415Y253329D01*
G01D02*
X889051D01*
G01X889759Y254673D02*
X890466Y255380D01*
G01D02*
X892572D01*
G01X894472D02*
X895681D01*
G01X897581D02*
X898908D01*
G01X900808D02*
X901808D01*
G01X903708D02*
X905500D01*
G01X907400D02*
X908400D01*
G01X890026Y256440D02*
X908400D01*
G01X882301Y241773D02*
X882937D01*
G01X883645Y243117D02*
X884587Y244059D01*
G01D02*
X885223D01*
G01X885931Y245403D02*
X887124Y246596D01*
G01D02*
X887761D01*
G01X888469Y247941D02*
X889957Y249429D01*
G01D02*
X890593D01*
G01X891301Y250773D02*
X892008Y251480D01*
G01X891568Y252540D02*
X910622D01*
G01X892008Y251480D02*
X894721D01*
G01X891568Y252540D02*
X910622D01*
G01X896621Y251480D02*
X897785D01*
G01X891568Y252540D02*
X910622D01*
G01X899685Y251480D02*
X900848D01*
G01X891568Y252540D02*
X910622D01*
G01X902748Y251480D02*
X905009D01*
G01X891568Y252540D02*
X910622D01*
G01X906909Y251480D02*
X910622D01*
G01X882301Y241773D02*
X882937D01*
G01X883645Y243117D02*
X884587Y244059D01*
G01D02*
X885223D01*
G01X885931Y245403D02*
X887124Y246596D01*
G01D02*
X887761D01*
G01X888469Y247941D02*
X889957Y249429D01*
G01D02*
X890593D01*
G01X891301Y250773D02*
X892008Y251480D01*
G01X891568Y252540D02*
X910622D01*
G01X892008Y251480D02*
X894721D01*
G01X891568Y252540D02*
X910622D01*
G01X896621Y251480D02*
X897785D01*
G01X891568Y252540D02*
X910622D01*
G01X899685Y251480D02*
X900848D01*
G01X891568Y252540D02*
X910622D01*
G01X902748Y251480D02*
X905009D01*
G01X891568Y252540D02*
X910622D01*
G01X906909Y251480D02*
X910622D01*
G01X907500Y225240D02*
X904572D01*
G01X907500Y224180D02*
X905012D01*
G01D02*
X903180Y222348D01*
G01X901835Y221003D02*
X901128Y220296D01*
G01X907500Y225240D02*
X904572D01*
G01X907500Y224180D02*
X905012D01*
G01D02*
X903180Y222348D01*
G01X901835Y221003D02*
X901128Y220296D01*
G01X906160Y221228D02*
X907318D01*
G01X906600Y220168D02*
X907318D01*
G01X906160Y221228D02*
X907318D01*
G01X906600Y220168D02*
X907318D01*
G01X882301Y241773D02*
X882937D01*
G01X883645Y243117D02*
X884587Y244059D01*
G01D02*
X885223D01*
G01X885931Y245403D02*
X887124Y246596D01*
G01D02*
X887761D01*
G01X888469Y247941D02*
X889957Y249429D01*
G01D02*
X890593D01*
G01X891301Y250773D02*
X892008Y251480D01*
G01D02*
X894721D01*
G01X896621D02*
X897785D01*
G01X899685D02*
X900848D01*
G01X902748D02*
X905009D01*
G01X906909D02*
X910622D01*
G01X891568Y252540D02*
X910622D01*
G01X882301Y241773D02*
X882937D01*
G01X883645Y243117D02*
X884587Y244059D01*
G01D02*
X885223D01*
G01X885931Y245403D02*
X887124Y246596D01*
G01D02*
X887761D01*
G01X888469Y247941D02*
X889957Y249429D01*
G01D02*
X890593D01*
G01X891301Y250773D02*
X892008Y251480D01*
G01D02*
X894721D01*
G01X896621D02*
X897785D01*
G01X899685D02*
X900848D01*
G01X902748D02*
X905009D01*
G01X906909D02*
X910622D01*
G01X891568Y252540D02*
X910622D01*
G01X907500Y224180D02*
X905012D01*
G01X907500Y225240D02*
X904572D01*
G01X905012Y224180D02*
X903180Y222348D01*
G01X901835Y221003D02*
X901128Y220296D01*
G01X907500Y224180D02*
X905012D01*
G01X907500Y225240D02*
X904572D01*
G01X905012Y224180D02*
X903180Y222348D01*
G01X901835Y221003D02*
X901128Y220296D01*
G01X906600Y220168D02*
X907318D01*
G01X906160Y221228D02*
X907318D01*
G01X906600Y220168D02*
X907318D01*
G01X906160Y221228D02*
X907318D01*
G01X907713Y347779D02*
X895991D01*
G01X907713Y348839D02*
X896431D01*
G01X895991Y347779D02*
X856840Y386930D01*
G01X896431Y348839D02*
X857900Y387370D01*
G01X856840Y386930D02*
Y390837D01*
G01X857900Y387370D02*
Y391277D01*
G01X907713Y347779D02*
X895991D01*
G01X907713Y348839D02*
X896431D01*
G01X895991Y347779D02*
X856840Y386930D01*
G01X896431Y348839D02*
X857900Y387370D01*
G01X856840Y386930D02*
Y390837D01*
G01X857900Y387370D02*
Y391277D01*
G01X907713Y348839D02*
X896431D01*
G01X907713Y347779D02*
X895991D01*
G01X896431Y348839D02*
X857900Y387370D01*
G01X895991Y347779D02*
X856840Y386930D01*
G01X857900Y387370D02*
Y391277D01*
G01X856840Y386930D02*
Y390837D01*
G01X907713Y348839D02*
X896431D01*
G01X907713Y347779D02*
X895991D01*
G01X896431Y348839D02*
X857900Y387370D01*
G01X895991Y347779D02*
X856840Y386930D01*
G01X857900Y387370D02*
Y391277D01*
G01X856840Y386930D02*
Y390837D01*
G01X899326Y352736D02*
X896964D01*
G01X899326Y351676D02*
X896524D01*
G01X896964Y352736D02*
X861360Y388340D01*
G01X896524Y351676D02*
X860300Y387900D01*
G01X861360Y388340D02*
Y393231D01*
G01X860300Y387900D02*
Y392791D01*
G01X903680Y378415D02*
X898585D01*
G01X903680Y379475D02*
X899025D01*
G01X898585Y378415D02*
X891340Y385660D01*
G01X899025Y379475D02*
X892400Y386100D01*
G01X891340Y385660D02*
Y398431D01*
G01X892400Y386100D02*
Y398871D01*
G01X902205Y383720D02*
X901585Y383732D01*
G01D02*
X899468D01*
G01X902185Y382660D02*
X901574Y382672D01*
G01X902205Y383720D02*
X901585Y383732D01*
G01D02*
X899468D01*
G01X901574Y382672D02*
X899028D01*
G01X899468Y383732D02*
X896400Y386800D01*
G01X899028Y382672D02*
X895340Y386360D01*
G01X896400Y386800D02*
Y400271D01*
G01X895340Y386360D02*
Y399831D01*
G01X899326Y351676D02*
X896524D01*
G01X899326Y352736D02*
X896964D01*
G01X896524Y351676D02*
X860300Y387900D01*
G01X896964Y352736D02*
X861360Y388340D01*
G01X860300Y387900D02*
Y392791D01*
G01X861360Y388340D02*
Y393231D01*
G01X903680Y379475D02*
X899025D01*
G01X903680Y378415D02*
X898585D01*
G01X899025Y379475D02*
X892400Y386100D01*
G01X898585Y378415D02*
X891340Y385660D01*
G01X892400Y386100D02*
Y398871D01*
G01X891340Y385660D02*
Y398431D01*
G01X902185Y382660D02*
X901574Y382672D01*
G01D02*
X899028D01*
G01X902205Y383720D02*
X901585Y383732D01*
G01X902185Y382660D02*
X901574Y382672D01*
G01D02*
X899028D01*
G01X901585Y383732D02*
X899468D01*
G01X899028Y382672D02*
X895340Y386360D01*
G01X899468Y383732D02*
X896400Y386800D01*
G01X895340Y386360D02*
Y399831D01*
G01X896400Y386800D02*
Y400271D01*
G01X899326Y352736D02*
X896964D01*
G01X899326Y351676D02*
X896524D01*
G01X896964Y352736D02*
X861360Y388340D01*
G01X896524Y351676D02*
X860300Y387900D01*
G01X861360Y388340D02*
Y393231D01*
G01X860300Y387900D02*
Y392791D01*
G01X903680Y378415D02*
X898585D01*
G01X903680Y379475D02*
X899025D01*
G01X898585Y378415D02*
X891340Y385660D01*
G01X899025Y379475D02*
X892400Y386100D01*
G01X891340Y385660D02*
Y398431D01*
G01X892400Y386100D02*
Y398871D01*
G01X902205Y383720D02*
X901585Y383732D01*
G01D02*
X899468D01*
G01X902185Y382660D02*
X901574Y382672D01*
G01X902205Y383720D02*
X901585Y383732D01*
G01D02*
X899468D01*
G01X901574Y382672D02*
X899028D01*
G01X899468Y383732D02*
X896400Y386800D01*
G01X899028Y382672D02*
X895340Y386360D01*
G01X896400Y386800D02*
Y400271D01*
G01X895340Y386360D02*
Y399831D01*
G01X899326Y351676D02*
X896524D01*
G01X899326Y352736D02*
X896964D01*
G01X896524Y351676D02*
X860300Y387900D01*
G01X896964Y352736D02*
X861360Y388340D01*
G01X860300Y387900D02*
Y392791D01*
G01X861360Y388340D02*
Y393231D01*
G01X903680Y379475D02*
X899025D01*
G01X903680Y378415D02*
X898585D01*
G01X899025Y379475D02*
X892400Y386100D01*
G01X898585Y378415D02*
X891340Y385660D01*
G01X892400Y386100D02*
Y398871D01*
G01X891340Y385660D02*
Y398431D01*
G01X902185Y382660D02*
X901574Y382672D01*
G01D02*
X899028D01*
G01X902205Y383720D02*
X901585Y383732D01*
G01X902185Y382660D02*
X901574Y382672D01*
G01D02*
X899028D01*
G01X901585Y383732D02*
X899468D01*
G01X899028Y382672D02*
X895340Y386360D01*
G01X899468Y383732D02*
X896400Y386800D01*
G01X895340Y386360D02*
Y399831D01*
G01X896400Y386800D02*
Y400271D01*
G01X849415Y454207D02*
Y456315D01*
G01Y454207D02*
Y456315D01*
G01Y454207D02*
Y456315D01*
G01Y454207D02*
Y456315D01*
G01X917500Y422632D02*
X866222Y473910D01*
G01X918560Y423072D02*
X867280Y474352D01*
G01X911878Y433891D02*
X909918Y435851D01*
G01D02*
Y438911D01*
G01X910978Y439354D02*
X909014Y441318D01*
G01X909918Y438911D02*
X908571Y440258D01*
G01X909014Y441318D02*
X905954D01*
G01X908571Y440258D02*
X905511D01*
G01X905954Y441318D02*
X904611Y442661D01*
G01X905511Y440258D02*
X903551Y442218D01*
G01X904611Y442661D02*
Y445721D01*
G01X903551Y442218D02*
Y445278D01*
G01X904611Y445721D02*
X902647Y447685D01*
G01X903551Y445278D02*
X902204Y446625D01*
G01X902647Y447685D02*
X899587D01*
G01X902204Y446625D02*
X899144D01*
G01X899587Y447685D02*
X898244Y449028D01*
G01X899144Y446625D02*
X897184Y448585D01*
G01X898244Y449028D02*
Y452088D01*
G01X897184Y448585D02*
Y451645D01*
G01X898244Y452088D02*
X896280Y454052D01*
G01X897184Y451645D02*
X895837Y452992D01*
G01X896280Y454052D02*
X893220D01*
G01X895837Y452992D02*
X892777D01*
G01X893220Y454052D02*
X891877Y455395D01*
G01X892777Y452992D02*
X890817Y454952D01*
G01X891877Y455395D02*
Y458455D01*
G01X890817Y454952D02*
Y458012D01*
G01X891877Y458455D02*
X889913Y460419D01*
G01X890817Y458012D02*
X889470Y459359D01*
G01X889913Y460419D02*
X886853D01*
G01X889470Y459359D02*
X886410D01*
G01X886853Y460419D02*
X885510Y461762D01*
G01X886410Y459359D02*
X884450Y461319D01*
G01X885510Y461762D02*
Y464822D01*
G01X884450Y461319D02*
Y464379D01*
G01X885510Y464822D02*
X883546Y466786D01*
G01X884450Y464379D02*
X883103Y465726D01*
G01X918560Y423072D02*
X867280Y474352D01*
G01X917500Y422632D02*
X866222Y473910D01*
G01X911878Y433891D02*
X909918Y435851D01*
G01D02*
Y438911D01*
G01D02*
X908571Y440258D01*
G01X910978Y439354D02*
X909014Y441318D01*
G01X908571Y440258D02*
X905511D01*
G01X909014Y441318D02*
X905954D01*
G01X905511Y440258D02*
X903551Y442218D01*
G01X905954Y441318D02*
X904611Y442661D01*
G01X903551Y442218D02*
Y445278D01*
G01X904611Y442661D02*
Y445721D01*
G01X903551Y445278D02*
X902204Y446625D01*
G01X904611Y445721D02*
X902647Y447685D01*
G01X902204Y446625D02*
X899144D01*
G01X902647Y447685D02*
X899587D01*
G01X899144Y446625D02*
X897184Y448585D01*
G01X899587Y447685D02*
X898244Y449028D01*
G01X897184Y448585D02*
Y451645D01*
G01X898244Y449028D02*
Y452088D01*
G01X897184Y451645D02*
X895837Y452992D01*
G01X898244Y452088D02*
X896280Y454052D01*
G01X895837Y452992D02*
X892777D01*
G01X896280Y454052D02*
X893220D01*
G01X892777Y452992D02*
X890817Y454952D01*
G01X893220Y454052D02*
X891877Y455395D01*
G01X890817Y454952D02*
Y458012D01*
G01X891877Y455395D02*
Y458455D01*
G01X890817Y458012D02*
X889470Y459359D01*
G01X891877Y458455D02*
X889913Y460419D01*
G01X889470Y459359D02*
X886410D01*
G01X889913Y460419D02*
X886853D01*
G01X886410Y459359D02*
X884450Y461319D01*
G01X886853Y460419D02*
X885510Y461762D01*
G01X884450Y461319D02*
Y464379D01*
G01X885510Y461762D02*
Y464822D01*
G01X884450Y464379D02*
X883103Y465726D01*
G01X885510Y464822D02*
X883546Y466786D01*
G01X917500Y422632D02*
X866222Y473910D01*
G01X918560Y423072D02*
X867280Y474352D01*
G01X911878Y433891D02*
X909918Y435851D01*
G01D02*
Y438911D01*
G01X910978Y439354D02*
X909014Y441318D01*
G01X909918Y438911D02*
X908571Y440258D01*
G01X909014Y441318D02*
X905954D01*
G01X908571Y440258D02*
X905511D01*
G01X905954Y441318D02*
X904611Y442661D01*
G01X905511Y440258D02*
X903551Y442218D01*
G01X904611Y442661D02*
Y445721D01*
G01X903551Y442218D02*
Y445278D01*
G01X904611Y445721D02*
X902647Y447685D01*
G01X903551Y445278D02*
X902204Y446625D01*
G01X902647Y447685D02*
X899587D01*
G01X902204Y446625D02*
X899144D01*
G01X899587Y447685D02*
X898244Y449028D01*
G01X899144Y446625D02*
X897184Y448585D01*
G01X898244Y449028D02*
Y452088D01*
G01X897184Y448585D02*
Y451645D01*
G01X898244Y452088D02*
X896280Y454052D01*
G01X897184Y451645D02*
X895837Y452992D01*
G01X896280Y454052D02*
X893220D01*
G01X895837Y452992D02*
X892777D01*
G01X893220Y454052D02*
X891877Y455395D01*
G01X892777Y452992D02*
X890817Y454952D01*
G01X891877Y455395D02*
Y458455D01*
G01X890817Y454952D02*
Y458012D01*
G01X891877Y458455D02*
X889913Y460419D01*
G01X890817Y458012D02*
X889470Y459359D01*
G01X889913Y460419D02*
X886853D01*
G01X889470Y459359D02*
X886410D01*
G01X886853Y460419D02*
X885510Y461762D01*
G01X886410Y459359D02*
X884450Y461319D01*
G01X885510Y461762D02*
Y464822D01*
G01X884450Y461319D02*
Y464379D01*
G01X885510Y464822D02*
X883546Y466786D01*
G01X884450Y464379D02*
X883103Y465726D01*
G01X918560Y423072D02*
X867280Y474352D01*
G01X917500Y422632D02*
X866222Y473910D01*
G01X911878Y433891D02*
X909918Y435851D01*
G01D02*
Y438911D01*
G01D02*
X908571Y440258D01*
G01X910978Y439354D02*
X909014Y441318D01*
G01X908571Y440258D02*
X905511D01*
G01X909014Y441318D02*
X905954D01*
G01X905511Y440258D02*
X903551Y442218D01*
G01X905954Y441318D02*
X904611Y442661D01*
G01X903551Y442218D02*
Y445278D01*
G01X904611Y442661D02*
Y445721D01*
G01X903551Y445278D02*
X902204Y446625D01*
G01X904611Y445721D02*
X902647Y447685D01*
G01X902204Y446625D02*
X899144D01*
G01X902647Y447685D02*
X899587D01*
G01X899144Y446625D02*
X897184Y448585D01*
G01X899587Y447685D02*
X898244Y449028D01*
G01X897184Y448585D02*
Y451645D01*
G01X898244Y449028D02*
Y452088D01*
G01X897184Y451645D02*
X895837Y452992D01*
G01X898244Y452088D02*
X896280Y454052D01*
G01X895837Y452992D02*
X892777D01*
G01X896280Y454052D02*
X893220D01*
G01X892777Y452992D02*
X890817Y454952D01*
G01X893220Y454052D02*
X891877Y455395D01*
G01X890817Y454952D02*
Y458012D01*
G01X891877Y455395D02*
Y458455D01*
G01X890817Y458012D02*
X889470Y459359D01*
G01X891877Y458455D02*
X889913Y460419D01*
G01X889470Y459359D02*
X886410D01*
G01X889913Y460419D02*
X886853D01*
G01X886410Y459359D02*
X884450Y461319D01*
G01X886853Y460419D02*
X885510Y461762D01*
G01X884450Y461319D02*
Y464379D01*
G01X885510Y461762D02*
Y464822D01*
G01X884450Y464379D02*
X883103Y465726D01*
G01X885510Y464822D02*
X883546Y466786D01*
G01X866220Y473910D02*
Y495509D01*
G01X867280Y474352D02*
Y495952D01*
G01X866220Y495509D02*
X862030Y499699D01*
G01X867280Y495952D02*
X863090Y500142D01*
G01X862030Y499699D02*
Y587409D01*
G01X863090Y500142D02*
Y587849D01*
G01X883546Y466786D02*
X880486D01*
G01X883103Y465726D02*
X880046D01*
G01X880486Y466786D02*
X879143Y468129D01*
G01X880046Y465726D02*
X878083Y467689D01*
G01X879143Y468129D02*
Y470554D01*
G01X878083Y467689D02*
Y470114D01*
G01X879143Y470554D02*
X876544Y473153D01*
G01X878083Y470114D02*
X876104Y472093D01*
G01X876544Y473153D02*
X875116D01*
G01X876104Y472093D02*
X874676D01*
G01X876544Y473153D02*
X875116D01*
G01D02*
X872776Y475493D01*
G01X874676Y472093D02*
X871716Y475053D01*
G01X872776Y475493D02*
Y477553D01*
G01X871716Y475053D02*
Y477113D01*
G01X872776Y477553D02*
X871080Y479249D01*
G01X871716Y477113D02*
X870020Y478809D01*
G01X871080Y479249D02*
Y497652D01*
G01X870020Y478809D02*
Y497209D01*
G01X871080Y497652D02*
X868254Y500478D01*
G01X870020Y497209D02*
X867194Y500035D01*
G01X868254Y500478D02*
Y587986D01*
G01X867194Y500035D02*
Y522200D01*
G01X868254Y500478D02*
Y587986D01*
G01X867194Y524440D02*
Y525776D01*
G01X868254Y500478D02*
Y587986D01*
G01Y500478D02*
Y587986D01*
G01Y500478D02*
Y587986D01*
G01Y500478D02*
Y587986D01*
G01Y500478D02*
Y587986D01*
G01Y500478D02*
Y587986D01*
G01Y500478D02*
Y587986D01*
G01Y500478D02*
Y587986D01*
G01Y500478D02*
Y587986D01*
G01Y500478D02*
Y587986D01*
G01X867280Y474352D02*
Y495952D01*
G01X866220Y473910D02*
Y495509D01*
G01X867280Y495952D02*
X863090Y500142D01*
G01X866220Y495509D02*
X862030Y499699D01*
G01X863090Y500142D02*
Y587849D01*
G01X862030Y499699D02*
Y587409D01*
G01X883103Y465726D02*
X880046D01*
G01X883546Y466786D02*
X880486D01*
G01X880046Y465726D02*
X878083Y467689D01*
G01X880486Y466786D02*
X879143Y468129D01*
G01X878083Y467689D02*
Y470114D01*
G01X879143Y468129D02*
Y470554D01*
G01X878083Y470114D02*
X876104Y472093D01*
G01X879143Y470554D02*
X876544Y473153D01*
G01X876104Y472093D02*
X874676D01*
G01D02*
X871716Y475053D01*
G01X876544Y473153D02*
X875116D01*
G01X874676Y472093D02*
X871716Y475053D01*
G01X875116Y473153D02*
X872776Y475493D01*
G01X871716Y475053D02*
Y477113D01*
G01X872776Y475493D02*
Y477553D01*
G01X871716Y477113D02*
X870020Y478809D01*
G01X872776Y477553D02*
X871080Y479249D01*
G01X870020Y478809D02*
Y497209D01*
G01X871080Y479249D02*
Y497652D01*
G01X870020Y497209D02*
X867194Y500035D01*
G01X871080Y497652D02*
X868254Y500478D01*
G01X867194Y500035D02*
Y522200D01*
G01Y524440D02*
Y525776D01*
G01X868254Y500478D02*
Y587986D01*
G01X913109Y473520D02*
X900863Y485766D01*
G01X913549Y474580D02*
X901762Y486367D01*
G01X900863Y485766D02*
X898841Y490649D01*
G01X901762Y486367D02*
X899901Y490860D01*
G01X898841Y490649D02*
Y577044D01*
G01X899901Y490860D02*
Y587849D01*
G01X915349Y478380D02*
X905001Y488728D01*
G01X914909Y477320D02*
X903941Y488288D01*
G01X905001Y488728D02*
Y588035D01*
G01X903941Y488288D02*
Y507212D01*
G01X905001Y488728D02*
Y588035D01*
G01X903941Y509034D02*
Y519493D01*
G01X905001Y488728D02*
Y588035D01*
G01X903941Y521481D02*
Y522509D01*
G01X905001Y488728D02*
Y588035D01*
G01X903941Y524749D02*
Y525749D01*
G01X905001Y488728D02*
Y588035D01*
G01Y488728D02*
Y588035D01*
G01Y488728D02*
Y588035D01*
G01Y488728D02*
Y588035D01*
G01Y488728D02*
Y588035D01*
G01Y488728D02*
Y588035D01*
G01Y488728D02*
Y588035D01*
G01Y488728D02*
Y588035D01*
G01Y488728D02*
Y588035D01*
G01Y488728D02*
Y588035D01*
G01X913549Y474580D02*
X901762Y486367D01*
G01X913109Y473520D02*
X900863Y485766D01*
G01X901762Y486367D02*
X899901Y490860D01*
G01X900863Y485766D02*
X898841Y490649D01*
G01X899901Y490860D02*
Y587849D01*
G01X898841Y490649D02*
Y577044D01*
G01X899901Y490860D02*
Y587849D01*
G01Y490860D02*
Y587849D01*
G01Y490860D02*
Y587849D01*
G01X914909Y477320D02*
X903941Y488288D01*
G01X915349Y478380D02*
X905001Y488728D01*
G01X903941Y488288D02*
Y507212D01*
G01Y509034D02*
Y519493D01*
G01Y521481D02*
Y522509D01*
G01Y524749D02*
Y525749D01*
G01X905001Y488728D02*
Y588035D01*
G01X866220Y473910D02*
Y495509D01*
G01X867280Y474352D02*
Y495952D01*
G01X866220Y495509D02*
X862030Y499699D01*
G01X867280Y495952D02*
X863090Y500142D01*
G01X862030Y499699D02*
Y587409D01*
G01X863090Y500142D02*
Y587849D01*
G01X913109Y473520D02*
X900863Y485766D01*
G01X913549Y474580D02*
X901762Y486367D01*
G01X900863Y485766D02*
X898841Y490649D01*
G01X901762Y486367D02*
X899901Y490860D01*
G01X898841Y490649D02*
Y577044D01*
G01X899901Y490860D02*
Y587849D01*
G01X883546Y466786D02*
X880486D01*
G01X883103Y465726D02*
X880046D01*
G01X880486Y466786D02*
X879143Y468129D01*
G01X880046Y465726D02*
X878083Y467689D01*
G01X879143Y468129D02*
Y470554D01*
G01X878083Y467689D02*
Y470114D01*
G01X879143Y470554D02*
X876544Y473153D01*
G01X878083Y470114D02*
X876104Y472093D01*
G01X876544Y473153D02*
X875116D01*
G01X876104Y472093D02*
X874676D01*
G01X876544Y473153D02*
X875116D01*
G01D02*
X872776Y475493D01*
G01X874676Y472093D02*
X871716Y475053D01*
G01X872776Y475493D02*
Y477553D01*
G01X871716Y475053D02*
Y477113D01*
G01X872776Y477553D02*
X871080Y479249D01*
G01X871716Y477113D02*
X870020Y478809D01*
G01X871080Y479249D02*
Y497652D01*
G01X870020Y478809D02*
Y497209D01*
G01X871080Y497652D02*
X868254Y500478D01*
G01X870020Y497209D02*
X867194Y500035D01*
G01X868254Y500478D02*
Y587986D01*
G01X867194Y500035D02*
Y522200D01*
G01X868254Y500478D02*
Y587986D01*
G01X867194Y524440D02*
Y525776D01*
G01X868254Y500478D02*
Y587986D01*
G01Y500478D02*
Y587986D01*
G01Y500478D02*
Y587986D01*
G01Y500478D02*
Y587986D01*
G01Y500478D02*
Y587986D01*
G01Y500478D02*
Y587986D01*
G01Y500478D02*
Y587986D01*
G01Y500478D02*
Y587986D01*
G01Y500478D02*
Y587986D01*
G01Y500478D02*
Y587986D01*
G01X915349Y478380D02*
X905001Y488728D01*
G01X914909Y477320D02*
X903941Y488288D01*
G01X905001Y488728D02*
Y588035D01*
G01X903941Y488288D02*
Y507212D01*
G01X905001Y488728D02*
Y588035D01*
G01X903941Y509034D02*
Y519493D01*
G01X905001Y488728D02*
Y588035D01*
G01X903941Y521481D02*
Y522509D01*
G01X905001Y488728D02*
Y588035D01*
G01X903941Y524749D02*
Y525749D01*
G01X905001Y488728D02*
Y588035D01*
G01Y488728D02*
Y588035D01*
G01Y488728D02*
Y588035D01*
G01Y488728D02*
Y588035D01*
G01Y488728D02*
Y588035D01*
G01Y488728D02*
Y588035D01*
G01Y488728D02*
Y588035D01*
G01Y488728D02*
Y588035D01*
G01Y488728D02*
Y588035D01*
G01Y488728D02*
Y588035D01*
G01X867280Y474352D02*
Y495952D01*
G01X866220Y473910D02*
Y495509D01*
G01X867280Y495952D02*
X863090Y500142D01*
G01X866220Y495509D02*
X862030Y499699D01*
G01X863090Y500142D02*
Y587849D01*
G01X862030Y499699D02*
Y587409D01*
G01X913549Y474580D02*
X901762Y486367D01*
G01X913109Y473520D02*
X900863Y485766D01*
G01X901762Y486367D02*
X899901Y490860D01*
G01X900863Y485766D02*
X898841Y490649D01*
G01X899901Y490860D02*
Y587849D01*
G01X898841Y490649D02*
Y577044D01*
G01X899901Y490860D02*
Y587849D01*
G01Y490860D02*
Y587849D01*
G01Y490860D02*
Y587849D01*
G01X883103Y465726D02*
X880046D01*
G01X883546Y466786D02*
X880486D01*
G01X880046Y465726D02*
X878083Y467689D01*
G01X880486Y466786D02*
X879143Y468129D01*
G01X878083Y467689D02*
Y470114D01*
G01X879143Y468129D02*
Y470554D01*
G01X878083Y470114D02*
X876104Y472093D01*
G01X879143Y470554D02*
X876544Y473153D01*
G01X876104Y472093D02*
X874676D01*
G01D02*
X871716Y475053D01*
G01X876544Y473153D02*
X875116D01*
G01X874676Y472093D02*
X871716Y475053D01*
G01X875116Y473153D02*
X872776Y475493D01*
G01X871716Y475053D02*
Y477113D01*
G01X872776Y475493D02*
Y477553D01*
G01X871716Y477113D02*
X870020Y478809D01*
G01X872776Y477553D02*
X871080Y479249D01*
G01X870020Y478809D02*
Y497209D01*
G01X871080Y479249D02*
Y497652D01*
G01X870020Y497209D02*
X867194Y500035D01*
G01X871080Y497652D02*
X868254Y500478D01*
G01X867194Y500035D02*
Y522200D01*
G01Y524440D02*
Y525776D01*
G01X868254Y500478D02*
Y587986D01*
G01X914909Y477320D02*
X903941Y488288D01*
G01X915349Y478380D02*
X905001Y488728D01*
G01X903941Y488288D02*
Y507212D01*
G01Y509034D02*
Y519493D01*
G01Y521481D02*
Y522509D01*
G01Y524749D02*
Y525749D01*
G01X905001Y488728D02*
Y588035D01*
G01X862030Y587409D02*
X861139Y588300D01*
G01X863090Y587849D02*
X860039Y590900D01*
G01X867194Y528016D02*
Y538181D01*
G01Y540421D02*
Y541421D01*
G01Y543661D02*
Y544661D01*
G01Y546901D02*
Y556844D01*
G01Y559084D02*
Y560084D01*
G01Y562324D02*
Y563324D01*
G01Y565564D02*
Y575812D01*
G01Y578052D02*
Y579052D01*
G01Y581292D02*
Y582292D01*
G01Y584532D02*
Y587375D01*
G01X863090Y587849D02*
X860039Y590900D01*
G01X862030Y587409D02*
X861139Y588300D01*
G01X867194Y528016D02*
Y538181D01*
G01Y540421D02*
Y541421D01*
G01Y543661D02*
Y544661D01*
G01Y546901D02*
Y556844D01*
G01Y559084D02*
Y560084D01*
G01Y562324D02*
Y563324D01*
G01Y565564D02*
Y575812D01*
G01Y578052D02*
Y579052D01*
G01Y581292D02*
Y582292D01*
G01Y584532D02*
Y587375D01*
G01X898841Y579004D02*
Y580004D01*
G01Y581964D02*
Y582964D01*
G01Y584924D02*
Y587409D01*
G01D02*
X897950Y588300D01*
G01X899901Y587849D02*
X896850Y590900D01*
G01X903941Y527989D02*
Y538042D01*
G01Y540282D02*
Y541282D01*
G01Y543522D02*
Y544522D01*
G01Y546762D02*
Y556983D01*
G01Y559223D02*
Y560223D01*
G01Y562463D02*
Y563463D01*
G01Y565703D02*
Y576036D01*
G01Y578276D02*
Y579276D01*
G01Y581516D02*
Y582516D01*
G01Y584756D02*
Y587595D01*
G01X905001Y588035D02*
X901922Y591114D01*
G01X903941Y587595D02*
X903022Y588514D01*
G01X905001Y588035D02*
X901922Y591114D01*
G01X898841Y579004D02*
Y580004D01*
G01Y581964D02*
Y582964D01*
G01Y584924D02*
Y587409D01*
G01X899901Y587849D02*
X896850Y590900D01*
G01X898841Y587409D02*
X897950Y588300D01*
G01X903941Y527989D02*
Y538042D01*
G01Y540282D02*
Y541282D01*
G01Y543522D02*
Y544522D01*
G01Y546762D02*
Y556983D01*
G01Y559223D02*
Y560223D01*
G01Y562463D02*
Y563463D01*
G01Y565703D02*
Y576036D01*
G01Y578276D02*
Y579276D01*
G01Y581516D02*
Y582516D01*
G01Y584756D02*
Y587595D01*
G01D02*
X903022Y588514D01*
G01X905001Y588035D02*
X901922Y591114D01*
G01X862030Y587409D02*
X861139Y588300D01*
G01X863090Y587849D02*
X860039Y590900D01*
G01X898841Y579004D02*
Y580004D01*
G01Y581964D02*
Y582964D01*
G01Y584924D02*
Y587409D01*
G01D02*
X897950Y588300D01*
G01X899901Y587849D02*
X896850Y590900D01*
G01X867194Y528016D02*
Y538181D01*
G01Y540421D02*
Y541421D01*
G01Y543661D02*
Y544661D01*
G01Y546901D02*
Y556844D01*
G01Y559084D02*
Y560084D01*
G01Y562324D02*
Y563324D01*
G01Y565564D02*
Y575812D01*
G01Y578052D02*
Y579052D01*
G01Y581292D02*
Y582292D01*
G01Y584532D02*
Y587375D01*
G01X903941Y527989D02*
Y538042D01*
G01Y540282D02*
Y541282D01*
G01Y543522D02*
Y544522D01*
G01Y546762D02*
Y556983D01*
G01Y559223D02*
Y560223D01*
G01Y562463D02*
Y563463D01*
G01Y565703D02*
Y576036D01*
G01Y578276D02*
Y579276D01*
G01Y581516D02*
Y582516D01*
G01Y584756D02*
Y587595D01*
G01X905001Y588035D02*
X901922Y591114D01*
G01X903941Y587595D02*
X903022Y588514D01*
G01X905001Y588035D02*
X901922Y591114D01*
G01X863090Y587849D02*
X860039Y590900D01*
G01X862030Y587409D02*
X861139Y588300D01*
G01X898841Y579004D02*
Y580004D01*
G01Y581964D02*
Y582964D01*
G01Y584924D02*
Y587409D01*
G01X899901Y587849D02*
X896850Y590900D01*
G01X898841Y587409D02*
X897950Y588300D01*
G01X867194Y528016D02*
Y538181D01*
G01Y540421D02*
Y541421D01*
G01Y543661D02*
Y544661D01*
G01Y546901D02*
Y556844D01*
G01Y559084D02*
Y560084D01*
G01Y562324D02*
Y563324D01*
G01Y565564D02*
Y575812D01*
G01Y578052D02*
Y579052D01*
G01Y581292D02*
Y582292D01*
G01Y584532D02*
Y587375D01*
G01X903941Y527989D02*
Y538042D01*
G01Y540282D02*
Y541282D01*
G01Y543522D02*
Y544522D01*
G01Y546762D02*
Y556983D01*
G01Y559223D02*
Y560223D01*
G01Y562463D02*
Y563463D01*
G01Y565703D02*
Y576036D01*
G01Y578276D02*
Y579276D01*
G01Y581516D02*
Y582516D01*
G01Y584756D02*
Y587595D01*
G01D02*
X903022Y588514D01*
G01X905001Y588035D02*
X901922Y591114D01*
G01X858022Y590000D02*
Y608011D01*
G01X859082Y595890D02*
Y597260D01*
G01X858022Y590000D02*
Y608011D01*
G01X859082Y600940D02*
Y602360D01*
G01X864306Y595500D02*
X863635Y596171D01*
G01X863405Y594900D02*
X862575Y595730D01*
G01X863635Y596171D02*
Y597448D01*
G01Y600938D02*
Y601829D01*
G01X862575Y595730D02*
Y602270D01*
G01X863635Y601829D02*
X864406Y602600D01*
G01X862575Y602270D02*
X863405Y603100D01*
G01X859082Y595890D02*
Y597260D01*
G01Y600940D02*
Y602360D01*
G01X858022Y590000D02*
Y608011D01*
G01X863405Y594900D02*
X862575Y595730D01*
G01X864306Y595500D02*
X863635Y596171D01*
G01X862575Y595730D02*
Y602270D01*
G01X863635Y596171D02*
Y597448D01*
G01X862575Y595730D02*
Y602270D01*
G01X863635Y600938D02*
Y601829D01*
G01X862575Y602270D02*
X863405Y603100D01*
G01X863635Y601829D02*
X864406Y602600D01*
G01X894833Y590000D02*
Y608011D01*
G01X895893Y595890D02*
Y597260D01*
G01X894833Y590000D02*
Y608011D01*
G01X895893Y600940D02*
Y602360D01*
G01X901117Y595500D02*
X900446Y596171D01*
G01X900216Y594900D02*
X899386Y595730D01*
G01X900446Y596171D02*
Y597448D01*
G01Y600938D02*
Y601829D01*
G01X899386Y595730D02*
Y602270D01*
G01X900446Y601829D02*
X901217Y602600D01*
G01X899386Y602270D02*
X900216Y603100D01*
G01X903022Y588514D02*
X901921D01*
G01X895893Y595890D02*
Y597260D01*
G01Y600940D02*
Y602360D01*
G01X894833Y590000D02*
Y608011D01*
G01X900216Y594900D02*
X899386Y595730D01*
G01X901117Y595500D02*
X900446Y596171D01*
G01X899386Y595730D02*
Y602270D01*
G01X900446Y596171D02*
Y597448D01*
G01X899386Y595730D02*
Y602270D01*
G01X900446Y600938D02*
Y601829D01*
G01X899386Y602270D02*
X900216Y603100D01*
G01X900446Y601829D02*
X901217Y602600D01*
G01X903022Y588514D02*
X901921D01*
G01X858022Y590000D02*
Y608011D01*
G01X859082Y595890D02*
Y597260D01*
G01X858022Y590000D02*
Y608011D01*
G01X859082Y600940D02*
Y602360D01*
G01X894833Y590000D02*
Y608011D01*
G01X895893Y595890D02*
Y597260D01*
G01X894833Y590000D02*
Y608011D01*
G01X895893Y600940D02*
Y602360D01*
G01X864306Y595500D02*
X863635Y596171D01*
G01X863405Y594900D02*
X862575Y595730D01*
G01X863635Y596171D02*
Y597448D01*
G01Y600938D02*
Y601829D01*
G01X862575Y595730D02*
Y602270D01*
G01X863635Y601829D02*
X864406Y602600D01*
G01X862575Y602270D02*
X863405Y603100D01*
G01X901117Y595500D02*
X900446Y596171D01*
G01X900216Y594900D02*
X899386Y595730D01*
G01X900446Y596171D02*
Y597448D01*
G01Y600938D02*
Y601829D01*
G01X899386Y595730D02*
Y602270D01*
G01X900446Y601829D02*
X901217Y602600D01*
G01X899386Y602270D02*
X900216Y603100D01*
G01X903022Y588514D02*
X901921D01*
G01X859082Y595890D02*
Y597260D01*
G01Y600940D02*
Y602360D01*
G01X858022Y590000D02*
Y608011D01*
G01X895893Y595890D02*
Y597260D01*
G01Y600940D02*
Y602360D01*
G01X894833Y590000D02*
Y608011D01*
G01X863405Y594900D02*
X862575Y595730D01*
G01X864306Y595500D02*
X863635Y596171D01*
G01X862575Y595730D02*
Y602270D01*
G01X863635Y596171D02*
Y597448D01*
G01X862575Y595730D02*
Y602270D01*
G01X863635Y600938D02*
Y601829D01*
G01X862575Y602270D02*
X863405Y603100D01*
G01X863635Y601829D02*
X864406Y602600D01*
G01X900216Y594900D02*
X899386Y595730D01*
G01X901117Y595500D02*
X900446Y596171D01*
G01X899386Y595730D02*
Y602270D01*
G01X900446Y596171D02*
Y597448D01*
G01X899386Y595730D02*
Y602270D01*
G01X900446Y600938D02*
Y601829D01*
G01X899386Y602270D02*
X900216Y603100D01*
G01X900446Y601829D02*
X901217Y602600D01*
G01X903022Y588514D02*
X901921D01*
G01X935678Y33291D02*
X934967Y32580D01*
G01X936738Y32848D02*
X935410Y31520D01*
G01X934967Y32580D02*
X934451D01*
G01X935410Y31520D02*
X934428D01*
G01X936738Y32848D02*
X935410Y31520D01*
G01X935678Y33291D02*
X934967Y32580D01*
G01X935410Y31520D02*
X934428D01*
G01X934967Y32580D02*
X934451D01*
G01X941924Y33732D02*
X938732Y30540D01*
G01X934451Y-5220D02*
X934967D01*
G01X934428Y-6280D02*
X935410D01*
G01X934967Y-5220D02*
X935678Y-4509D01*
G01X935410Y-6280D02*
X936738Y-4952D01*
G01X935678Y-4509D02*
Y-1220D01*
G01Y3120D02*
Y4080D01*
G01Y8220D02*
Y10753D01*
G01X936738Y-4952D02*
Y11194D01*
G01X935678Y10753D02*
X934731Y11700D01*
G01X936738Y11194D02*
X933632Y14300D01*
G01X938732Y-4651D02*
X939841D01*
G01D02*
X940864Y-3628D01*
G01X938732Y-7260D02*
X941924Y-4068D01*
G01X940864Y-3628D02*
Y-1007D01*
G01Y2907D02*
Y4280D01*
G01Y8106D02*
Y10881D01*
G01X941924Y-4068D02*
Y11322D01*
G01X940864Y10881D02*
X939830Y11915D01*
G01D02*
X938732D01*
G01X941924Y11322D02*
X938732Y14514D01*
G01X934428Y-6280D02*
X935410D01*
G01X934451Y-5220D02*
X934967D01*
G01X935410Y-6280D02*
X936738Y-4952D01*
G01X934967Y-5220D02*
X935678Y-4509D01*
G01X936738Y-4952D02*
Y11194D01*
G01X935678Y-4509D02*
Y-1220D01*
G01X936738Y-4952D02*
Y11194D01*
G01X935678Y3120D02*
Y4080D01*
G01X936738Y-4952D02*
Y11194D01*
G01X935678Y8220D02*
Y10753D01*
G01X936738Y11194D02*
X933632Y14300D01*
G01X935678Y10753D02*
X934731Y11700D01*
G01X938732Y-7260D02*
X941924Y-4068D01*
G01X938732Y-4651D02*
X939841D01*
G01X938732Y-7260D02*
X941924Y-4068D01*
G01X939841Y-4651D02*
X940864Y-3628D01*
G01X941924Y-4068D02*
Y11322D01*
G01X940864Y-3628D02*
Y-1007D01*
G01X941924Y-4068D02*
Y11322D01*
G01X940864Y2907D02*
Y4280D01*
G01X941924Y-4068D02*
Y11322D01*
G01X940864Y8106D02*
Y10881D01*
G01X941924Y11322D02*
X938732Y14514D01*
G01X940864Y10881D02*
X939830Y11915D01*
G01X941924Y11322D02*
X938732Y14514D01*
G01X939830Y11915D02*
X938732D01*
G01X935678Y33291D02*
X934967Y32580D01*
G01X936738Y32848D02*
X935410Y31520D01*
G01X934967Y32580D02*
X934451D01*
G01X935410Y31520D02*
X934428D01*
G01X941924Y33732D02*
X938732Y30540D01*
G01X941924Y33732D02*
X938732Y30540D01*
G01X941924Y33732D02*
X938732Y30540D01*
G01X941924Y33732D02*
X938732Y30540D01*
G01X936738Y32848D02*
X935410Y31520D01*
G01X935678Y33291D02*
X934967Y32580D01*
G01X935410Y31520D02*
X934428D01*
G01X934967Y32580D02*
X934451D01*
G01X941924Y33732D02*
X938732Y30540D01*
G01X935589Y105934D02*
Y62190D01*
G01X936649Y107497D02*
Y61747D01*
G01X935589Y62190D02*
X933589Y60190D01*
G01X936649Y61747D02*
X934649Y59747D01*
G01X933589Y60190D02*
Y57320D01*
G01X934649Y59747D02*
Y56451D01*
G01X934731Y49500D02*
X935678Y48553D01*
G01X933632Y52100D02*
X936738Y48994D01*
G01X935678Y48553D02*
Y46020D01*
G01Y41880D02*
Y40920D01*
G01Y36580D02*
Y33291D01*
G01X936738Y48994D02*
Y32848D01*
G01X936649Y107497D02*
Y61747D01*
G01X935589Y105934D02*
Y62190D01*
G01X936649Y61747D02*
X934649Y59747D01*
G01X935589Y62190D02*
X933589Y60190D01*
G01X934649Y59747D02*
Y56451D01*
G01X933589Y60190D02*
Y57320D01*
G01X933632Y52100D02*
X936738Y48994D01*
G01X934731Y49500D02*
X935678Y48553D01*
G01X936738Y48994D02*
Y32848D01*
G01X935678Y48553D02*
Y46020D01*
G01X936738Y48994D02*
Y32848D01*
G01X935678Y41880D02*
Y40920D01*
G01X936738Y48994D02*
Y32848D01*
G01X935678Y36580D02*
Y33291D01*
G01X940689Y105698D02*
Y60092D01*
G01X941749Y107247D02*
Y59649D01*
G01X940689Y60092D02*
X938789Y58192D01*
G01X941749Y59649D02*
X939849Y57749D01*
G01X938789Y58192D02*
Y57520D01*
G01X939849Y57749D02*
Y56620D01*
G01X938732Y49715D02*
X939830D01*
G01D02*
X940864Y48681D01*
G01X938732Y52314D02*
X941924Y49122D01*
G01X940864Y48681D02*
Y45906D01*
G01Y42080D02*
Y40707D01*
G01Y36793D02*
Y34172D01*
G01X941924Y49122D02*
Y33732D01*
G01X940864Y34172D02*
X939841Y33149D01*
G01D02*
X938732D01*
G01X935589Y105934D02*
Y62190D01*
G01X936649Y107497D02*
Y61747D01*
G01X935589Y62190D02*
X933589Y60190D01*
G01X936649Y61747D02*
X934649Y59747D01*
G01X933589Y60190D02*
Y57320D01*
G01X934649Y59747D02*
Y56451D01*
G01X934731Y49500D02*
X935678Y48553D01*
G01X933632Y52100D02*
X936738Y48994D01*
G01X935678Y48553D02*
Y46020D01*
G01Y41880D02*
Y40920D01*
G01Y36580D02*
Y33291D01*
G01X936738Y48994D02*
Y32848D01*
G01X938732Y52314D02*
X941924Y49122D01*
G01X938732Y49715D02*
X939830D01*
G01X938732Y52314D02*
X941924Y49122D01*
G01X939830Y49715D02*
X940864Y48681D01*
G01X941924Y49122D02*
Y33732D01*
G01X940864Y48681D02*
Y45906D01*
G01X941924Y49122D02*
Y33732D01*
G01X940864Y42080D02*
Y40707D01*
G01X941924Y49122D02*
Y33732D01*
G01X940864Y36793D02*
Y34172D01*
G01D02*
X939841Y33149D01*
G01D02*
X938732D01*
G01X941749Y107247D02*
Y59649D01*
G01X940689Y105698D02*
Y60092D01*
G01X941749Y59649D02*
X939849Y57749D01*
G01X940689Y60092D02*
X938789Y58192D01*
G01X939849Y57749D02*
Y56620D01*
G01X938789Y58192D02*
Y57520D01*
G01X938732Y52314D02*
X941924Y49122D01*
G01X938732Y49715D02*
X939830D01*
G01X938732Y52314D02*
X941924Y49122D01*
G01X939830Y49715D02*
X940864Y48681D01*
G01X941924Y49122D02*
Y33732D01*
G01X940864Y48681D02*
Y45906D01*
G01X941924Y49122D02*
Y33732D01*
G01X940864Y42080D02*
Y40707D01*
G01X941924Y49122D02*
Y33732D01*
G01X940864Y36793D02*
Y34172D01*
G01D02*
X939841Y33149D01*
G01D02*
X938732D01*
G01X941749Y107247D02*
Y59649D01*
G01X940689Y105698D02*
Y60092D01*
G01X941749Y59649D02*
X939849Y57749D01*
G01X940689Y60092D02*
X938789Y58192D01*
G01X939849Y57749D02*
Y56620D01*
G01X938789Y58192D02*
Y57520D01*
G01X936649Y107497D02*
Y61747D01*
G01X935589Y105934D02*
Y62190D01*
G01X936649Y61747D02*
X934649Y59747D01*
G01X935589Y62190D02*
X933589Y60190D01*
G01X934649Y59747D02*
Y56451D01*
G01X933589Y60190D02*
Y57320D01*
G01X933632Y52100D02*
X936738Y48994D01*
G01X934731Y49500D02*
X935678Y48553D01*
G01X936738Y48994D02*
Y32848D01*
G01X935678Y48553D02*
Y46020D01*
G01X936738Y48994D02*
Y32848D01*
G01X935678Y41880D02*
Y40920D01*
G01X936738Y48994D02*
Y32848D01*
G01X935678Y36580D02*
Y33291D01*
G01X940689Y105698D02*
Y60092D01*
G01X941749Y107247D02*
Y59649D01*
G01X940689Y60092D02*
X938789Y58192D01*
G01X941749Y59649D02*
X939849Y57749D01*
G01X938789Y58192D02*
Y57520D01*
G01X939849Y57749D02*
Y56620D01*
G01X938732Y49715D02*
X939830D01*
G01D02*
X940864Y48681D01*
G01X938732Y52314D02*
X941924Y49122D01*
G01X940864Y48681D02*
Y45906D01*
G01Y42080D02*
Y40707D01*
G01Y36793D02*
Y34172D01*
G01X941924Y49122D02*
Y33732D01*
G01X940864Y34172D02*
X939841Y33149D01*
G01D02*
X938732D01*
G01X910582Y127982D02*
X911814D01*
G01X910142Y126922D02*
X912254D01*
G01X911814Y127982D02*
X922411Y138579D01*
G01X912254Y126922D02*
X923471Y138139D01*
G01X922411Y138579D02*
Y147904D01*
G01X923471Y138139D02*
Y147464D01*
G01X922411Y147904D02*
X963200Y188693D01*
G01X923471Y147464D02*
X947167Y171160D01*
G01X922411Y147904D02*
X963200Y188693D01*
G01X922411Y147904D02*
X963200Y188693D01*
G01X922411Y147904D02*
X963200Y188693D01*
G01X922411Y147904D02*
X963200Y188693D01*
G01X922411Y147904D02*
X963200Y188693D01*
G01X922411Y147904D02*
X963200Y188693D01*
G01X922411Y147904D02*
X963200Y188693D01*
G01X922411Y147904D02*
X963200Y188693D01*
G01X910582Y127982D02*
X911814D01*
G01X910142Y126922D02*
X912254D01*
G01X911814Y127982D02*
X922411Y138579D01*
G01X912254Y126922D02*
X923471Y138139D01*
G01X922411Y138579D02*
Y147904D01*
G01X923471Y138139D02*
Y147464D01*
G01X922411Y147904D02*
X963200Y188693D01*
G01X923471Y147464D02*
X947167Y171160D01*
G01X922411Y147904D02*
X963200Y188693D01*
G01X922411Y147904D02*
X963200Y188693D01*
G01X922411Y147904D02*
X963200Y188693D01*
G01X922411Y147904D02*
X963200Y188693D01*
G01X922411Y147904D02*
X963200Y188693D01*
G01X922411Y147904D02*
X963200Y188693D01*
G01X922411Y147904D02*
X963200Y188693D01*
G01X922411Y147904D02*
X963200Y188693D01*
G01X926983Y137751D02*
Y147058D01*
G01X928043Y137311D02*
Y146618D01*
G01X926983Y147058D02*
X967293Y187368D01*
G01X928043Y146618D02*
X972990Y191565D01*
G01X926983Y137751D02*
Y147058D01*
G01X928043Y137311D02*
Y146618D01*
G01X926983Y147058D02*
X967293Y187368D01*
G01X928043Y146618D02*
X972990Y191565D01*
G01X910142Y126922D02*
X912254D01*
G01X910582Y127982D02*
X911814D01*
G01X912254Y126922D02*
X923471Y138139D01*
G01X911814Y127982D02*
X922411Y138579D01*
G01X923471Y138139D02*
Y147464D01*
G01X922411Y138579D02*
Y147904D01*
G01X923471Y147464D02*
X947167Y171160D01*
G01X922411Y147904D02*
X963200Y188693D01*
G01X910142Y126922D02*
X912254D01*
G01X910582Y127982D02*
X911814D01*
G01X912254Y126922D02*
X923471Y138139D01*
G01X911814Y127982D02*
X922411Y138579D01*
G01X923471Y138139D02*
Y147464D01*
G01X922411Y138579D02*
Y147904D01*
G01X923471Y147464D02*
X947167Y171160D01*
G01X922411Y147904D02*
X963200Y188693D01*
G01X928043Y137311D02*
Y146618D01*
G01X926983Y137751D02*
Y147058D01*
G01X928043Y146618D02*
X972990Y191565D01*
G01X926983Y147058D02*
X967293Y187368D01*
G01X928043Y146618D02*
X972990Y191565D01*
G01X928043Y146618D02*
X972990Y191565D01*
G01X928043Y137311D02*
Y146618D01*
G01X926983Y137751D02*
Y147058D01*
G01X928043Y146618D02*
X972990Y191565D01*
G01X926983Y147058D02*
X967293Y187368D01*
G01X928043Y146618D02*
X972990Y191565D01*
G01X928043Y146618D02*
X972990Y191565D01*
G01X911821Y181013D02*
X912598Y181790D01*
G01X911538Y182230D02*
Y186007D01*
G01X912598Y181790D02*
Y185567D01*
G01X911538Y186007D02*
X919802Y194271D01*
G01X912598Y185567D02*
X914189Y187158D01*
G01X911538Y186007D02*
X919802Y194271D01*
G01X914189Y187158D02*
X914827D01*
G01X911538Y186007D02*
X919802Y194271D01*
G01X915535Y188503D02*
X916636Y189604D01*
G01X911538Y186007D02*
X919802Y194271D01*
G01X916636Y189604D02*
X917273D01*
G01X911538Y186007D02*
X919802Y194271D01*
G01X917981Y190949D02*
X920466Y193434D01*
G01X919802Y194271D02*
X923012Y196265D01*
G01X920466Y193434D02*
X923802Y195507D01*
G01X923012Y196265D02*
X923826Y197703D01*
G01X923802Y195507D02*
X924749Y197181D01*
G01X911821Y181013D02*
X912598Y181790D01*
G01X911538Y182230D02*
Y186007D01*
G01X912598Y181790D02*
Y185567D01*
G01X911538Y186007D02*
X919802Y194271D01*
G01X912598Y185567D02*
X914189Y187158D01*
G01X911538Y186007D02*
X919802Y194271D01*
G01X914189Y187158D02*
X914827D01*
G01X911538Y186007D02*
X919802Y194271D01*
G01X915535Y188503D02*
X916636Y189604D01*
G01X911538Y186007D02*
X919802Y194271D01*
G01X916636Y189604D02*
X917273D01*
G01X911538Y186007D02*
X919802Y194271D01*
G01X917981Y190949D02*
X920466Y193434D01*
G01X919802Y194271D02*
X923012Y196265D01*
G01X920466Y193434D02*
X923802Y195507D01*
G01X923012Y196265D02*
X923826Y197703D01*
G01X923802Y195507D02*
X924749Y197181D01*
G01X948511Y172504D02*
X949218Y173211D01*
G01X950562Y174555D02*
X951343Y175336D01*
G01X952688Y176681D02*
X953659Y177652D01*
G01X955003Y178996D02*
X955710Y179703D01*
G01X957055Y181048D02*
X957866Y181859D01*
G01X959210Y183203D02*
X959917Y183910D01*
G01X961261Y185254D02*
X962180Y186173D01*
G01X963525Y187518D02*
X964260Y188253D01*
G01X963200Y188693D02*
Y193888D01*
G01X964260Y188253D02*
Y190343D01*
G01X963200Y188693D02*
Y193888D01*
G01X964260Y192243D02*
Y193448D01*
G01X963200Y193888D02*
X968550Y199238D01*
G01X964260Y193448D02*
X969300Y198488D01*
G01X948511Y172504D02*
X949218Y173211D01*
G01X950562Y174555D02*
X951343Y175336D01*
G01X952688Y176681D02*
X953659Y177652D01*
G01X955003Y178996D02*
X955710Y179703D01*
G01X957055Y181048D02*
X957866Y181859D01*
G01X959210Y183203D02*
X959917Y183910D01*
G01X961261Y185254D02*
X962180Y186173D01*
G01X963525Y187518D02*
X964260Y188253D01*
G01X963200Y188693D02*
Y193888D01*
G01X964260Y188253D02*
Y190343D01*
G01X963200Y188693D02*
Y193888D01*
G01X964260Y192243D02*
Y193448D01*
G01X963200Y193888D02*
X968550Y199238D01*
G01X964260Y193448D02*
X969300Y198488D01*
G01X915072Y180279D02*
Y184165D01*
G01X916132Y179839D02*
Y183725D01*
G01X915072Y184165D02*
X921743Y190836D01*
G01X916132Y183725D02*
X917289Y184882D01*
G01X915072Y184165D02*
X921743Y190836D01*
G01X917289Y184882D02*
X917926D01*
G01X915072Y184165D02*
X921743Y190836D01*
G01X918634Y186227D02*
X919941Y187534D01*
G01X915072Y184165D02*
X921743Y190836D01*
G01X919941Y187534D02*
X920578D01*
G01X915072Y184165D02*
X921743Y190836D01*
G01X921286Y188879D02*
X922453Y190046D01*
G01X921743Y190836D02*
X928001Y195878D01*
G01X922453Y190046D02*
X928711Y195088D01*
G01X928001Y195878D02*
X929992Y197869D01*
G01X928711Y195088D02*
X930741Y197119D01*
G01X915072Y180279D02*
Y184165D01*
G01X916132Y179839D02*
Y183725D01*
G01X915072Y184165D02*
X921743Y190836D01*
G01X916132Y183725D02*
X917289Y184882D01*
G01X915072Y184165D02*
X921743Y190836D01*
G01X917289Y184882D02*
X917926D01*
G01X915072Y184165D02*
X921743Y190836D01*
G01X918634Y186227D02*
X919941Y187534D01*
G01X915072Y184165D02*
X921743Y190836D01*
G01X919941Y187534D02*
X920578D01*
G01X915072Y184165D02*
X921743Y190836D01*
G01X921286Y188879D02*
X922453Y190046D01*
G01X921743Y190836D02*
X928001Y195878D01*
G01X922453Y190046D02*
X928711Y195088D01*
G01X928001Y195878D02*
X929992Y197869D01*
G01X928711Y195088D02*
X930741Y197119D01*
G01X968638Y188713D02*
X969740Y189815D01*
G01X971084Y191159D02*
X971930Y192005D01*
G01X968638Y188713D02*
X969740Y189815D01*
G01X971084Y191159D02*
X971930Y192005D01*
G01X911821Y181013D02*
X912598Y181790D01*
G01D02*
Y185567D01*
G01X911538Y182230D02*
Y186007D01*
G01X912598Y185567D02*
X914189Y187158D01*
G01D02*
X914827D01*
G01X915535Y188503D02*
X916636Y189604D01*
G01D02*
X917273D01*
G01X917981Y190949D02*
X920466Y193434D01*
G01X911538Y186007D02*
X919802Y194271D01*
G01X920466Y193434D02*
X923802Y195507D01*
G01X919802Y194271D02*
X923012Y196265D01*
G01X923802Y195507D02*
X924749Y197181D01*
G01X923012Y196265D02*
X923826Y197703D01*
G01X911821Y181013D02*
X912598Y181790D01*
G01D02*
Y185567D01*
G01X911538Y182230D02*
Y186007D01*
G01X912598Y185567D02*
X914189Y187158D01*
G01D02*
X914827D01*
G01X915535Y188503D02*
X916636Y189604D01*
G01D02*
X917273D01*
G01X917981Y190949D02*
X920466Y193434D01*
G01X911538Y186007D02*
X919802Y194271D01*
G01X920466Y193434D02*
X923802Y195507D01*
G01X919802Y194271D02*
X923012Y196265D01*
G01X923802Y195507D02*
X924749Y197181D01*
G01X923012Y196265D02*
X923826Y197703D01*
G01X948511Y172504D02*
X949218Y173211D01*
G01X950562Y174555D02*
X951343Y175336D01*
G01X952688Y176681D02*
X953659Y177652D01*
G01X955003Y178996D02*
X955710Y179703D01*
G01X957055Y181048D02*
X957866Y181859D01*
G01X959210Y183203D02*
X959917Y183910D01*
G01X961261Y185254D02*
X962180Y186173D01*
G01X963525Y187518D02*
X964260Y188253D01*
G01D02*
Y190343D01*
G01Y192243D02*
Y193448D01*
G01X963200Y188693D02*
Y193888D01*
G01X964260Y193448D02*
X969300Y198488D01*
G01X963200Y193888D02*
X968550Y199238D01*
G01X948511Y172504D02*
X949218Y173211D01*
G01X950562Y174555D02*
X951343Y175336D01*
G01X952688Y176681D02*
X953659Y177652D01*
G01X955003Y178996D02*
X955710Y179703D01*
G01X957055Y181048D02*
X957866Y181859D01*
G01X959210Y183203D02*
X959917Y183910D01*
G01X961261Y185254D02*
X962180Y186173D01*
G01X963525Y187518D02*
X964260Y188253D01*
G01D02*
Y190343D01*
G01Y192243D02*
Y193448D01*
G01X963200Y188693D02*
Y193888D01*
G01X964260Y193448D02*
X969300Y198488D01*
G01X963200Y193888D02*
X968550Y199238D01*
G01X916132Y179839D02*
Y183725D01*
G01X915072Y180279D02*
Y184165D01*
G01X916132Y183725D02*
X917289Y184882D01*
G01D02*
X917926D01*
G01X918634Y186227D02*
X919941Y187534D01*
G01D02*
X920578D01*
G01X921286Y188879D02*
X922453Y190046D01*
G01X915072Y184165D02*
X921743Y190836D01*
G01X922453Y190046D02*
X928711Y195088D01*
G01X921743Y190836D02*
X928001Y195878D01*
G01X928711Y195088D02*
X930741Y197119D01*
G01X928001Y195878D02*
X929992Y197869D01*
G01X916132Y179839D02*
Y183725D01*
G01X915072Y180279D02*
Y184165D01*
G01X916132Y183725D02*
X917289Y184882D01*
G01D02*
X917926D01*
G01X918634Y186227D02*
X919941Y187534D01*
G01D02*
X920578D01*
G01X921286Y188879D02*
X922453Y190046D01*
G01X915072Y184165D02*
X921743Y190836D01*
G01X922453Y190046D02*
X928711Y195088D01*
G01X921743Y190836D02*
X928001Y195878D01*
G01X928711Y195088D02*
X930741Y197119D01*
G01X928001Y195878D02*
X929992Y197869D01*
G01X968638Y188713D02*
X969740Y189815D01*
G01X971084Y191159D02*
X971930Y192005D01*
G01X968638Y188713D02*
X969740Y189815D01*
G01X971084Y191159D02*
X971930Y192005D01*
G01X922474Y408786D02*
X917500Y413760D01*
G01X923224Y409536D02*
X918560Y414200D01*
G01X917500Y413760D02*
Y422632D01*
G01X918560Y414200D02*
Y423072D01*
G01X925111Y413237D02*
X922500Y415847D01*
G01X924361Y412486D02*
X921440Y415407D01*
G01X922500Y415847D02*
Y426172D01*
G01X921440Y415407D02*
Y425732D01*
G01X922500Y426172D02*
X920088Y428584D01*
G01X921440Y425732D02*
X919648Y427524D01*
G01X922500Y426172D02*
X920088Y428584D01*
G01D02*
X919448D01*
G01X919648Y427524D02*
X919008D01*
G01X919448Y428584D02*
X917345Y430687D01*
G01X919008Y427524D02*
X916285Y430247D01*
G01X917345Y430687D02*
Y432987D01*
G01X916285Y430247D02*
Y432544D01*
G01X917345Y432987D02*
X915381Y434951D01*
G01X916285Y432544D02*
X914938Y433891D01*
G01X915381Y434951D02*
X912321D01*
G01X914938Y433891D02*
X911878D01*
G01X912321Y434951D02*
X910978Y436294D01*
G01D02*
Y439354D01*
G01X923224Y409536D02*
X918560Y414200D01*
G01X922474Y408786D02*
X917500Y413760D01*
G01X918560Y414200D02*
Y423072D01*
G01X917500Y413760D02*
Y422632D01*
G01X924361Y412486D02*
X921440Y415407D01*
G01X925111Y413237D02*
X922500Y415847D01*
G01X921440Y415407D02*
Y425732D01*
G01X922500Y415847D02*
Y426172D01*
G01X921440Y425732D02*
X919648Y427524D01*
G01D02*
X919008D01*
G01X922500Y426172D02*
X920088Y428584D01*
G01X919648Y427524D02*
X919008D01*
G01X920088Y428584D02*
X919448D01*
G01X919008Y427524D02*
X916285Y430247D01*
G01X919448Y428584D02*
X917345Y430687D01*
G01X916285Y430247D02*
Y432544D01*
G01X917345Y430687D02*
Y432987D01*
G01X916285Y432544D02*
X914938Y433891D01*
G01X917345Y432987D02*
X915381Y434951D01*
G01X914938Y433891D02*
X911878D01*
G01X915381Y434951D02*
X912321D01*
G01D02*
X910978Y436294D01*
G01D02*
Y439354D01*
G01X964753Y406287D02*
Y413419D01*
G01X965813Y406287D02*
Y413859D01*
G01X964753Y413419D02*
X950022Y428150D01*
G01X965813Y413859D02*
X951080Y428592D01*
G01X950020Y428150D02*
Y449609D01*
G01X951080Y428592D02*
Y450052D01*
G01X950020Y449609D02*
X926109Y473520D01*
G01X951080Y450052D02*
X926552Y474580D01*
G01X970043Y408160D02*
Y415029D01*
G01X968983Y408160D02*
Y414589D01*
G01X970043Y415029D02*
X954880Y430192D01*
G01X968983Y414589D02*
X953822Y429750D01*
G01X954880Y430192D02*
Y451691D01*
G01X953820Y429750D02*
Y451248D01*
G01X954880Y451691D02*
X947292Y459279D01*
G01X953820Y451248D02*
X946232Y458836D01*
G01X947292Y459279D02*
Y460507D01*
G01X946232Y458836D02*
Y460950D01*
G01X947292Y460507D02*
X947852Y461067D01*
G01X946232Y460950D02*
X946792Y461510D01*
G01X947852Y461067D02*
Y463179D01*
G01X946792Y461510D02*
Y462736D01*
G01X947852Y463179D02*
X946028Y465003D01*
G01X946792Y462736D02*
X945585Y463943D01*
G01X943916Y465003D02*
X943356Y464443D01*
G01X945585Y463943D02*
X944359D01*
G01X943916Y465003D02*
X943356Y464443D01*
G01X944359Y463943D02*
X943799Y463383D01*
G01X943356Y464443D02*
X942128D01*
G01X943799Y463383D02*
X941685D01*
G01X943356Y464443D02*
X942128D01*
G01D02*
X940925Y465646D01*
G01X941685Y463383D02*
X939865Y465203D01*
G01X965813Y406287D02*
Y413859D01*
G01X964753Y406287D02*
Y413419D01*
G01X965813Y413859D02*
X951080Y428592D01*
G01X964753Y413419D02*
X950022Y428150D01*
G01X951080Y428592D02*
Y450052D01*
G01X950020Y428150D02*
Y449609D01*
G01X951080Y450052D02*
X926552Y474580D01*
G01X950020Y449609D02*
X926109Y473520D01*
G01X968983Y408160D02*
Y414589D01*
G01X970043Y408160D02*
Y415029D01*
G01X968983Y414589D02*
X953822Y429750D01*
G01X970043Y415029D02*
X954880Y430192D01*
G01X953820Y429750D02*
Y451248D01*
G01X954880Y430192D02*
Y451691D01*
G01X953820Y451248D02*
X946232Y458836D01*
G01X954880Y451691D02*
X947292Y459279D01*
G01X946232Y458836D02*
Y460950D01*
G01X947292Y459279D02*
Y460507D01*
G01X946232Y460950D02*
X946792Y461510D01*
G01X947292Y460507D02*
X947852Y461067D01*
G01X946792Y461510D02*
Y462736D01*
G01X947852Y461067D02*
Y463179D01*
G01X946792Y462736D02*
X945585Y463943D01*
G01X947852Y463179D02*
X946028Y465003D01*
G01X945585Y463943D02*
X944359D01*
G01X945585D02*
X944359D01*
G01D02*
X943799Y463383D01*
G01X943916Y465003D02*
X943356Y464443D01*
G01X943799Y463383D02*
X941685D01*
G01D02*
X939865Y465203D01*
G01X943356Y464443D02*
X942128D01*
G01X941685Y463383D02*
X939865Y465203D01*
G01X942128Y464443D02*
X940925Y465646D01*
G01X922474Y408786D02*
X917500Y413760D01*
G01X923224Y409536D02*
X918560Y414200D01*
G01X917500Y413760D02*
Y422632D01*
G01X918560Y414200D02*
Y423072D01*
G01X964753Y406287D02*
Y413419D01*
G01X965813Y406287D02*
Y413859D01*
G01X964753Y413419D02*
X950022Y428150D01*
G01X965813Y413859D02*
X951080Y428592D01*
G01X950020Y428150D02*
Y449609D01*
G01X951080Y428592D02*
Y450052D01*
G01X950020Y449609D02*
X926109Y473520D01*
G01X951080Y450052D02*
X926552Y474580D01*
G01X925111Y413237D02*
X922500Y415847D01*
G01X924361Y412486D02*
X921440Y415407D01*
G01X922500Y415847D02*
Y426172D01*
G01X921440Y415407D02*
Y425732D01*
G01X922500Y426172D02*
X920088Y428584D01*
G01X921440Y425732D02*
X919648Y427524D01*
G01X922500Y426172D02*
X920088Y428584D01*
G01D02*
X919448D01*
G01X919648Y427524D02*
X919008D01*
G01X919448Y428584D02*
X917345Y430687D01*
G01X919008Y427524D02*
X916285Y430247D01*
G01X917345Y430687D02*
Y432987D01*
G01X916285Y430247D02*
Y432544D01*
G01X917345Y432987D02*
X915381Y434951D01*
G01X916285Y432544D02*
X914938Y433891D01*
G01X915381Y434951D02*
X912321D01*
G01X914938Y433891D02*
X911878D01*
G01X912321Y434951D02*
X910978Y436294D01*
G01D02*
Y439354D01*
G01X970043Y408160D02*
Y415029D01*
G01X968983Y408160D02*
Y414589D01*
G01X970043Y415029D02*
X954880Y430192D01*
G01X968983Y414589D02*
X953822Y429750D01*
G01X954880Y430192D02*
Y451691D01*
G01X953820Y429750D02*
Y451248D01*
G01X954880Y451691D02*
X947292Y459279D01*
G01X953820Y451248D02*
X946232Y458836D01*
G01X947292Y459279D02*
Y460507D01*
G01X946232Y458836D02*
Y460950D01*
G01X947292Y460507D02*
X947852Y461067D01*
G01X946232Y460950D02*
X946792Y461510D01*
G01X947852Y461067D02*
Y463179D01*
G01X946792Y461510D02*
Y462736D01*
G01X947852Y463179D02*
X946028Y465003D01*
G01X946792Y462736D02*
X945585Y463943D01*
G01X943916Y465003D02*
X943356Y464443D01*
G01X945585Y463943D02*
X944359D01*
G01X943916Y465003D02*
X943356Y464443D01*
G01X944359Y463943D02*
X943799Y463383D01*
G01X943356Y464443D02*
X942128D01*
G01X943799Y463383D02*
X941685D01*
G01X943356Y464443D02*
X942128D01*
G01D02*
X940925Y465646D01*
G01X941685Y463383D02*
X939865Y465203D01*
G01X923224Y409536D02*
X918560Y414200D01*
G01X922474Y408786D02*
X917500Y413760D01*
G01X918560Y414200D02*
Y423072D01*
G01X917500Y413760D02*
Y422632D01*
G01X965813Y406287D02*
Y413859D01*
G01X964753Y406287D02*
Y413419D01*
G01X965813Y413859D02*
X951080Y428592D01*
G01X964753Y413419D02*
X950022Y428150D01*
G01X951080Y428592D02*
Y450052D01*
G01X950020Y428150D02*
Y449609D01*
G01X951080Y450052D02*
X926552Y474580D01*
G01X950020Y449609D02*
X926109Y473520D01*
G01X924361Y412486D02*
X921440Y415407D01*
G01X925111Y413237D02*
X922500Y415847D01*
G01X921440Y415407D02*
Y425732D01*
G01X922500Y415847D02*
Y426172D01*
G01X921440Y425732D02*
X919648Y427524D01*
G01D02*
X919008D01*
G01X922500Y426172D02*
X920088Y428584D01*
G01X919648Y427524D02*
X919008D01*
G01X920088Y428584D02*
X919448D01*
G01X919008Y427524D02*
X916285Y430247D01*
G01X919448Y428584D02*
X917345Y430687D01*
G01X916285Y430247D02*
Y432544D01*
G01X917345Y430687D02*
Y432987D01*
G01X916285Y432544D02*
X914938Y433891D01*
G01X917345Y432987D02*
X915381Y434951D01*
G01X914938Y433891D02*
X911878D01*
G01X915381Y434951D02*
X912321D01*
G01D02*
X910978Y436294D01*
G01D02*
Y439354D01*
G01X968983Y408160D02*
Y414589D01*
G01X970043Y408160D02*
Y415029D01*
G01X968983Y414589D02*
X953822Y429750D01*
G01X970043Y415029D02*
X954880Y430192D01*
G01X953820Y429750D02*
Y451248D01*
G01X954880Y430192D02*
Y451691D01*
G01X953820Y451248D02*
X946232Y458836D01*
G01X954880Y451691D02*
X947292Y459279D01*
G01X946232Y458836D02*
Y460950D01*
G01X947292Y459279D02*
Y460507D01*
G01X946232Y460950D02*
X946792Y461510D01*
G01X947292Y460507D02*
X947852Y461067D01*
G01X946792Y461510D02*
Y462736D01*
G01X947852Y461067D02*
Y463179D01*
G01X946792Y462736D02*
X945585Y463943D01*
G01X947852Y463179D02*
X946028Y465003D01*
G01X945585Y463943D02*
X944359D01*
G01X945585D02*
X944359D01*
G01D02*
X943799Y463383D01*
G01X943916Y465003D02*
X943356Y464443D01*
G01X943799Y463383D02*
X941685D01*
G01D02*
X939865Y465203D01*
G01X943356Y464443D02*
X942128D01*
G01X941685Y463383D02*
X939865Y465203D01*
G01X942128Y464443D02*
X940925Y465646D01*
G01X926109Y473520D02*
X913109D01*
G01X926552Y474580D02*
X913549D01*
G01X946028Y465003D02*
X943916D01*
G01X940925Y465646D02*
Y466874D01*
G01X939865Y465203D02*
Y467317D01*
G01X940925Y466874D02*
X941485Y467434D01*
G01X939865Y467317D02*
X940425Y467877D01*
G01X941485Y467434D02*
Y469546D01*
G01X940425Y467877D02*
Y469106D01*
G01X941485Y469546D02*
X939661Y471370D01*
G01X940425Y469106D02*
X939221Y470310D01*
G01X939661Y471370D02*
X937219D01*
G01X939221Y470310D02*
X936779D01*
G01X937219Y471370D02*
X934558Y474031D01*
G01X936779Y470310D02*
X933498Y473591D01*
G01X934558Y474031D02*
Y475914D01*
G01X933498Y473591D02*
Y475474D01*
G01X934558Y475914D02*
X932092Y478380D01*
G01X933498Y475474D02*
X931652Y477320D01*
G01X932092Y478380D02*
X915349D01*
G01X931652Y477320D02*
X914909D01*
G01X926552Y474580D02*
X913549D01*
G01X926109Y473520D02*
X913109D01*
G01X946028Y465003D02*
X943916D01*
G01X939865Y465203D02*
Y467317D01*
G01X940925Y465646D02*
Y466874D01*
G01X939865Y467317D02*
X940425Y467877D01*
G01X940925Y466874D02*
X941485Y467434D01*
G01X940425Y467877D02*
Y469106D01*
G01X941485Y467434D02*
Y469546D01*
G01X940425Y469106D02*
X939221Y470310D01*
G01X941485Y469546D02*
X939661Y471370D01*
G01X939221Y470310D02*
X936779D01*
G01X939661Y471370D02*
X937219D01*
G01X936779Y470310D02*
X933498Y473591D01*
G01X937219Y471370D02*
X934558Y474031D01*
G01X933498Y473591D02*
Y475474D01*
G01X934558Y474031D02*
Y475914D01*
G01X933498Y475474D02*
X931652Y477320D01*
G01X934558Y475914D02*
X932092Y478380D01*
G01X931652Y477320D02*
X914909D01*
G01X932092Y478380D02*
X915349D01*
G01X926109Y473520D02*
X913109D01*
G01X926552Y474580D02*
X913549D01*
G01X946028Y465003D02*
X943916D01*
G01X940925Y465646D02*
Y466874D01*
G01X939865Y465203D02*
Y467317D01*
G01X940925Y466874D02*
X941485Y467434D01*
G01X939865Y467317D02*
X940425Y467877D01*
G01X941485Y467434D02*
Y469546D01*
G01X940425Y467877D02*
Y469106D01*
G01X941485Y469546D02*
X939661Y471370D01*
G01X940425Y469106D02*
X939221Y470310D01*
G01X939661Y471370D02*
X937219D01*
G01X939221Y470310D02*
X936779D01*
G01X937219Y471370D02*
X934558Y474031D01*
G01X936779Y470310D02*
X933498Y473591D01*
G01X934558Y474031D02*
Y475914D01*
G01X933498Y473591D02*
Y475474D01*
G01X934558Y475914D02*
X932092Y478380D01*
G01X933498Y475474D02*
X931652Y477320D01*
G01X932092Y478380D02*
X915349D01*
G01X931652Y477320D02*
X914909D01*
G01X926552Y474580D02*
X913549D01*
G01X926109Y473520D02*
X913109D01*
G01X946028Y465003D02*
X943916D01*
G01X939865Y465203D02*
Y467317D01*
G01X940925Y465646D02*
Y466874D01*
G01X939865Y467317D02*
X940425Y467877D01*
G01X940925Y466874D02*
X941485Y467434D01*
G01X940425Y467877D02*
Y469106D01*
G01X941485Y467434D02*
Y469546D01*
G01X940425Y469106D02*
X939221Y470310D01*
G01X941485Y469546D02*
X939661Y471370D01*
G01X939221Y470310D02*
X936779D01*
G01X939661Y471370D02*
X937219D01*
G01X936779Y470310D02*
X933498Y473591D01*
G01X937219Y471370D02*
X934558Y474031D01*
G01X933498Y473591D02*
Y475474D01*
G01X934558Y474031D02*
Y475914D01*
G01X933498Y475474D02*
X931652Y477320D01*
G01X934558Y475914D02*
X932092Y478380D01*
G01X931652Y477320D02*
X914909D01*
G01X932092Y478380D02*
X915349D01*
G01X935652Y548509D02*
Y505798D01*
G01X936712Y550049D02*
Y505358D01*
G01X935652Y505798D02*
X931920Y502066D01*
G01X936712Y505358D02*
X935412Y504058D01*
G01X940500Y502549D02*
Y497712D01*
G01X939440Y502140D02*
Y502989D01*
G01X941812Y503861D02*
X940500Y502549D01*
G01X939440Y502989D02*
X940752Y504301D01*
G01X941812Y520840D02*
Y503861D01*
G01X940752Y504301D02*
Y520400D01*
G01X939800Y522852D02*
X941812Y520840D01*
G01X940752Y520400D02*
X938740Y522412D01*
G01X939800Y525000D02*
Y522852D01*
G01X938740Y522412D02*
Y525440D01*
G01X941812Y527012D02*
X939800Y525000D01*
G01X938740Y525440D02*
X940752Y527452D01*
G01X936712Y550049D02*
Y505358D01*
G01X935652Y548509D02*
Y505798D01*
G01X936712Y505358D02*
X935412Y504058D01*
G01X935652Y505798D02*
X931920Y502066D01*
G01X938740Y525440D02*
X940752Y527452D01*
G01X941812Y527012D02*
X939800Y525000D01*
G01X938740Y522412D02*
Y525440D01*
G01X939800Y525000D02*
Y522852D01*
G01X940752Y520400D02*
X938740Y522412D01*
G01X939800Y522852D02*
X941812Y520840D01*
G01X940752Y504301D02*
Y520400D01*
G01X941812Y520840D02*
Y503861D01*
G01X939440Y502989D02*
X940752Y504301D01*
G01X941812Y503861D02*
X940500Y502549D01*
G01X939440Y502140D02*
Y502989D01*
G01X940500Y502549D02*
Y497712D01*
G01X941812Y540588D02*
Y527012D01*
G01X940752Y527452D02*
Y540148D01*
G01X940860Y541540D02*
X941812Y540588D01*
G01X940752Y540148D02*
X939800Y541100D01*
G01X940860Y544960D02*
Y541540D01*
G01X939800Y541100D02*
Y545400D01*
G01X941812Y545912D02*
X940860Y544960D01*
G01X939800Y545400D02*
X940752Y546352D01*
G01X941812Y550235D02*
Y545912D01*
G01X940752Y546352D02*
Y548695D01*
G01Y546352D02*
Y548695D01*
G01X941812Y550235D02*
Y545912D01*
G01X939800Y545400D02*
X940752Y546352D01*
G01X941812Y545912D02*
X940860Y544960D01*
G01X939800Y541100D02*
Y545400D01*
G01X940860Y544960D02*
Y541540D01*
G01X940752Y540148D02*
X939800Y541100D01*
G01X940860Y541540D02*
X941812Y540588D01*
G01X940752Y527452D02*
Y540148D01*
G01X941812Y540588D02*
Y527012D01*
G01X931644Y608011D02*
Y590288D01*
G01X932704Y602066D02*
Y600940D01*
G01X931644Y608011D02*
Y590288D01*
G01X932704Y597260D02*
Y595890D01*
G01X937257Y597448D02*
Y596171D01*
G01X936197Y601994D02*
Y595730D01*
G01X937257Y596171D02*
X937928Y595500D01*
G01X936197Y595730D02*
X937027Y594900D01*
G01X932704Y602066D02*
Y600940D01*
G01Y597260D02*
Y595890D01*
G01X931644Y608011D02*
Y590288D01*
G01X936197Y601994D02*
Y595730D01*
G01X937257Y597448D02*
Y596171D01*
G01X936197Y595730D02*
X937027Y594900D01*
G01X937257Y596171D02*
X937928Y595500D01*
G01X971930Y192005D02*
Y194243D01*
G01X972990Y191565D02*
Y193803D01*
G01X971930Y194243D02*
X972637Y194950D01*
G01X973345Y196294D02*
X973981D01*
G01D02*
X974718Y197031D01*
G01X972990Y193803D02*
X975468Y196281D01*
G01X971930Y192005D02*
Y194243D01*
G01X972990Y191565D02*
Y193803D01*
G01X971930Y194243D02*
X972637Y194950D01*
G01X973345Y196294D02*
X973981D01*
G01D02*
X974718Y197031D01*
G01X972990Y193803D02*
X975468Y196281D01*
G01X972990Y191565D02*
Y193803D01*
G01X971930Y192005D02*
Y194243D01*
G01X972990Y193803D02*
X975468Y196281D01*
G01X971930Y194243D02*
X972637Y194950D01*
G01X972990Y193803D02*
X975468Y196281D01*
G01X973345Y196294D02*
X973981D01*
G01X972990Y193803D02*
X975468Y196281D01*
G01X973981Y196294D02*
X974718Y197031D01*
G01X972990Y191565D02*
Y193803D01*
G01X971930Y192005D02*
Y194243D01*
G01X972990Y193803D02*
X975468Y196281D01*
G01X971930Y194243D02*
X972637Y194950D01*
G01X972990Y193803D02*
X975468Y196281D01*
G01X973345Y196294D02*
X973981D01*
G01X972990Y193803D02*
X975468Y196281D01*
G01X973981Y196294D02*
X974718Y197031D01*
G01X1079845Y154575D02*
X1117620Y116800D01*
G01X1118680Y117240D02*
X1085038Y150882D01*
G01X1079845Y154575D02*
X1117620Y116800D01*
G01X1083694Y152226D02*
X1082956Y152964D01*
G01X1079845Y154575D02*
X1117620Y116800D01*
G01X1081612Y154308D02*
X1080905Y155015D01*
G01X1079845Y186013D02*
Y154575D01*
G01X1080905Y155015D02*
Y157250D01*
G01X1079845Y186013D02*
Y154575D01*
G01Y186013D02*
Y154575D01*
G01Y186013D02*
Y154575D01*
G01Y186013D02*
Y154575D01*
G01Y186013D02*
Y154575D01*
G01Y186013D02*
Y154575D01*
G01Y186013D02*
Y154575D01*
G01Y186013D02*
Y154575D01*
G01Y186013D02*
Y154575D01*
G01X1121512Y118467D02*
X1084216Y155763D01*
G01X1122572Y118907D02*
X1085276Y156203D01*
G01X1084216Y155763D02*
Y167925D01*
G01X1085276Y156203D02*
Y183955D01*
G01X1080905Y155015D02*
Y157250D01*
G01X1079845Y186013D02*
Y154575D01*
G01X1118680Y117240D02*
X1085038Y150882D01*
G01X1083694Y152226D02*
X1082956Y152964D01*
G01X1081612Y154308D02*
X1080905Y155015D01*
G01X1079845Y154575D02*
X1117620Y116800D01*
G01X1122572Y118907D02*
X1085276Y156203D01*
G01X1121512Y118467D02*
X1084216Y155763D01*
G01X1085276Y156203D02*
Y183955D01*
G01X1084216Y155763D02*
Y167925D01*
G01X1085276Y156203D02*
Y183955D01*
G01Y156203D02*
Y183955D01*
G01Y156203D02*
Y183955D01*
G01Y156203D02*
Y183955D01*
G01X1079845Y154575D02*
X1117620Y116800D01*
G01X1118680Y117240D02*
X1085038Y150882D01*
G01X1079845Y154575D02*
X1117620Y116800D01*
G01X1083694Y152226D02*
X1082956Y152964D01*
G01X1079845Y154575D02*
X1117620Y116800D01*
G01X1081612Y154308D02*
X1080905Y155015D01*
G01X1079845Y186013D02*
Y154575D01*
G01X1080905Y155015D02*
Y157250D01*
G01X1079845Y186013D02*
Y154575D01*
G01Y186013D02*
Y154575D01*
G01Y186013D02*
Y154575D01*
G01Y186013D02*
Y154575D01*
G01Y186013D02*
Y154575D01*
G01Y186013D02*
Y154575D01*
G01Y186013D02*
Y154575D01*
G01Y186013D02*
Y154575D01*
G01Y186013D02*
Y154575D01*
G01X1121512Y118467D02*
X1084216Y155763D01*
G01X1122572Y118907D02*
X1085276Y156203D01*
G01X1084216Y155763D02*
Y167925D01*
G01X1085276Y156203D02*
Y183955D01*
G01X1080905Y155015D02*
Y157250D01*
G01X1079845Y186013D02*
Y154575D01*
G01X1118680Y117240D02*
X1085038Y150882D01*
G01X1083694Y152226D02*
X1082956Y152964D01*
G01X1081612Y154308D02*
X1080905Y155015D01*
G01X1079845Y154575D02*
X1117620Y116800D01*
G01X1122572Y118907D02*
X1085276Y156203D01*
G01X1121512Y118467D02*
X1084216Y155763D01*
G01X1085276Y156203D02*
Y183955D01*
G01X1084216Y155763D02*
Y167925D01*
G01X1085276Y156203D02*
Y183955D01*
G01Y156203D02*
Y183955D01*
G01Y156203D02*
Y183955D01*
G01Y156203D02*
Y183955D01*
G01X1080905Y159150D02*
Y160150D01*
G01Y162050D02*
Y163050D01*
G01Y164950D02*
Y166122D01*
G01Y168022D02*
Y169022D01*
G01Y170922D02*
Y171922D01*
G01Y173822D02*
Y174879D01*
G01Y176779D02*
Y178219D01*
G01Y180119D02*
Y181119D01*
G01Y183019D02*
Y186013D01*
G01X1084216Y169825D02*
Y171760D01*
G01Y173660D02*
Y175757D01*
G01Y177657D02*
Y180047D01*
G01Y181947D02*
Y183515D01*
G01D02*
X1083545Y184186D01*
G01X1085276Y183955D02*
X1084605Y184626D01*
G01X1083545Y184186D02*
Y186413D01*
G01X1084605Y184626D02*
Y186413D01*
G01X1080905Y159150D02*
Y160150D01*
G01Y162050D02*
Y163050D01*
G01Y164950D02*
Y166122D01*
G01Y168022D02*
Y169022D01*
G01Y170922D02*
Y171922D01*
G01Y173822D02*
Y174879D01*
G01Y176779D02*
Y178219D01*
G01Y180119D02*
Y181119D01*
G01Y183019D02*
Y186013D01*
G01X1084216Y169825D02*
Y171760D01*
G01Y173660D02*
Y175757D01*
G01Y177657D02*
Y180047D01*
G01Y181947D02*
Y183515D01*
G01X1085276Y183955D02*
X1084605Y184626D01*
G01X1084216Y183515D02*
X1083545Y184186D01*
G01X1084605Y184626D02*
Y186413D01*
G01X1083545Y184186D02*
Y186413D01*
G01X1080905Y159150D02*
Y160150D01*
G01Y162050D02*
Y163050D01*
G01Y164950D02*
Y166122D01*
G01Y168022D02*
Y169022D01*
G01Y170922D02*
Y171922D01*
G01Y173822D02*
Y174879D01*
G01Y176779D02*
Y178219D01*
G01Y180119D02*
Y181119D01*
G01Y183019D02*
Y186013D01*
G01X1084216Y169825D02*
Y171760D01*
G01Y173660D02*
Y175757D01*
G01Y177657D02*
Y180047D01*
G01Y181947D02*
Y183515D01*
G01D02*
X1083545Y184186D01*
G01X1085276Y183955D02*
X1084605Y184626D01*
G01X1083545Y184186D02*
Y186413D01*
G01X1084605Y184626D02*
Y186413D01*
G01X1080905Y159150D02*
Y160150D01*
G01Y162050D02*
Y163050D01*
G01Y164950D02*
Y166122D01*
G01Y168022D02*
Y169022D01*
G01Y170922D02*
Y171922D01*
G01Y173822D02*
Y174879D01*
G01Y176779D02*
Y178219D01*
G01Y180119D02*
Y181119D01*
G01Y183019D02*
Y186013D01*
G01X1084216Y169825D02*
Y171760D01*
G01Y173660D02*
Y175757D01*
G01Y177657D02*
Y180047D01*
G01Y181947D02*
Y183515D01*
G01X1085276Y183955D02*
X1084605Y184626D01*
G01X1084216Y183515D02*
X1083545Y184186D01*
G01X1084605Y184626D02*
Y186413D01*
G01X1083545Y184186D02*
Y186413D01*
G01X1081125Y412574D02*
Y457457D01*
G01X1082185Y412574D02*
Y457017D01*
G01X1081125Y457457D02*
X1102949Y479281D01*
G01X1082185Y457017D02*
X1104009Y478841D01*
G01X1085935Y412574D02*
Y455435D01*
G01X1084875Y412574D02*
Y455875D01*
G01X1085935Y455435D02*
X1109569Y479069D01*
G01X1084875Y455875D02*
X1108509Y479509D01*
G01X1082185Y412574D02*
Y457017D01*
G01X1081125Y412574D02*
Y457457D01*
G01X1082185Y457017D02*
X1104009Y478841D01*
G01X1081125Y457457D02*
X1102949Y479281D01*
G01X1084875Y412574D02*
Y455875D01*
G01X1085935Y412574D02*
Y455435D01*
G01X1084875Y455875D02*
X1108509Y479509D01*
G01X1085935Y455435D02*
X1109569Y479069D01*
G01X1081125Y412574D02*
Y457457D01*
G01X1082185Y412574D02*
Y457017D01*
G01X1081125Y457457D02*
X1102949Y479281D01*
G01X1082185Y457017D02*
X1104009Y478841D01*
G01X1081125Y412574D02*
Y457457D01*
G01X1082185Y412574D02*
Y457017D01*
G01X1081125Y457457D02*
X1102949Y479281D01*
G01X1082185Y457017D02*
X1104009Y478841D01*
G01X1085935Y412574D02*
Y455435D01*
G01X1084875Y412574D02*
Y455875D01*
G01X1085935Y455435D02*
X1109569Y479069D01*
G01X1084875Y455875D02*
X1108509Y479509D01*
G01X1082185Y412574D02*
Y457017D01*
G01X1081125Y412574D02*
Y457457D01*
G01X1082185Y457017D02*
X1104009Y478841D01*
G01X1081125Y457457D02*
X1102949Y479281D01*
G01X1084875Y412574D02*
Y455875D01*
G01X1085935Y412574D02*
Y455435D01*
G01X1084875Y455875D02*
X1108509Y479509D01*
G01X1085935Y455435D02*
X1109569Y479069D01*
G01X1115159Y-5220D02*
X1115675D01*
G01X1115136Y-6280D02*
X1116118D01*
G01X1115675Y-5220D02*
X1116386Y-4509D01*
G01X1116118Y-6280D02*
X1117446Y-4952D01*
G01X1116386Y-4509D02*
Y-1220D01*
G01Y3120D02*
Y4080D01*
G01Y8220D02*
Y10753D01*
G01X1117446Y-4952D02*
Y11194D01*
G01X1116386Y10753D02*
X1115439Y11700D01*
G01X1117446Y11194D02*
X1114340Y14300D01*
G01X1112486Y21131D02*
Y13554D01*
G01X1113546Y19620D02*
Y20688D01*
G01X1116361Y25006D02*
X1112486Y21131D01*
G01X1113546Y20688D02*
X1117421Y24563D01*
G01X1116361Y99229D02*
Y25006D01*
G01X1117421Y24563D02*
Y55580D01*
G01X1116361Y99229D02*
Y25006D01*
G01Y99229D02*
Y25006D01*
G01X1119440Y-4651D02*
X1120549D01*
G01D02*
X1121572Y-3628D01*
G01X1119440Y-7260D02*
X1122632Y-4068D01*
G01X1121572Y-3628D02*
Y-1007D01*
G01Y2907D02*
Y4280D01*
G01Y8106D02*
Y10881D01*
G01X1122632Y-4068D02*
Y11322D01*
G01X1121572Y10881D02*
X1120538Y11915D01*
G01D02*
X1119440D01*
G01X1122632Y11322D02*
X1119440Y14514D01*
G01X1118186Y18687D02*
Y21231D01*
G01X1119246Y19920D02*
Y20788D01*
G01X1118186Y21231D02*
X1121512Y24557D01*
G01X1119246Y20788D02*
X1120220Y21762D01*
G01X1118186Y21231D02*
X1121512Y24557D01*
G01X1120220Y21762D02*
X1121096D01*
G01X1118186Y21231D02*
X1121512Y24557D01*
G01X1121804Y23346D02*
X1122572Y24114D01*
G01X1121512Y24557D02*
Y118467D01*
G01X1122572Y24114D02*
Y24946D01*
G01X1121512Y24557D02*
Y118467D01*
G01X1122572Y27186D02*
Y37280D01*
G01X1121512Y24557D02*
Y118467D01*
G01Y24557D02*
Y118467D01*
G01X1115136Y-6280D02*
X1116118D01*
G01X1115159Y-5220D02*
X1115675D01*
G01X1116118Y-6280D02*
X1117446Y-4952D01*
G01X1115675Y-5220D02*
X1116386Y-4509D01*
G01X1117446Y-4952D02*
Y11194D01*
G01X1116386Y-4509D02*
Y-1220D01*
G01X1117446Y-4952D02*
Y11194D01*
G01X1116386Y3120D02*
Y4080D01*
G01X1117446Y-4952D02*
Y11194D01*
G01X1116386Y8220D02*
Y10753D01*
G01X1117446Y11194D02*
X1114340Y14300D01*
G01X1116386Y10753D02*
X1115439Y11700D01*
G01X1117421Y24563D02*
Y55580D01*
G01X1116361Y99229D02*
Y25006D01*
G01X1113546Y20688D02*
X1117421Y24563D01*
G01X1116361Y25006D02*
X1112486Y21131D01*
G01X1113546Y19620D02*
Y20688D01*
G01X1112486Y21131D02*
Y13554D01*
G01X1119440Y-7260D02*
X1122632Y-4068D01*
G01X1119440Y-4651D02*
X1120549D01*
G01X1119440Y-7260D02*
X1122632Y-4068D01*
G01X1120549Y-4651D02*
X1121572Y-3628D01*
G01X1122632Y-4068D02*
Y11322D01*
G01X1121572Y-3628D02*
Y-1007D01*
G01X1122632Y-4068D02*
Y11322D01*
G01X1121572Y2907D02*
Y4280D01*
G01X1122632Y-4068D02*
Y11322D01*
G01X1121572Y8106D02*
Y10881D01*
G01X1122632Y11322D02*
X1119440Y14514D01*
G01X1121572Y10881D02*
X1120538Y11915D01*
G01X1122632Y11322D02*
X1119440Y14514D01*
G01X1120538Y11915D02*
X1119440D01*
G01X1119246Y19920D02*
Y20788D01*
G01X1118186Y18687D02*
Y21231D01*
G01X1119246Y20788D02*
X1120220Y21762D01*
G01D02*
X1121096D01*
G01X1121804Y23346D02*
X1122572Y24114D01*
G01X1118186Y21231D02*
X1121512Y24557D01*
G01X1122572Y24114D02*
Y24946D01*
G01Y27186D02*
Y37280D01*
G01X1121512Y24557D02*
Y118467D01*
G01X1151970Y32580D02*
X1152487D01*
G01X1151947Y31520D02*
X1152930D01*
G01X1151970Y32580D02*
X1152487D01*
G01D02*
X1153198Y33291D01*
G01X1152930Y31520D02*
X1154258Y32848D01*
G01X1151947Y31520D02*
X1152930D01*
G01D02*
X1154258Y32848D01*
G01X1151970Y32580D02*
X1152487D01*
G01X1152930Y31520D02*
X1154258Y32848D01*
G01X1152487Y32580D02*
X1153198Y33291D01*
G01X1156252Y30540D02*
X1159444Y33732D01*
G01X1115159Y-5220D02*
X1115675D01*
G01X1115136Y-6280D02*
X1116118D01*
G01X1115675Y-5220D02*
X1116386Y-4509D01*
G01X1116118Y-6280D02*
X1117446Y-4952D01*
G01X1116386Y-4509D02*
Y-1220D01*
G01Y3120D02*
Y4080D01*
G01Y8220D02*
Y10753D01*
G01X1117446Y-4952D02*
Y11194D01*
G01X1116386Y10753D02*
X1115439Y11700D01*
G01X1117446Y11194D02*
X1114340Y14300D01*
G01X1112486Y21131D02*
Y13554D01*
G01X1113546Y19620D02*
Y20688D01*
G01X1116361Y25006D02*
X1112486Y21131D01*
G01X1113546Y20688D02*
X1117421Y24563D01*
G01X1116361Y99229D02*
Y25006D01*
G01X1117421Y24563D02*
Y55580D01*
G01X1116361Y99229D02*
Y25006D01*
G01Y99229D02*
Y25006D01*
G01X1152251Y11700D02*
X1153198Y10753D01*
G01X1151152Y14300D02*
X1154258Y11194D01*
G01X1153198Y10753D02*
Y8220D01*
G01Y4080D02*
Y3120D01*
G01Y-1220D02*
Y-4509D01*
G01X1154258Y11194D02*
Y-4952D01*
G01X1153198Y-4509D02*
X1152487Y-5220D01*
G01D02*
X1151971D01*
G01X1154258Y-4952D02*
X1152930Y-6280D01*
G01X1152487Y-5220D02*
X1151971D01*
G01X1152930Y-6280D02*
X1151948D01*
G01X1119440Y-4651D02*
X1120549D01*
G01D02*
X1121572Y-3628D01*
G01X1119440Y-7260D02*
X1122632Y-4068D01*
G01X1121572Y-3628D02*
Y-1007D01*
G01Y2907D02*
Y4280D01*
G01Y8106D02*
Y10881D01*
G01X1122632Y-4068D02*
Y11322D01*
G01X1121572Y10881D02*
X1120538Y11915D01*
G01D02*
X1119440D01*
G01X1122632Y11322D02*
X1119440Y14514D01*
G01X1118186Y18687D02*
Y21231D01*
G01X1119246Y19920D02*
Y20788D01*
G01X1118186Y21231D02*
X1121512Y24557D01*
G01X1119246Y20788D02*
X1120220Y21762D01*
G01X1118186Y21231D02*
X1121512Y24557D01*
G01X1120220Y21762D02*
X1121096D01*
G01X1118186Y21231D02*
X1121512Y24557D01*
G01X1121804Y23346D02*
X1122572Y24114D01*
G01X1121512Y24557D02*
Y118467D01*
G01X1122572Y24114D02*
Y24946D01*
G01X1121512Y24557D02*
Y118467D01*
G01X1122572Y27186D02*
Y37280D01*
G01X1121512Y24557D02*
Y118467D01*
G01Y24557D02*
Y118467D01*
G01X1156252Y11915D02*
X1157350D01*
G01X1156252Y14514D02*
X1159444Y11322D01*
G01X1157361Y-4651D02*
X1156252D01*
G01X1159444Y-4068D02*
X1156252Y-7260D01*
G01X1115136Y-6280D02*
X1116118D01*
G01X1115159Y-5220D02*
X1115675D01*
G01X1116118Y-6280D02*
X1117446Y-4952D01*
G01X1115675Y-5220D02*
X1116386Y-4509D01*
G01X1117446Y-4952D02*
Y11194D01*
G01X1116386Y-4509D02*
Y-1220D01*
G01X1117446Y-4952D02*
Y11194D01*
G01X1116386Y3120D02*
Y4080D01*
G01X1117446Y-4952D02*
Y11194D01*
G01X1116386Y8220D02*
Y10753D01*
G01X1117446Y11194D02*
X1114340Y14300D01*
G01X1116386Y10753D02*
X1115439Y11700D01*
G01X1117421Y24563D02*
Y55580D01*
G01X1116361Y99229D02*
Y25006D01*
G01X1113546Y20688D02*
X1117421Y24563D01*
G01X1116361Y25006D02*
X1112486Y21131D01*
G01X1113546Y19620D02*
Y20688D01*
G01X1112486Y21131D02*
Y13554D01*
G01X1151152Y14300D02*
X1154258Y11194D01*
G01X1152251Y11700D02*
X1153198Y10753D01*
G01X1154258Y11194D02*
Y-4952D01*
G01X1153198Y10753D02*
Y8220D01*
G01X1154258Y11194D02*
Y-4952D01*
G01X1153198Y4080D02*
Y3120D01*
G01X1154258Y11194D02*
Y-4952D01*
G01X1153198Y-1220D02*
Y-4509D01*
G01X1154258Y-4952D02*
X1152930Y-6280D01*
G01X1153198Y-4509D02*
X1152487Y-5220D01*
G01X1154258Y-4952D02*
X1152930Y-6280D01*
G01D02*
X1151948D01*
G01X1152487Y-5220D02*
X1151971D01*
G01X1119440Y-7260D02*
X1122632Y-4068D01*
G01X1119440Y-4651D02*
X1120549D01*
G01X1119440Y-7260D02*
X1122632Y-4068D01*
G01X1120549Y-4651D02*
X1121572Y-3628D01*
G01X1122632Y-4068D02*
Y11322D01*
G01X1121572Y-3628D02*
Y-1007D01*
G01X1122632Y-4068D02*
Y11322D01*
G01X1121572Y2907D02*
Y4280D01*
G01X1122632Y-4068D02*
Y11322D01*
G01X1121572Y8106D02*
Y10881D01*
G01X1122632Y11322D02*
X1119440Y14514D01*
G01X1121572Y10881D02*
X1120538Y11915D01*
G01X1122632Y11322D02*
X1119440Y14514D01*
G01X1120538Y11915D02*
X1119440D01*
G01X1119246Y19920D02*
Y20788D01*
G01X1118186Y18687D02*
Y21231D01*
G01X1119246Y20788D02*
X1120220Y21762D01*
G01D02*
X1121096D01*
G01X1121804Y23346D02*
X1122572Y24114D01*
G01X1118186Y21231D02*
X1121512Y24557D01*
G01X1122572Y24114D02*
Y24946D01*
G01Y27186D02*
Y37280D01*
G01X1121512Y24557D02*
Y118467D01*
G01X1156252Y14514D02*
X1159444Y11322D01*
G01X1156252Y11915D02*
X1157350D01*
G01X1156252Y14514D02*
X1159444Y11322D01*
G01Y-4068D02*
X1156252Y-7260D01*
G01X1159444Y-4068D02*
X1156252Y-7260D01*
G01X1157361Y-4651D02*
X1156252D01*
G01X1151970Y32580D02*
X1152487D01*
G01X1151947Y31520D02*
X1152930D01*
G01X1151970Y32580D02*
X1152487D01*
G01D02*
X1153198Y33291D01*
G01X1152930Y31520D02*
X1154258Y32848D01*
G01X1156252Y30540D02*
X1159444Y33732D01*
G01X1156252Y30540D02*
X1159444Y33732D01*
G01X1156252Y30540D02*
X1159444Y33732D01*
G01X1156252Y30540D02*
X1159444Y33732D01*
G01X1156252Y30540D02*
X1159444Y33732D01*
G01X1156252Y30540D02*
X1159444Y33732D01*
G01X1151947Y31520D02*
X1152930D01*
G01D02*
X1154258Y32848D01*
G01X1151970Y32580D02*
X1152487D01*
G01X1152930Y31520D02*
X1154258Y32848D01*
G01X1152487Y32580D02*
X1153198Y33291D01*
G01X1151947Y31520D02*
X1152930D01*
G01D02*
X1154258Y32848D01*
G01X1151970Y32580D02*
X1152487D01*
G01X1152930Y31520D02*
X1154258Y32848D01*
G01X1152487Y32580D02*
X1153198Y33291D01*
G01X1156252Y30540D02*
X1159444Y33732D01*
G01X1117421Y57820D02*
Y58580D01*
G01Y60820D02*
Y98789D01*
G01X1122572Y39520D02*
Y40280D01*
G01Y42520D02*
Y118907D01*
G01X1117421Y57820D02*
Y58580D01*
G01Y60820D02*
Y98789D01*
G01X1122572Y39520D02*
Y40280D01*
G01Y42520D02*
Y118907D01*
G01X1151109Y60609D02*
Y57320D01*
G01X1152169Y56781D02*
Y60169D01*
G01X1153109Y62609D02*
X1151109Y60609D01*
G01X1152169Y60169D02*
X1154169Y62169D01*
G01X1153109Y74592D02*
Y62609D01*
G01X1154169Y62169D02*
Y75032D01*
G01X1152140Y75561D02*
X1153109Y74592D01*
G01X1154169Y75032D02*
X1153200Y76001D01*
G01X1152140Y83140D02*
Y75561D01*
G01X1153200Y76001D02*
Y82700D01*
G01X1153109Y84109D02*
X1152140Y83140D01*
G01X1153200Y82700D02*
X1154169Y83669D01*
G01X1153109Y105934D02*
Y84109D01*
G01X1154169Y83669D02*
Y107497D01*
G01X1153198Y33291D02*
Y36580D01*
G01Y40920D02*
Y41880D01*
G01Y46020D02*
Y48552D01*
G01X1154258Y32848D02*
Y48993D01*
G01X1153198Y48552D02*
X1152250Y49500D01*
G01X1154258Y48993D02*
X1151151Y52100D01*
G01X1154169Y83669D02*
Y107497D01*
G01X1153109Y105934D02*
Y84109D01*
G01X1153200Y82700D02*
X1154169Y83669D01*
G01X1153109Y84109D02*
X1152140Y83140D01*
G01X1153200Y76001D02*
Y82700D01*
G01X1152140Y83140D02*
Y75561D01*
G01X1154169Y75032D02*
X1153200Y76001D01*
G01X1152140Y75561D02*
X1153109Y74592D01*
G01X1154169Y62169D02*
Y75032D01*
G01X1153109Y74592D02*
Y62609D01*
G01X1152169Y60169D02*
X1154169Y62169D01*
G01X1153109Y62609D02*
X1151109Y60609D01*
G01X1152169Y56781D02*
Y60169D01*
G01X1151109Y60609D02*
Y57320D01*
G01X1154258Y32848D02*
Y48993D01*
G01X1153198Y33291D02*
Y36580D01*
G01X1154258Y32848D02*
Y48993D01*
G01X1153198Y40920D02*
Y41880D01*
G01X1154258Y32848D02*
Y48993D01*
G01X1153198Y46020D02*
Y48552D01*
G01X1154258Y48993D02*
X1151151Y52100D01*
G01X1153198Y48552D02*
X1152250Y49500D01*
G01X1156309Y57520D02*
Y58192D01*
G01D02*
X1158209Y60092D01*
G01X1156251Y33149D02*
X1157361D01*
G01X1157350Y49715D02*
X1156251D01*
G01X1159444Y49121D02*
X1156251Y52314D01*
G01X1117421Y57820D02*
Y58580D01*
G01Y60820D02*
Y98789D01*
G01X1122572Y39520D02*
Y40280D01*
G01Y42520D02*
Y118907D01*
G01X1117421Y57820D02*
Y58580D01*
G01Y60820D02*
Y98789D01*
G01X1122572Y39520D02*
Y40280D01*
G01Y42520D02*
Y118907D01*
G01X1151109Y60609D02*
Y57320D01*
G01X1152169Y56781D02*
Y60169D01*
G01X1153109Y62609D02*
X1151109Y60609D01*
G01X1152169Y60169D02*
X1154169Y62169D01*
G01X1153109Y74592D02*
Y62609D01*
G01X1154169Y62169D02*
Y75032D01*
G01X1152140Y75561D02*
X1153109Y74592D01*
G01X1154169Y75032D02*
X1153200Y76001D01*
G01X1152140Y83140D02*
Y75561D01*
G01X1153200Y76001D02*
Y82700D01*
G01X1153109Y84109D02*
X1152140Y83140D01*
G01X1153200Y82700D02*
X1154169Y83669D01*
G01X1153109Y105934D02*
Y84109D01*
G01X1154169Y83669D02*
Y107497D01*
G01X1153198Y33291D02*
Y36580D01*
G01Y40920D02*
Y41880D01*
G01Y46020D02*
Y48552D01*
G01X1154258Y32848D02*
Y48993D01*
G01X1153198Y48552D02*
X1152250Y49500D01*
G01X1154258Y48993D02*
X1151151Y52100D01*
G01X1156309Y57520D02*
Y58192D01*
G01D02*
X1158209Y60092D01*
G01X1156251Y33149D02*
X1157361D01*
G01X1159444Y49121D02*
X1156251Y52314D01*
G01X1159444Y49121D02*
X1156251Y52314D01*
G01X1157350Y49715D02*
X1156251D01*
G01X1156309Y57520D02*
Y58192D01*
G01D02*
X1158209Y60092D01*
G01X1156251Y33149D02*
X1157361D01*
G01X1159444Y49121D02*
X1156251Y52314D01*
G01X1159444Y49121D02*
X1156251Y52314D01*
G01X1157350Y49715D02*
X1156251D01*
G01X1156309Y57520D02*
Y58192D01*
G01D02*
X1158209Y60092D01*
G01X1156251Y33149D02*
X1157361D01*
G01X1159444Y49121D02*
X1156251Y52314D01*
G01X1159444Y49121D02*
X1156251Y52314D01*
G01X1157350Y49715D02*
X1156251D01*
G01X1154169Y83669D02*
Y107497D01*
G01X1153109Y105934D02*
Y84109D01*
G01X1153200Y82700D02*
X1154169Y83669D01*
G01X1153109Y84109D02*
X1152140Y83140D01*
G01X1153200Y76001D02*
Y82700D01*
G01X1152140Y83140D02*
Y75561D01*
G01X1154169Y75032D02*
X1153200Y76001D01*
G01X1152140Y75561D02*
X1153109Y74592D01*
G01X1154169Y62169D02*
Y75032D01*
G01X1153109Y74592D02*
Y62609D01*
G01X1152169Y60169D02*
X1154169Y62169D01*
G01X1153109Y62609D02*
X1151109Y60609D01*
G01X1152169Y56781D02*
Y60169D01*
G01X1151109Y60609D02*
Y57320D01*
G01X1154258Y32848D02*
Y48993D01*
G01X1153198Y33291D02*
Y36580D01*
G01X1154258Y32848D02*
Y48993D01*
G01X1153198Y40920D02*
Y41880D01*
G01X1154258Y32848D02*
Y48993D01*
G01X1153198Y46020D02*
Y48552D01*
G01X1154258Y48993D02*
X1151151Y52100D01*
G01X1153198Y48552D02*
X1152250Y49500D01*
G01X1154169Y83669D02*
Y107497D01*
G01X1153109Y105934D02*
Y84109D01*
G01X1153200Y82700D02*
X1154169Y83669D01*
G01X1153109Y84109D02*
X1152140Y83140D01*
G01X1153200Y76001D02*
Y82700D01*
G01X1152140Y83140D02*
Y75561D01*
G01X1154169Y75032D02*
X1153200Y76001D01*
G01X1152140Y75561D02*
X1153109Y74592D01*
G01X1154169Y62169D02*
Y75032D01*
G01X1153109Y74592D02*
Y62609D01*
G01X1152169Y60169D02*
X1154169Y62169D01*
G01X1153109Y62609D02*
X1151109Y60609D01*
G01X1152169Y56781D02*
Y60169D01*
G01X1151109Y60609D02*
Y57320D01*
G01X1154258Y32848D02*
Y48993D01*
G01X1153198Y33291D02*
Y36580D01*
G01X1154258Y32848D02*
Y48993D01*
G01X1153198Y40920D02*
Y41880D01*
G01X1154258Y32848D02*
Y48993D01*
G01X1153198Y46020D02*
Y48552D01*
G01X1154258Y48993D02*
X1151151Y52100D01*
G01X1153198Y48552D02*
X1152250Y49500D01*
G01X1156309Y57520D02*
Y58192D01*
G01D02*
X1158209Y60092D01*
G01X1156251Y33149D02*
X1157361D01*
G01X1157350Y49715D02*
X1156251D01*
G01X1159444Y49121D02*
X1156251Y52314D01*
G01X1117620Y100488D02*
X1116361Y99229D01*
G01X1117421Y98789D02*
X1118680Y100048D01*
G01X1117620Y107634D02*
Y100488D01*
G01X1118680Y100048D02*
Y108074D01*
G01X1117119Y108135D02*
X1117620Y107634D01*
G01X1118680Y108074D02*
X1117559Y109195D01*
G01X1113612Y108135D02*
X1117119D01*
G01X1117559Y109195D02*
X1114052D01*
G01X1112020Y109727D02*
X1113612Y108135D01*
G01X1114052Y109195D02*
X1113080Y110167D01*
G01X1112020Y113006D02*
Y109727D01*
G01X1113080Y110167D02*
Y112563D01*
G01X1113509Y114495D02*
X1112020Y113006D01*
G01X1113080Y112563D02*
X1113952Y113435D01*
G01X1116748Y114495D02*
X1113509D01*
G01X1113952Y113435D02*
X1117191D01*
G01X1117620Y115367D02*
X1116748Y114495D01*
G01X1117191Y113435D02*
X1118680Y114924D01*
G01X1117620Y116800D02*
Y115367D01*
G01X1118680Y114924D02*
Y117240D01*
G01Y114924D02*
Y117240D01*
G01X1117620Y116800D02*
Y115367D01*
G01X1117191Y113435D02*
X1118680Y114924D01*
G01X1117620Y115367D02*
X1116748Y114495D01*
G01X1113952Y113435D02*
X1117191D01*
G01X1116748Y114495D02*
X1113509D01*
G01X1113080Y112563D02*
X1113952Y113435D01*
G01X1113509Y114495D02*
X1112020Y113006D01*
G01X1113080Y110167D02*
Y112563D01*
G01X1112020Y113006D02*
Y109727D01*
G01X1114052Y109195D02*
X1113080Y110167D01*
G01X1112020Y109727D02*
X1113612Y108135D01*
G01X1117559Y109195D02*
X1114052D01*
G01X1113612Y108135D02*
X1117119D01*
G01X1118680Y108074D02*
X1117559Y109195D01*
G01X1117119Y108135D02*
X1117620Y107634D01*
G01X1118680Y100048D02*
Y108074D01*
G01X1117620Y107634D02*
Y100488D01*
G01X1117421Y98789D02*
X1118680Y100048D01*
G01X1117620Y100488D02*
X1116361Y99229D01*
G01X1117620Y100488D02*
X1116361Y99229D01*
G01X1117421Y98789D02*
X1118680Y100048D01*
G01X1117620Y107634D02*
Y100488D01*
G01X1118680Y100048D02*
Y108074D01*
G01X1117119Y108135D02*
X1117620Y107634D01*
G01X1118680Y108074D02*
X1117559Y109195D01*
G01X1113612Y108135D02*
X1117119D01*
G01X1117559Y109195D02*
X1114052D01*
G01X1112020Y109727D02*
X1113612Y108135D01*
G01X1114052Y109195D02*
X1113080Y110167D01*
G01X1112020Y113006D02*
Y109727D01*
G01X1113080Y110167D02*
Y112563D01*
G01X1113509Y114495D02*
X1112020Y113006D01*
G01X1113080Y112563D02*
X1113952Y113435D01*
G01X1116748Y114495D02*
X1113509D01*
G01X1113952Y113435D02*
X1117191D01*
G01X1117620Y115367D02*
X1116748Y114495D01*
G01X1117191Y113435D02*
X1118680Y114924D01*
G01X1117620Y116800D02*
Y115367D01*
G01X1118680Y114924D02*
Y117240D01*
G01Y114924D02*
Y117240D01*
G01X1117620Y116800D02*
Y115367D01*
G01X1117191Y113435D02*
X1118680Y114924D01*
G01X1117620Y115367D02*
X1116748Y114495D01*
G01X1113952Y113435D02*
X1117191D01*
G01X1116748Y114495D02*
X1113509D01*
G01X1113080Y112563D02*
X1113952Y113435D01*
G01X1113509Y114495D02*
X1112020Y113006D01*
G01X1113080Y110167D02*
Y112563D01*
G01X1112020Y113006D02*
Y109727D01*
G01X1114052Y109195D02*
X1113080Y110167D01*
G01X1112020Y109727D02*
X1113612Y108135D01*
G01X1117559Y109195D02*
X1114052D01*
G01X1113612Y108135D02*
X1117119D01*
G01X1118680Y108074D02*
X1117559Y109195D01*
G01X1117119Y108135D02*
X1117620Y107634D01*
G01X1118680Y100048D02*
Y108074D01*
G01X1117620Y107634D02*
Y100488D01*
G01X1117421Y98789D02*
X1118680Y100048D01*
G01X1117620Y100488D02*
X1116361Y99229D01*
G01X1157336Y137620D02*
X1154840D01*
G01X1157779Y138680D02*
X1154397D01*
G01X1154840Y137620D02*
X1153968Y136748D01*
G01X1154397Y138680D02*
X1152908Y137191D01*
G01X1153968Y136748D02*
Y135209D01*
G01X1152908Y137191D02*
Y135649D01*
G01X1153968Y135209D02*
X1152479Y133720D01*
G01X1152908Y135649D02*
X1152039Y134780D01*
G01X1152479Y133720D02*
X1148598D01*
G01X1152039Y134780D02*
X1149038D01*
G01X1148598Y133720D02*
X1146852Y135466D01*
G01X1149038Y134780D02*
X1147912Y135906D01*
G01X1146852Y135466D02*
Y136984D01*
G01X1147912Y135906D02*
Y137424D01*
G01X1146852Y136984D02*
X1146216Y137620D01*
G01X1147912Y137424D02*
X1146656Y138680D01*
G01X1146216Y137620D02*
X1138597D01*
G01X1146656Y138680D02*
X1139037D01*
G01X1138597Y137620D02*
X1120973Y155246D01*
G01X1139037Y138680D02*
X1122033Y155686D01*
G01X1120973Y155246D02*
Y169156D01*
G01X1122033Y155686D02*
Y157866D01*
G01X1120973Y155246D02*
Y169156D01*
G01Y155246D02*
Y169156D01*
G01Y155246D02*
Y169156D01*
G01Y155246D02*
Y169156D01*
G01X1169748Y141420D02*
X1140197D01*
G01X1170191Y142480D02*
X1140637D01*
G01X1140197Y141420D02*
X1126667Y154950D01*
G01X1140637Y142480D02*
X1127727Y155390D01*
G01X1126667Y154950D02*
Y170030D01*
G01X1127727Y155390D02*
Y170470D01*
G01X1157779Y138680D02*
X1154397D01*
G01X1157336Y137620D02*
X1154840D01*
G01X1154397Y138680D02*
X1152908Y137191D01*
G01X1154840Y137620D02*
X1153968Y136748D01*
G01X1152908Y137191D02*
Y135649D01*
G01X1153968Y136748D02*
Y135209D01*
G01X1152908Y135649D02*
X1152039Y134780D01*
G01X1153968Y135209D02*
X1152479Y133720D01*
G01X1152039Y134780D02*
X1149038D01*
G01X1152479Y133720D02*
X1148598D01*
G01X1149038Y134780D02*
X1147912Y135906D01*
G01X1148598Y133720D02*
X1146852Y135466D01*
G01X1147912Y135906D02*
Y137424D01*
G01X1146852Y135466D02*
Y136984D01*
G01X1147912Y137424D02*
X1146656Y138680D01*
G01X1146852Y136984D02*
X1146216Y137620D01*
G01X1146656Y138680D02*
X1139037D01*
G01X1146216Y137620D02*
X1138597D01*
G01X1139037Y138680D02*
X1122033Y155686D01*
G01X1138597Y137620D02*
X1120973Y155246D01*
G01X1122033Y155686D02*
Y157866D01*
G01X1120973Y155246D02*
Y169156D01*
G01X1170191Y142480D02*
X1140637D01*
G01X1169748Y141420D02*
X1140197D01*
G01X1140637Y142480D02*
X1127727Y155390D01*
G01X1140197Y141420D02*
X1126667Y154950D01*
G01X1127727Y155390D02*
Y170470D01*
G01X1126667Y154950D02*
Y170030D01*
G01X1157336Y137620D02*
X1154840D01*
G01X1157779Y138680D02*
X1154397D01*
G01X1154840Y137620D02*
X1153968Y136748D01*
G01X1154397Y138680D02*
X1152908Y137191D01*
G01X1153968Y136748D02*
Y135209D01*
G01X1152908Y137191D02*
Y135649D01*
G01X1153968Y135209D02*
X1152479Y133720D01*
G01X1152908Y135649D02*
X1152039Y134780D01*
G01X1152479Y133720D02*
X1148598D01*
G01X1152039Y134780D02*
X1149038D01*
G01X1148598Y133720D02*
X1146852Y135466D01*
G01X1149038Y134780D02*
X1147912Y135906D01*
G01X1146852Y135466D02*
Y136984D01*
G01X1147912Y135906D02*
Y137424D01*
G01X1146852Y136984D02*
X1146216Y137620D01*
G01X1147912Y137424D02*
X1146656Y138680D01*
G01X1146216Y137620D02*
X1138597D01*
G01X1146656Y138680D02*
X1139037D01*
G01X1138597Y137620D02*
X1120973Y155246D01*
G01X1139037Y138680D02*
X1122033Y155686D01*
G01X1120973Y155246D02*
Y169156D01*
G01X1122033Y155686D02*
Y157866D01*
G01X1120973Y155246D02*
Y169156D01*
G01Y155246D02*
Y169156D01*
G01Y155246D02*
Y169156D01*
G01Y155246D02*
Y169156D01*
G01X1169748Y141420D02*
X1140197D01*
G01X1170191Y142480D02*
X1140637D01*
G01X1140197Y141420D02*
X1126667Y154950D01*
G01X1140637Y142480D02*
X1127727Y155390D01*
G01X1126667Y154950D02*
Y170030D01*
G01X1127727Y155390D02*
Y170470D01*
G01X1157779Y138680D02*
X1154397D01*
G01X1157336Y137620D02*
X1154840D01*
G01X1154397Y138680D02*
X1152908Y137191D01*
G01X1154840Y137620D02*
X1153968Y136748D01*
G01X1152908Y137191D02*
Y135649D01*
G01X1153968Y136748D02*
Y135209D01*
G01X1152908Y135649D02*
X1152039Y134780D01*
G01X1153968Y135209D02*
X1152479Y133720D01*
G01X1152039Y134780D02*
X1149038D01*
G01X1152479Y133720D02*
X1148598D01*
G01X1149038Y134780D02*
X1147912Y135906D01*
G01X1148598Y133720D02*
X1146852Y135466D01*
G01X1147912Y135906D02*
Y137424D01*
G01X1146852Y135466D02*
Y136984D01*
G01X1147912Y137424D02*
X1146656Y138680D01*
G01X1146852Y136984D02*
X1146216Y137620D01*
G01X1146656Y138680D02*
X1139037D01*
G01X1146216Y137620D02*
X1138597D01*
G01X1139037Y138680D02*
X1122033Y155686D01*
G01X1138597Y137620D02*
X1120973Y155246D01*
G01X1122033Y155686D02*
Y157866D01*
G01X1120973Y155246D02*
Y169156D01*
G01X1170191Y142480D02*
X1140637D01*
G01X1169748Y141420D02*
X1140197D01*
G01X1140637Y142480D02*
X1127727Y155390D01*
G01X1140197Y141420D02*
X1126667Y154950D01*
G01X1127727Y155390D02*
Y170470D01*
G01X1126667Y154950D02*
Y170030D01*
G01X1122033Y159766D02*
Y160766D01*
G01Y162666D02*
Y163666D01*
G01Y165566D02*
Y166566D01*
G01Y168466D02*
Y169596D01*
G01X1120973Y169156D02*
X1109566Y180563D01*
G01X1122033Y169596D02*
X1120881Y170748D01*
G01X1120973Y169156D02*
X1109566Y180563D01*
G01X1119537Y172092D02*
X1118830Y172799D01*
G01X1120973Y169156D02*
X1109566Y180563D01*
G01X1117486Y174143D02*
X1116779Y174850D01*
G01X1120973Y169156D02*
X1109566Y180563D01*
G01X1115435Y176194D02*
X1114728Y176901D01*
G01X1120973Y169156D02*
X1109566Y180563D01*
G01X1113384Y178245D02*
X1112677Y178952D01*
G01X1120973Y169156D02*
X1109566Y180563D01*
G01X1111333Y180296D02*
X1110626Y181003D01*
G01X1109566Y180563D02*
Y183900D01*
G01X1110626Y181003D02*
Y183900D01*
G01X1126667Y170030D02*
X1123955Y172742D01*
G01X1122611Y174086D02*
X1121852Y174845D01*
G01X1120508Y176189D02*
X1119520Y177177D01*
G01X1118175Y178522D02*
X1117074Y179623D01*
G01X1115729Y180968D02*
X1113367Y183330D01*
G01X1127727Y170470D02*
X1114427Y183770D01*
G01X1113367Y183330D02*
Y185913D01*
G01X1114427Y183770D02*
Y185913D01*
G01X1122033Y159766D02*
Y160766D01*
G01Y162666D02*
Y163666D01*
G01Y165566D02*
Y166566D01*
G01Y168466D02*
Y169596D01*
G01D02*
X1120881Y170748D01*
G01X1119537Y172092D02*
X1118830Y172799D01*
G01X1117486Y174143D02*
X1116779Y174850D01*
G01X1115435Y176194D02*
X1114728Y176901D01*
G01X1113384Y178245D02*
X1112677Y178952D01*
G01X1111333Y180296D02*
X1110626Y181003D01*
G01X1120973Y169156D02*
X1109566Y180563D01*
G01X1110626Y181003D02*
Y183900D01*
G01X1109566Y180563D02*
Y183900D01*
G01X1127727Y170470D02*
X1114427Y183770D01*
G01X1126667Y170030D02*
X1123955Y172742D01*
G01X1127727Y170470D02*
X1114427Y183770D01*
G01X1122611Y174086D02*
X1121852Y174845D01*
G01X1127727Y170470D02*
X1114427Y183770D01*
G01X1120508Y176189D02*
X1119520Y177177D01*
G01X1127727Y170470D02*
X1114427Y183770D01*
G01X1118175Y178522D02*
X1117074Y179623D01*
G01X1127727Y170470D02*
X1114427Y183770D01*
G01X1115729Y180968D02*
X1113367Y183330D01*
G01X1114427Y183770D02*
Y185913D01*
G01X1113367Y183330D02*
Y185913D01*
G01X1135400Y195200D02*
X1145600Y185000D01*
G01X1136150Y195950D02*
X1136997Y195103D01*
G01X1135400Y195200D02*
X1145600Y185000D01*
G01X1138342Y193758D02*
X1139049Y193051D01*
G01X1135400Y195200D02*
X1145600Y185000D01*
G01X1140464Y191636D02*
X1141171Y190929D01*
G01X1135400Y195200D02*
X1145600Y185000D01*
G01X1142586Y189514D02*
X1143293Y188807D01*
G01X1135400Y195200D02*
X1145600Y185000D01*
G01X1144708Y187392D02*
X1146040Y186060D01*
G01X1145600Y185000D02*
X1158400D01*
G01X1146040Y186060D02*
X1147040D01*
G01X1145600Y185000D02*
X1158400D01*
G01X1149040Y186060D02*
X1150100D01*
G01X1145600Y185000D02*
X1158400D01*
G01X1152100Y186060D02*
X1153600D01*
G01X1145600Y185000D02*
X1158400D01*
G01X1155600Y186060D02*
X1158840D01*
G01X1136650Y199650D02*
X1146155Y190145D01*
G01X1137400Y200400D02*
X1146595Y191205D01*
G01X1146155Y190145D02*
X1147818D01*
G01X1149718D02*
X1151555D01*
G01X1153455D02*
X1158255D01*
G01X1146595Y191205D02*
X1158695D01*
G01X1136150Y195950D02*
X1136997Y195103D01*
G01X1138342Y193758D02*
X1139049Y193051D01*
G01X1140464Y191636D02*
X1141171Y190929D01*
G01X1142586Y189514D02*
X1143293Y188807D01*
G01X1144708Y187392D02*
X1146040Y186060D01*
G01X1135400Y195200D02*
X1145600Y185000D01*
G01X1146040Y186060D02*
X1147040D01*
G01X1149040D02*
X1150100D01*
G01X1152100D02*
X1153600D01*
G01X1155600D02*
X1158840D01*
G01X1145600Y185000D02*
X1158400D01*
G01X1137400Y200400D02*
X1146595Y191205D01*
G01X1136650Y199650D02*
X1146155Y190145D01*
G01X1146595Y191205D02*
X1158695D01*
G01X1146155Y190145D02*
X1147818D01*
G01X1146595Y191205D02*
X1158695D01*
G01X1149718Y190145D02*
X1151555D01*
G01X1146595Y191205D02*
X1158695D01*
G01X1153455Y190145D02*
X1158255D01*
G01X1122033Y159766D02*
Y160766D01*
G01Y162666D02*
Y163666D01*
G01Y165566D02*
Y166566D01*
G01Y168466D02*
Y169596D01*
G01X1120973Y169156D02*
X1109566Y180563D01*
G01X1122033Y169596D02*
X1120881Y170748D01*
G01X1120973Y169156D02*
X1109566Y180563D01*
G01X1119537Y172092D02*
X1118830Y172799D01*
G01X1120973Y169156D02*
X1109566Y180563D01*
G01X1117486Y174143D02*
X1116779Y174850D01*
G01X1120973Y169156D02*
X1109566Y180563D01*
G01X1115435Y176194D02*
X1114728Y176901D01*
G01X1120973Y169156D02*
X1109566Y180563D01*
G01X1113384Y178245D02*
X1112677Y178952D01*
G01X1120973Y169156D02*
X1109566Y180563D01*
G01X1111333Y180296D02*
X1110626Y181003D01*
G01X1109566Y180563D02*
Y183900D01*
G01X1110626Y181003D02*
Y183900D01*
G01X1126667Y170030D02*
X1123955Y172742D01*
G01X1122611Y174086D02*
X1121852Y174845D01*
G01X1120508Y176189D02*
X1119520Y177177D01*
G01X1118175Y178522D02*
X1117074Y179623D01*
G01X1115729Y180968D02*
X1113367Y183330D01*
G01X1127727Y170470D02*
X1114427Y183770D01*
G01X1113367Y183330D02*
Y185913D01*
G01X1114427Y183770D02*
Y185913D01*
G01X1122033Y159766D02*
Y160766D01*
G01Y162666D02*
Y163666D01*
G01Y165566D02*
Y166566D01*
G01Y168466D02*
Y169596D01*
G01D02*
X1120881Y170748D01*
G01X1119537Y172092D02*
X1118830Y172799D01*
G01X1117486Y174143D02*
X1116779Y174850D01*
G01X1115435Y176194D02*
X1114728Y176901D01*
G01X1113384Y178245D02*
X1112677Y178952D01*
G01X1111333Y180296D02*
X1110626Y181003D01*
G01X1120973Y169156D02*
X1109566Y180563D01*
G01X1110626Y181003D02*
Y183900D01*
G01X1109566Y180563D02*
Y183900D01*
G01X1127727Y170470D02*
X1114427Y183770D01*
G01X1126667Y170030D02*
X1123955Y172742D01*
G01X1127727Y170470D02*
X1114427Y183770D01*
G01X1122611Y174086D02*
X1121852Y174845D01*
G01X1127727Y170470D02*
X1114427Y183770D01*
G01X1120508Y176189D02*
X1119520Y177177D01*
G01X1127727Y170470D02*
X1114427Y183770D01*
G01X1118175Y178522D02*
X1117074Y179623D01*
G01X1127727Y170470D02*
X1114427Y183770D01*
G01X1115729Y180968D02*
X1113367Y183330D01*
G01X1114427Y183770D02*
Y185913D01*
G01X1113367Y183330D02*
Y185913D01*
G01X1135400Y195200D02*
X1145600Y185000D01*
G01X1136150Y195950D02*
X1136997Y195103D01*
G01X1135400Y195200D02*
X1145600Y185000D01*
G01X1138342Y193758D02*
X1139049Y193051D01*
G01X1135400Y195200D02*
X1145600Y185000D01*
G01X1140464Y191636D02*
X1141171Y190929D01*
G01X1135400Y195200D02*
X1145600Y185000D01*
G01X1142586Y189514D02*
X1143293Y188807D01*
G01X1135400Y195200D02*
X1145600Y185000D01*
G01X1144708Y187392D02*
X1146040Y186060D01*
G01X1145600Y185000D02*
X1158400D01*
G01X1146040Y186060D02*
X1147040D01*
G01X1145600Y185000D02*
X1158400D01*
G01X1149040Y186060D02*
X1150100D01*
G01X1145600Y185000D02*
X1158400D01*
G01X1152100Y186060D02*
X1153600D01*
G01X1145600Y185000D02*
X1158400D01*
G01X1155600Y186060D02*
X1158840D01*
G01X1136650Y199650D02*
X1146155Y190145D01*
G01X1137400Y200400D02*
X1146595Y191205D01*
G01X1146155Y190145D02*
X1147818D01*
G01X1149718D02*
X1151555D01*
G01X1153455D02*
X1158255D01*
G01X1146595Y191205D02*
X1158695D01*
G01X1136150Y195950D02*
X1136997Y195103D01*
G01X1138342Y193758D02*
X1139049Y193051D01*
G01X1140464Y191636D02*
X1141171Y190929D01*
G01X1142586Y189514D02*
X1143293Y188807D01*
G01X1144708Y187392D02*
X1146040Y186060D01*
G01X1135400Y195200D02*
X1145600Y185000D01*
G01X1146040Y186060D02*
X1147040D01*
G01X1149040D02*
X1150100D01*
G01X1152100D02*
X1153600D01*
G01X1155600D02*
X1158840D01*
G01X1145600Y185000D02*
X1158400D01*
G01X1137400Y200400D02*
X1146595Y191205D01*
G01X1136650Y199650D02*
X1146155Y190145D01*
G01X1146595Y191205D02*
X1158695D01*
G01X1146155Y190145D02*
X1147818D01*
G01X1146595Y191205D02*
X1158695D01*
G01X1149718Y190145D02*
X1151555D01*
G01X1146595Y191205D02*
X1158695D01*
G01X1153455Y190145D02*
X1158255D01*
G01X1112298Y422000D02*
Y445398D01*
G01X1111238Y422000D02*
Y445838D01*
G01X1112298Y445398D02*
X1141668Y474768D01*
G01X1111238Y445838D02*
X1141228Y475828D01*
G01X1111238Y422000D02*
Y445838D01*
G01X1112298Y422000D02*
Y445398D01*
G01X1111238Y445838D02*
X1141228Y475828D01*
G01X1112298Y445398D02*
X1141668Y474768D01*
G01X1140896Y411515D02*
Y412996D01*
G01X1141956Y411515D02*
Y412556D01*
G01X1140896Y412996D02*
X1152030Y424130D01*
G01X1141956Y412556D02*
X1152470Y423070D01*
G01X1152030Y424130D02*
X1158364D01*
G01X1152470Y423070D02*
X1158804D01*
G01X1116061Y422000D02*
Y444685D01*
G01X1115001Y422000D02*
Y445125D01*
G01X1116061Y444685D02*
X1143098Y471722D01*
G01X1115001Y445125D02*
X1142658Y472782D01*
G01X1145646Y410383D02*
Y411246D01*
G01X1144586Y410383D02*
Y411686D01*
G01X1145646Y411246D02*
X1149460Y415060D01*
G01X1144586Y411686D02*
X1149020Y416120D01*
G01X1149460Y415060D02*
X1150556D01*
G01X1149020Y416120D02*
X1150996D01*
G01X1149460Y415060D02*
X1150556D01*
G01D02*
X1151359Y414257D01*
G01X1150996Y416120D02*
X1151799Y415317D01*
G01X1151359Y414257D02*
X1153618D01*
G01X1151799Y415317D02*
X1153178D01*
G01X1153618Y414257D02*
X1155220Y415859D01*
G01X1153178Y415317D02*
X1154160Y416299D01*
G01X1155220Y415859D02*
Y419361D01*
G01X1154160Y416299D02*
Y419801D01*
G01X1155220Y419361D02*
X1155899Y420040D01*
G01X1154160Y419801D02*
X1155459Y421100D01*
G01X1155899Y420040D02*
X1160692D01*
G01X1155459Y421100D02*
X1160252D01*
G01X1141956Y411515D02*
Y412556D01*
G01X1140896Y411515D02*
Y412996D01*
G01X1141956Y412556D02*
X1152470Y423070D01*
G01X1140896Y412996D02*
X1152030Y424130D01*
G01X1152470Y423070D02*
X1158804D01*
G01X1152030Y424130D02*
X1158364D01*
G01X1115001Y422000D02*
Y445125D01*
G01X1116061Y422000D02*
Y444685D01*
G01X1115001Y445125D02*
X1142658Y472782D01*
G01X1116061Y444685D02*
X1143098Y471722D01*
G01X1144586Y410383D02*
Y411686D01*
G01X1145646Y410383D02*
Y411246D01*
G01X1144586Y411686D02*
X1149020Y416120D01*
G01X1145646Y411246D02*
X1149460Y415060D01*
G01X1149020Y416120D02*
X1150996D01*
G01D02*
X1151799Y415317D01*
G01X1149460Y415060D02*
X1150556D01*
G01X1150996Y416120D02*
X1151799Y415317D01*
G01X1150556Y415060D02*
X1151359Y414257D01*
G01X1151799Y415317D02*
X1153178D01*
G01X1151359Y414257D02*
X1153618D01*
G01X1153178Y415317D02*
X1154160Y416299D01*
G01X1153618Y414257D02*
X1155220Y415859D01*
G01X1154160Y416299D02*
Y419801D01*
G01X1155220Y415859D02*
Y419361D01*
G01X1154160Y419801D02*
X1155459Y421100D01*
G01X1155220Y419361D02*
X1155899Y420040D01*
G01X1155459Y421100D02*
X1160252D01*
G01X1155899Y420040D02*
X1160692D01*
G01X1111238Y422000D02*
Y445838D01*
G01X1112298Y422000D02*
Y445398D01*
G01X1111238Y445838D02*
X1141228Y475828D01*
G01X1112298Y445398D02*
X1141668Y474768D01*
G01X1116061Y422000D02*
Y444685D01*
G01X1115001Y422000D02*
Y445125D01*
G01X1116061Y444685D02*
X1143098Y471722D01*
G01X1115001Y445125D02*
X1142658Y472782D01*
G01X1112298Y422000D02*
Y445398D01*
G01X1111238Y422000D02*
Y445838D01*
G01X1112298Y445398D02*
X1141668Y474768D01*
G01X1111238Y445838D02*
X1141228Y475828D01*
G01X1115001Y422000D02*
Y445125D01*
G01X1116061Y422000D02*
Y444685D01*
G01X1115001Y445125D02*
X1142658Y472782D01*
G01X1116061Y444685D02*
X1143098Y471722D01*
G01X1140896Y411515D02*
Y412996D01*
G01X1141956Y411515D02*
Y412556D01*
G01X1140896Y412996D02*
X1152030Y424130D01*
G01X1141956Y412556D02*
X1152470Y423070D01*
G01X1152030Y424130D02*
X1158364D01*
G01X1152470Y423070D02*
X1158804D01*
G01X1145646Y410383D02*
Y411246D01*
G01X1144586Y410383D02*
Y411686D01*
G01X1145646Y411246D02*
X1149460Y415060D01*
G01X1144586Y411686D02*
X1149020Y416120D01*
G01X1149460Y415060D02*
X1150556D01*
G01X1149020Y416120D02*
X1150996D01*
G01X1149460Y415060D02*
X1150556D01*
G01D02*
X1151359Y414257D01*
G01X1150996Y416120D02*
X1151799Y415317D01*
G01X1151359Y414257D02*
X1153618D01*
G01X1151799Y415317D02*
X1153178D01*
G01X1153618Y414257D02*
X1155220Y415859D01*
G01X1153178Y415317D02*
X1154160Y416299D01*
G01X1155220Y415859D02*
Y419361D01*
G01X1154160Y416299D02*
Y419801D01*
G01X1155220Y419361D02*
X1155899Y420040D01*
G01X1154160Y419801D02*
X1155459Y421100D01*
G01X1155899Y420040D02*
X1160692D01*
G01X1155459Y421100D02*
X1160252D01*
G01X1141956Y411515D02*
Y412556D01*
G01X1140896Y411515D02*
Y412996D01*
G01X1141956Y412556D02*
X1152470Y423070D01*
G01X1140896Y412996D02*
X1152030Y424130D01*
G01X1152470Y423070D02*
X1158804D01*
G01X1152030Y424130D02*
X1158364D01*
G01X1144586Y410383D02*
Y411686D01*
G01X1145646Y410383D02*
Y411246D01*
G01X1144586Y411686D02*
X1149020Y416120D01*
G01X1145646Y411246D02*
X1149460Y415060D01*
G01X1149020Y416120D02*
X1150996D01*
G01D02*
X1151799Y415317D01*
G01X1149460Y415060D02*
X1150556D01*
G01X1150996Y416120D02*
X1151799Y415317D01*
G01X1150556Y415060D02*
X1151359Y414257D01*
G01X1151799Y415317D02*
X1153178D01*
G01X1151359Y414257D02*
X1153618D01*
G01X1153178Y415317D02*
X1154160Y416299D01*
G01X1153618Y414257D02*
X1155220Y415859D01*
G01X1154160Y416299D02*
Y419801D01*
G01X1155220Y415859D02*
Y419361D01*
G01X1154160Y419801D02*
X1155459Y421100D01*
G01X1155220Y419361D02*
X1155899Y420040D01*
G01X1155459Y421100D02*
X1160252D01*
G01X1155899Y420040D02*
X1160692D01*
G01X1102949Y479281D02*
Y484030D01*
G01X1104009Y478841D02*
Y483590D01*
G01X1102949Y484030D02*
X1114758Y495840D01*
G01X1104009Y483590D02*
X1115658Y495239D01*
G01X1114758Y495840D02*
X1115559Y497774D01*
G01D02*
X1115950Y498717D01*
G01D02*
X1116361Y499708D01*
G01X1115658Y495239D02*
X1117098Y498717D01*
G01X1115950D02*
X1116361Y499708D01*
G01X1117098Y498717D02*
X1117421Y499497D01*
G01X1116361Y499708D02*
Y563854D01*
G01X1117421Y499497D02*
Y586915D01*
G01X1109569Y479069D02*
Y480811D01*
G01X1108509Y479509D02*
Y480371D01*
G01X1109569Y480811D02*
X1108563Y481817D01*
G01X1108509Y480371D02*
X1107503Y481377D01*
G01X1108563Y481817D02*
Y482677D01*
G01X1107503Y481377D02*
Y483117D01*
G01X1108563Y482677D02*
X1109551Y483665D01*
G01X1107503Y483117D02*
X1109111Y484725D01*
G01X1109551Y483665D02*
X1110411D01*
G01X1109111Y484725D02*
X1110851D01*
G01X1110411Y483665D02*
X1111417Y482659D01*
G01X1110851Y484725D02*
X1111857Y483719D01*
G01X1111417Y482659D02*
X1113159D01*
G01X1111857Y483719D02*
X1112719D01*
G01X1113159Y482659D02*
X1114763Y484263D01*
G01X1112719Y483719D02*
X1113703Y484703D01*
G01X1114763Y484263D02*
Y486005D01*
G01X1113703Y484703D02*
Y485565D01*
G01X1114763Y486005D02*
X1113646Y487122D01*
G01X1113703Y485565D02*
X1112586Y486682D01*
G01X1113646Y487122D02*
Y487941D01*
G01X1112586Y486682D02*
Y488381D01*
G01X1113646Y487941D02*
X1114634Y488929D01*
G01X1112586Y488381D02*
X1114194Y489989D01*
G01X1114634Y488929D02*
X1115535D01*
G01X1114194Y489989D02*
X1115975D01*
G01X1115535Y488929D02*
X1116611Y487853D01*
G01X1115975Y489989D02*
X1117051Y488913D01*
G01X1116611Y487853D02*
X1118353D01*
G01X1117051Y488913D02*
X1117913D01*
G01X1118353Y487853D02*
X1121055Y490555D01*
G01X1117913Y488913D02*
X1119995Y490995D01*
G01X1121055Y490555D02*
Y508355D01*
G01X1119995Y490995D02*
Y508795D01*
G01X1121055Y508355D02*
X1122521Y509821D01*
G01X1119995Y508795D02*
X1121461Y510261D01*
G01X1122521Y509821D02*
Y588034D01*
G01X1121461Y510261D02*
Y576231D01*
G01X1122521Y509821D02*
Y588034D01*
G01Y509821D02*
Y588034D01*
G01Y509821D02*
Y588034D01*
G01X1104009Y478841D02*
Y483590D01*
G01X1102949Y479281D02*
Y484030D01*
G01X1104009Y483590D02*
X1115658Y495239D01*
G01X1102949Y484030D02*
X1114758Y495840D01*
G01X1115658Y495239D02*
X1117098Y498717D01*
G01X1114758Y495840D02*
X1115559Y497774D01*
G01X1115658Y495239D02*
X1117098Y498717D01*
G01X1115559Y497774D02*
X1115950Y498717D01*
G01X1115658Y495239D02*
X1117098Y498717D01*
G01D02*
X1117421Y499497D01*
G01X1115950Y498717D02*
X1116361Y499708D01*
G01X1117421Y499497D02*
Y586915D01*
G01X1116361Y499708D02*
Y563854D01*
G01X1117421Y499497D02*
Y586915D01*
G01Y499497D02*
Y586915D01*
G01Y499497D02*
Y586915D01*
G01Y499497D02*
Y586915D01*
G01X1141668Y474768D02*
X1176391D01*
G01X1141228Y475828D02*
X1175951D01*
G01X1108509Y479509D02*
Y480371D01*
G01X1109569Y479069D02*
Y480811D01*
G01X1108509Y480371D02*
X1107503Y481377D01*
G01X1109569Y480811D02*
X1108563Y481817D01*
G01X1107503Y481377D02*
Y483117D01*
G01X1108563Y481817D02*
Y482677D01*
G01X1107503Y483117D02*
X1109111Y484725D01*
G01X1108563Y482677D02*
X1109551Y483665D01*
G01X1109111Y484725D02*
X1110851D01*
G01X1109551Y483665D02*
X1110411D01*
G01X1110851Y484725D02*
X1111857Y483719D01*
G01X1110411Y483665D02*
X1111417Y482659D01*
G01X1111857Y483719D02*
X1112719D01*
G01X1111417Y482659D02*
X1113159D01*
G01X1112719Y483719D02*
X1113703Y484703D01*
G01X1113159Y482659D02*
X1114763Y484263D01*
G01X1113703Y484703D02*
Y485565D01*
G01X1114763Y484263D02*
Y486005D01*
G01X1113703Y485565D02*
X1112586Y486682D01*
G01X1114763Y486005D02*
X1113646Y487122D01*
G01X1112586Y486682D02*
Y488381D01*
G01X1113646Y487122D02*
Y487941D01*
G01X1112586Y488381D02*
X1114194Y489989D01*
G01X1113646Y487941D02*
X1114634Y488929D01*
G01X1114194Y489989D02*
X1115975D01*
G01X1114634Y488929D02*
X1115535D01*
G01X1115975Y489989D02*
X1117051Y488913D01*
G01X1115535Y488929D02*
X1116611Y487853D01*
G01X1117051Y488913D02*
X1117913D01*
G01X1116611Y487853D02*
X1118353D01*
G01X1117913Y488913D02*
X1119995Y490995D01*
G01X1118353Y487853D02*
X1121055Y490555D01*
G01X1119995Y490995D02*
Y508795D01*
G01X1121055Y490555D02*
Y508355D01*
G01X1119995Y508795D02*
X1121461Y510261D01*
G01X1121055Y508355D02*
X1122521Y509821D01*
G01X1121461Y510261D02*
Y576231D01*
G01X1122521Y509821D02*
Y588034D01*
G01X1141228Y475828D02*
X1175951D01*
G01X1141668Y474768D02*
X1176391D01*
G01X1143098Y471722D02*
X1159615D01*
G01X1142658Y472782D02*
X1160055D01*
G01X1142658D02*
X1160055D01*
G01X1143098Y471722D02*
X1159615D01*
G01X1153172Y548674D02*
Y505072D01*
G01X1154232Y549114D02*
Y504632D01*
G01X1153172Y505072D02*
X1151440Y503340D01*
G01X1154232Y504632D02*
X1152500Y502900D01*
G01X1151440Y503340D02*
Y501940D01*
G01X1152500Y502900D02*
Y500400D01*
G01X1158272Y505073D02*
X1156040Y502841D01*
G01D02*
Y501040D01*
G01X1154232Y549114D02*
Y504632D01*
G01X1153172Y548674D02*
Y505072D01*
G01X1154232Y504632D02*
X1152500Y502900D01*
G01X1153172Y505072D02*
X1151440Y503340D01*
G01X1152500Y502900D02*
Y500400D01*
G01X1151440Y503340D02*
Y501940D01*
G01X1158272Y505073D02*
X1156040Y502841D01*
G01D02*
Y501040D01*
G01X1102949Y479281D02*
Y484030D01*
G01X1104009Y478841D02*
Y483590D01*
G01X1102949Y484030D02*
X1114758Y495840D01*
G01X1104009Y483590D02*
X1115658Y495239D01*
G01X1114758Y495840D02*
X1115559Y497774D01*
G01D02*
X1115950Y498717D01*
G01D02*
X1116361Y499708D01*
G01X1115658Y495239D02*
X1117098Y498717D01*
G01X1115950D02*
X1116361Y499708D01*
G01X1117098Y498717D02*
X1117421Y499497D01*
G01X1116361Y499708D02*
Y563854D01*
G01X1117421Y499497D02*
Y586915D01*
G01X1102949Y479281D02*
Y484030D01*
G01X1104009Y478841D02*
Y483590D01*
G01X1102949Y484030D02*
X1114758Y495840D01*
G01X1104009Y483590D02*
X1115658Y495239D01*
G01X1114758Y495840D02*
X1115559Y497774D01*
G01D02*
X1115950Y498717D01*
G01D02*
X1116361Y499708D01*
G01X1115658Y495239D02*
X1117098Y498717D01*
G01X1115950D02*
X1116361Y499708D01*
G01X1117098Y498717D02*
X1117421Y499497D01*
G01X1116361Y499708D02*
Y563854D01*
G01X1117421Y499497D02*
Y586915D01*
G01X1109569Y479069D02*
Y480811D01*
G01X1108509Y479509D02*
Y480371D01*
G01X1109569Y480811D02*
X1108563Y481817D01*
G01X1108509Y480371D02*
X1107503Y481377D01*
G01X1108563Y481817D02*
Y482677D01*
G01X1107503Y481377D02*
Y483117D01*
G01X1108563Y482677D02*
X1109551Y483665D01*
G01X1107503Y483117D02*
X1109111Y484725D01*
G01X1109551Y483665D02*
X1110411D01*
G01X1109111Y484725D02*
X1110851D01*
G01X1110411Y483665D02*
X1111417Y482659D01*
G01X1110851Y484725D02*
X1111857Y483719D01*
G01X1111417Y482659D02*
X1113159D01*
G01X1111857Y483719D02*
X1112719D01*
G01X1113159Y482659D02*
X1114763Y484263D01*
G01X1112719Y483719D02*
X1113703Y484703D01*
G01X1114763Y484263D02*
Y486005D01*
G01X1113703Y484703D02*
Y485565D01*
G01X1114763Y486005D02*
X1113646Y487122D01*
G01X1113703Y485565D02*
X1112586Y486682D01*
G01X1113646Y487122D02*
Y487941D01*
G01X1112586Y486682D02*
Y488381D01*
G01X1113646Y487941D02*
X1114634Y488929D01*
G01X1112586Y488381D02*
X1114194Y489989D01*
G01X1114634Y488929D02*
X1115535D01*
G01X1114194Y489989D02*
X1115975D01*
G01X1115535Y488929D02*
X1116611Y487853D01*
G01X1115975Y489989D02*
X1117051Y488913D01*
G01X1116611Y487853D02*
X1118353D01*
G01X1117051Y488913D02*
X1117913D01*
G01X1118353Y487853D02*
X1121055Y490555D01*
G01X1117913Y488913D02*
X1119995Y490995D01*
G01X1121055Y490555D02*
Y508355D01*
G01X1119995Y490995D02*
Y508795D01*
G01X1121055Y508355D02*
X1122521Y509821D01*
G01X1119995Y508795D02*
X1121461Y510261D01*
G01X1122521Y509821D02*
Y588034D01*
G01X1121461Y510261D02*
Y576231D01*
G01X1122521Y509821D02*
Y588034D01*
G01Y509821D02*
Y588034D01*
G01Y509821D02*
Y588034D01*
G01X1104009Y478841D02*
Y483590D01*
G01X1102949Y479281D02*
Y484030D01*
G01X1104009Y483590D02*
X1115658Y495239D01*
G01X1102949Y484030D02*
X1114758Y495840D01*
G01X1115658Y495239D02*
X1117098Y498717D01*
G01X1114758Y495840D02*
X1115559Y497774D01*
G01X1115658Y495239D02*
X1117098Y498717D01*
G01X1115559Y497774D02*
X1115950Y498717D01*
G01X1115658Y495239D02*
X1117098Y498717D01*
G01D02*
X1117421Y499497D01*
G01X1115950Y498717D02*
X1116361Y499708D01*
G01X1117421Y499497D02*
Y586915D01*
G01X1116361Y499708D02*
Y563854D01*
G01X1117421Y499497D02*
Y586915D01*
G01Y499497D02*
Y586915D01*
G01Y499497D02*
Y586915D01*
G01Y499497D02*
Y586915D01*
G01X1108509Y479509D02*
Y480371D01*
G01X1109569Y479069D02*
Y480811D01*
G01X1108509Y480371D02*
X1107503Y481377D01*
G01X1109569Y480811D02*
X1108563Y481817D01*
G01X1107503Y481377D02*
Y483117D01*
G01X1108563Y481817D02*
Y482677D01*
G01X1107503Y483117D02*
X1109111Y484725D01*
G01X1108563Y482677D02*
X1109551Y483665D01*
G01X1109111Y484725D02*
X1110851D01*
G01X1109551Y483665D02*
X1110411D01*
G01X1110851Y484725D02*
X1111857Y483719D01*
G01X1110411Y483665D02*
X1111417Y482659D01*
G01X1111857Y483719D02*
X1112719D01*
G01X1111417Y482659D02*
X1113159D01*
G01X1112719Y483719D02*
X1113703Y484703D01*
G01X1113159Y482659D02*
X1114763Y484263D01*
G01X1113703Y484703D02*
Y485565D01*
G01X1114763Y484263D02*
Y486005D01*
G01X1113703Y485565D02*
X1112586Y486682D01*
G01X1114763Y486005D02*
X1113646Y487122D01*
G01X1112586Y486682D02*
Y488381D01*
G01X1113646Y487122D02*
Y487941D01*
G01X1112586Y488381D02*
X1114194Y489989D01*
G01X1113646Y487941D02*
X1114634Y488929D01*
G01X1114194Y489989D02*
X1115975D01*
G01X1114634Y488929D02*
X1115535D01*
G01X1115975Y489989D02*
X1117051Y488913D01*
G01X1115535Y488929D02*
X1116611Y487853D01*
G01X1117051Y488913D02*
X1117913D01*
G01X1116611Y487853D02*
X1118353D01*
G01X1117913Y488913D02*
X1119995Y490995D01*
G01X1118353Y487853D02*
X1121055Y490555D01*
G01X1119995Y490995D02*
Y508795D01*
G01X1121055Y490555D02*
Y508355D01*
G01X1119995Y508795D02*
X1121461Y510261D01*
G01X1121055Y508355D02*
X1122521Y509821D01*
G01X1121461Y510261D02*
Y576231D01*
G01X1122521Y509821D02*
Y588034D01*
G01X1141228Y475828D02*
X1175951D01*
G01X1141668Y474768D02*
X1176391D01*
G01X1143098Y471722D02*
X1159615D01*
G01X1142658Y472782D02*
X1160055D01*
G01X1141668Y474768D02*
X1176391D01*
G01X1141228Y475828D02*
X1175951D01*
G01X1142658Y472782D02*
X1160055D01*
G01X1143098Y471722D02*
X1159615D01*
G01X1116361Y565758D02*
Y576050D01*
G01Y578038D02*
Y579164D01*
G01Y581404D02*
Y582404D01*
G01Y584644D02*
Y586474D01*
G01D02*
X1114535Y588300D01*
G01X1117421Y586915D02*
X1116341Y587995D01*
G01X1121461Y578471D02*
Y579471D01*
G01Y581711D02*
Y582711D01*
G01Y584951D02*
Y587594D01*
G01X1122521Y588034D02*
X1119441Y591114D01*
G01X1121461Y587594D02*
X1120541Y588514D01*
G01X1116361Y565758D02*
Y576050D01*
G01Y578038D02*
Y579164D01*
G01Y581404D02*
Y582404D01*
G01Y584644D02*
Y586474D01*
G01X1117421Y586915D02*
X1116341Y587995D01*
G01X1116361Y586474D02*
X1114535Y588300D01*
G01X1121461Y578471D02*
Y579471D01*
G01Y581711D02*
Y582711D01*
G01Y584951D02*
Y587594D01*
G01D02*
X1120541Y588514D01*
G01X1122521Y588034D02*
X1119441Y591114D01*
G01X1151346Y550500D02*
X1153172Y548674D01*
G01X1152900Y550446D02*
X1154232Y549114D01*
G01X1156986Y550714D02*
X1158272Y549428D01*
G01X1152900Y550446D02*
X1154232Y549114D01*
G01X1151346Y550500D02*
X1153172Y548674D01*
G01X1156986Y550714D02*
X1158272Y549428D01*
G01X1116361Y565758D02*
Y576050D01*
G01Y578038D02*
Y579164D01*
G01Y581404D02*
Y582404D01*
G01Y584644D02*
Y586474D01*
G01D02*
X1114535Y588300D01*
G01X1117421Y586915D02*
X1116341Y587995D01*
G01X1116361Y565758D02*
Y576050D01*
G01Y578038D02*
Y579164D01*
G01Y581404D02*
Y582404D01*
G01Y584644D02*
Y586474D01*
G01D02*
X1114535Y588300D01*
G01X1117421Y586915D02*
X1116341Y587995D01*
G01X1121461Y578471D02*
Y579471D01*
G01Y581711D02*
Y582711D01*
G01Y584951D02*
Y587594D01*
G01X1122521Y588034D02*
X1119441Y591114D01*
G01X1121461Y587594D02*
X1120541Y588514D01*
G01X1116361Y565758D02*
Y576050D01*
G01Y578038D02*
Y579164D01*
G01Y581404D02*
Y582404D01*
G01Y584644D02*
Y586474D01*
G01X1117421Y586915D02*
X1116341Y587995D01*
G01X1116361Y586474D02*
X1114535Y588300D01*
G01X1121461Y578471D02*
Y579471D01*
G01Y581711D02*
Y582711D01*
G01Y584951D02*
Y587594D01*
G01D02*
X1120541Y588514D01*
G01X1122521Y588034D02*
X1119441Y591114D01*
G01X1112353Y590000D02*
Y608012D01*
G01X1113413Y602360D02*
Y600940D01*
G01X1112353Y590000D02*
Y608012D01*
G01X1113413Y597260D02*
Y595890D01*
G01X1118637Y595500D02*
X1117966Y596171D01*
G01X1117735Y594901D02*
X1116906Y595730D01*
G01X1117966Y596171D02*
Y597448D01*
G01Y600938D02*
Y601829D01*
G01X1116906Y595730D02*
Y602270D01*
G01X1117966Y601829D02*
X1118737Y602600D01*
G01X1116906Y602270D02*
X1117735Y603099D01*
G01X1113413Y602360D02*
Y600940D01*
G01Y597260D02*
Y595890D01*
G01X1112353Y590000D02*
Y608012D01*
G01X1117735Y594901D02*
X1116906Y595730D01*
G01X1118637Y595500D02*
X1117966Y596171D01*
G01X1116906Y595730D02*
Y602270D01*
G01X1117966Y596171D02*
Y597448D01*
G01X1116906Y595730D02*
Y602270D01*
G01X1117966Y600938D02*
Y601829D01*
G01X1116906Y602270D02*
X1117735Y603099D01*
G01X1117966Y601829D02*
X1118737Y602600D01*
G01X1112353Y590000D02*
Y608012D01*
G01X1113413Y602360D02*
Y600940D01*
G01X1112353Y590000D02*
Y608012D01*
G01X1113413Y597260D02*
Y595890D01*
G01X1112353Y590000D02*
Y608012D01*
G01X1113413Y602360D02*
Y600940D01*
G01X1112353Y590000D02*
Y608012D01*
G01X1113413Y597260D02*
Y595890D01*
G01X1149164Y590000D02*
Y608011D01*
G01X1150224Y595890D02*
Y597260D01*
G01X1149164Y590000D02*
Y608011D01*
G01X1150224Y600940D02*
Y602360D01*
G01X1118637Y595500D02*
X1117966Y596171D01*
G01X1117735Y594901D02*
X1116906Y595730D01*
G01X1117966Y596171D02*
Y597448D01*
G01Y600938D02*
Y601829D01*
G01X1116906Y595730D02*
Y602270D01*
G01X1117966Y601829D02*
X1118737Y602600D01*
G01X1116906Y602270D02*
X1117735Y603099D01*
G01X1155448Y595500D02*
X1154777Y596171D01*
G01X1154546Y594901D02*
X1153717Y595730D01*
G01X1154777Y596171D02*
Y597448D01*
G01Y600938D02*
Y601829D01*
G01X1153717Y595730D02*
Y602270D01*
G01X1154777Y601829D02*
X1155548Y602600D01*
G01X1153717Y602270D02*
X1154546Y603099D01*
G01X1113413Y602360D02*
Y600940D01*
G01Y597260D02*
Y595890D01*
G01X1112353Y590000D02*
Y608012D01*
G01X1150224Y595890D02*
Y597260D01*
G01Y600940D02*
Y602360D01*
G01X1149164Y590000D02*
Y608011D01*
G01X1117735Y594901D02*
X1116906Y595730D01*
G01X1118637Y595500D02*
X1117966Y596171D01*
G01X1116906Y595730D02*
Y602270D01*
G01X1117966Y596171D02*
Y597448D01*
G01X1116906Y595730D02*
Y602270D01*
G01X1117966Y600938D02*
Y601829D01*
G01X1116906Y602270D02*
X1117735Y603099D01*
G01X1117966Y601829D02*
X1118737Y602600D01*
G01X1154546Y594901D02*
X1153717Y595730D01*
G01X1155448Y595500D02*
X1154777Y596171D01*
G01X1153717Y595730D02*
Y602270D01*
G01X1154777Y596171D02*
Y597448D01*
G01X1153717Y595730D02*
Y602270D01*
G01X1154777Y600938D02*
Y601829D01*
G01X1153717Y602270D02*
X1154546Y603099D01*
G01X1154777Y601829D02*
X1155548Y602600D01*
G01X1157350Y11915D02*
X1158384Y10881D01*
G01D02*
Y8106D01*
G01Y4280D02*
Y2907D01*
G01Y-1007D02*
Y-3628D01*
G01X1159444Y11322D02*
Y-4068D01*
G01X1158384Y-3628D02*
X1157361Y-4651D01*
G01X1157350Y11915D02*
X1158384Y10881D01*
G01X1159444Y11322D02*
Y-4068D01*
G01X1158384Y10881D02*
Y8106D01*
G01X1159444Y11322D02*
Y-4068D01*
G01X1158384Y4280D02*
Y2907D01*
G01X1159444Y11322D02*
Y-4068D01*
G01X1158384Y-1007D02*
Y-3628D01*
G01D02*
X1157361Y-4651D01*
G01X1188782Y-5220D02*
X1189298D01*
G01X1188759Y-6280D02*
X1189741D01*
G01X1188782Y-5220D02*
X1189298D01*
G01D02*
X1190009Y-4509D01*
G01X1189741Y-6280D02*
X1191069Y-4952D01*
G01X1190009Y-4509D02*
Y-1220D01*
G01Y3120D02*
Y4080D01*
G01Y8220D02*
Y10753D01*
G01X1191069Y-4952D02*
Y11194D01*
G01X1190009Y10753D02*
X1189062Y11700D01*
G01D02*
X1187963D01*
G01X1191069Y11194D02*
X1187963Y14300D01*
G01X1186109Y13554D02*
Y21879D01*
G01X1187169Y19620D02*
Y21436D01*
G01X1186109Y21879D02*
X1189983Y25753D01*
G01X1187169Y21436D02*
X1191043Y25310D01*
G01X1189983Y25753D02*
Y115388D01*
G01X1191043Y25310D02*
Y36580D01*
G01X1189983Y25753D02*
Y115388D01*
G01Y25753D02*
Y115388D01*
G01Y25753D02*
Y115388D01*
G01X1193063Y-4651D02*
X1194172D01*
G01D02*
X1195195Y-3628D01*
G01X1193063Y-7260D02*
X1196255Y-4068D01*
G01X1195195Y-3628D02*
Y-1007D01*
G01Y2907D02*
Y4280D01*
G01Y8106D02*
Y10881D01*
G01X1196255Y-4068D02*
Y11322D01*
G01X1195195Y10881D02*
X1194161Y11915D01*
G01D02*
X1193063D01*
G01X1196255Y11322D02*
X1193063Y14514D01*
G01X1191309Y13668D02*
Y21038D01*
G01X1192369Y19501D02*
Y20598D01*
G01X1191309Y21038D02*
X1195220Y24949D01*
G01X1192369Y20598D02*
X1194094Y22323D01*
G01X1191309Y21038D02*
X1195220Y24949D01*
G01X1194094Y22323D02*
X1194970D01*
G01X1191309Y21038D02*
X1195220Y24949D01*
G01X1195677Y23906D02*
X1196280Y24509D01*
G01X1195220Y24949D02*
Y115948D01*
G01X1196280Y24509D02*
Y29380D01*
G01X1195220Y24949D02*
Y115948D01*
G01X1196280Y31620D02*
Y116391D01*
G01X1188759Y-6280D02*
X1189741D01*
G01D02*
X1191069Y-4952D01*
G01X1188782Y-5220D02*
X1189298D01*
G01X1189741Y-6280D02*
X1191069Y-4952D01*
G01X1189298Y-5220D02*
X1190009Y-4509D01*
G01X1191069Y-4952D02*
Y11194D01*
G01X1190009Y-4509D02*
Y-1220D01*
G01X1191069Y-4952D02*
Y11194D01*
G01X1190009Y3120D02*
Y4080D01*
G01X1191069Y-4952D02*
Y11194D01*
G01X1190009Y8220D02*
Y10753D01*
G01X1191069Y11194D02*
X1187963Y14300D01*
G01X1190009Y10753D02*
X1189062Y11700D01*
G01X1191069Y11194D02*
X1187963Y14300D01*
G01X1189062Y11700D02*
X1187963D01*
G01X1187169Y19620D02*
Y21436D01*
G01X1186109Y13554D02*
Y21879D01*
G01X1187169Y21436D02*
X1191043Y25310D01*
G01X1186109Y21879D02*
X1189983Y25753D01*
G01X1191043Y25310D02*
Y36580D01*
G01X1189983Y25753D02*
Y115388D01*
G01X1193063Y-7260D02*
X1196255Y-4068D01*
G01X1193063Y-4651D02*
X1194172D01*
G01X1193063Y-7260D02*
X1196255Y-4068D01*
G01X1194172Y-4651D02*
X1195195Y-3628D01*
G01X1196255Y-4068D02*
Y11322D01*
G01X1195195Y-3628D02*
Y-1007D01*
G01X1196255Y-4068D02*
Y11322D01*
G01X1195195Y2907D02*
Y4280D01*
G01X1196255Y-4068D02*
Y11322D01*
G01X1195195Y8106D02*
Y10881D01*
G01X1196255Y11322D02*
X1193063Y14514D01*
G01X1195195Y10881D02*
X1194161Y11915D01*
G01X1196255Y11322D02*
X1193063Y14514D01*
G01X1194161Y11915D02*
X1193063D01*
G01X1192369Y19501D02*
Y20598D01*
G01X1191309Y13668D02*
Y21038D01*
G01X1192369Y20598D02*
X1194094Y22323D01*
G01D02*
X1194970D01*
G01X1195677Y23906D02*
X1196280Y24509D01*
G01X1191309Y21038D02*
X1195220Y24949D01*
G01X1196280Y24509D02*
Y29380D01*
G01Y31620D02*
Y116391D01*
G01X1195220Y24949D02*
Y115948D01*
G01X1188782Y-5220D02*
X1189298D01*
G01X1188759Y-6280D02*
X1189741D01*
G01X1188782Y-5220D02*
X1189298D01*
G01D02*
X1190009Y-4509D01*
G01X1189741Y-6280D02*
X1191069Y-4952D01*
G01X1190009Y-4509D02*
Y-1220D01*
G01Y3120D02*
Y4080D01*
G01Y8220D02*
Y10753D01*
G01X1191069Y-4952D02*
Y11194D01*
G01X1190009Y10753D02*
X1189062Y11700D01*
G01D02*
X1187963D01*
G01X1191069Y11194D02*
X1187963Y14300D01*
G01X1186109Y13554D02*
Y21879D01*
G01X1187169Y19620D02*
Y21436D01*
G01X1186109Y21879D02*
X1189983Y25753D01*
G01X1187169Y21436D02*
X1191043Y25310D01*
G01X1189983Y25753D02*
Y115388D01*
G01X1191043Y25310D02*
Y36580D01*
G01X1189983Y25753D02*
Y115388D01*
G01Y25753D02*
Y115388D01*
G01Y25753D02*
Y115388D01*
G01X1193063Y-4651D02*
X1194172D01*
G01D02*
X1195195Y-3628D01*
G01X1193063Y-7260D02*
X1196255Y-4068D01*
G01X1195195Y-3628D02*
Y-1007D01*
G01Y2907D02*
Y4280D01*
G01Y8106D02*
Y10881D01*
G01X1196255Y-4068D02*
Y11322D01*
G01X1195195Y10881D02*
X1194161Y11915D01*
G01D02*
X1193063D01*
G01X1196255Y11322D02*
X1193063Y14514D01*
G01X1191309Y13668D02*
Y21038D01*
G01X1192369Y19501D02*
Y20598D01*
G01X1191309Y21038D02*
X1195220Y24949D01*
G01X1192369Y20598D02*
X1194094Y22323D01*
G01X1191309Y21038D02*
X1195220Y24949D01*
G01X1194094Y22323D02*
X1194970D01*
G01X1191309Y21038D02*
X1195220Y24949D01*
G01X1195677Y23906D02*
X1196280Y24509D01*
G01X1195220Y24949D02*
Y115948D01*
G01X1196280Y24509D02*
Y29380D01*
G01X1195220Y24949D02*
Y115948D01*
G01X1196280Y31620D02*
Y116391D01*
G01X1188759Y-6280D02*
X1189741D01*
G01D02*
X1191069Y-4952D01*
G01X1188782Y-5220D02*
X1189298D01*
G01X1189741Y-6280D02*
X1191069Y-4952D01*
G01X1189298Y-5220D02*
X1190009Y-4509D01*
G01X1191069Y-4952D02*
Y11194D01*
G01X1190009Y-4509D02*
Y-1220D01*
G01X1191069Y-4952D02*
Y11194D01*
G01X1190009Y3120D02*
Y4080D01*
G01X1191069Y-4952D02*
Y11194D01*
G01X1190009Y8220D02*
Y10753D01*
G01X1191069Y11194D02*
X1187963Y14300D01*
G01X1190009Y10753D02*
X1189062Y11700D01*
G01X1191069Y11194D02*
X1187963Y14300D01*
G01X1189062Y11700D02*
X1187963D01*
G01X1187169Y19620D02*
Y21436D01*
G01X1186109Y13554D02*
Y21879D01*
G01X1187169Y21436D02*
X1191043Y25310D01*
G01X1186109Y21879D02*
X1189983Y25753D01*
G01X1191043Y25310D02*
Y36580D01*
G01X1189983Y25753D02*
Y115388D01*
G01X1193063Y-7260D02*
X1196255Y-4068D01*
G01X1193063Y-4651D02*
X1194172D01*
G01X1193063Y-7260D02*
X1196255Y-4068D01*
G01X1194172Y-4651D02*
X1195195Y-3628D01*
G01X1196255Y-4068D02*
Y11322D01*
G01X1195195Y-3628D02*
Y-1007D01*
G01X1196255Y-4068D02*
Y11322D01*
G01X1195195Y2907D02*
Y4280D01*
G01X1196255Y-4068D02*
Y11322D01*
G01X1195195Y8106D02*
Y10881D01*
G01X1196255Y11322D02*
X1193063Y14514D01*
G01X1195195Y10881D02*
X1194161Y11915D01*
G01X1196255Y11322D02*
X1193063Y14514D01*
G01X1194161Y11915D02*
X1193063D01*
G01X1192369Y19501D02*
Y20598D01*
G01X1191309Y13668D02*
Y21038D01*
G01X1192369Y20598D02*
X1194094Y22323D01*
G01D02*
X1194970D01*
G01X1195677Y23906D02*
X1196280Y24509D01*
G01X1191309Y21038D02*
X1195220Y24949D01*
G01X1196280Y24509D02*
Y29380D01*
G01Y31620D02*
Y116391D01*
G01X1195220Y24949D02*
Y115948D01*
G01X1157369Y56620D02*
Y57749D01*
G01D02*
X1159269Y59649D01*
G01X1158209Y60092D02*
Y105698D01*
G01X1159269Y59649D02*
Y107247D01*
G01X1157361Y33149D02*
X1158384Y34172D01*
G01D02*
Y36793D01*
G01Y40707D02*
Y42080D01*
G01Y45906D02*
Y48681D01*
G01X1159444Y33732D02*
Y49121D01*
G01X1158384Y48681D02*
X1157350Y49715D01*
G01X1157369Y56620D02*
Y57749D01*
G01D02*
X1159269Y59649D01*
G01D02*
Y107247D01*
G01X1158209Y60092D02*
Y105698D01*
G01X1157361Y33149D02*
X1158384Y34172D01*
G01X1159444Y33732D02*
Y49121D01*
G01X1158384Y34172D02*
Y36793D01*
G01X1159444Y33732D02*
Y49121D01*
G01X1158384Y40707D02*
Y42080D01*
G01X1159444Y33732D02*
Y49121D01*
G01X1158384Y45906D02*
Y48681D01*
G01D02*
X1157350Y49715D01*
G01X1157369Y56620D02*
Y57749D01*
G01D02*
X1159269Y59649D01*
G01D02*
Y107247D01*
G01X1158209Y60092D02*
Y105698D01*
G01X1157361Y33149D02*
X1158384Y34172D01*
G01X1159444Y33732D02*
Y49121D01*
G01X1158384Y34172D02*
Y36793D01*
G01X1159444Y33732D02*
Y49121D01*
G01X1158384Y40707D02*
Y42080D01*
G01X1159444Y33732D02*
Y49121D01*
G01X1158384Y45906D02*
Y48681D01*
G01D02*
X1157350Y49715D01*
G01X1157369Y56620D02*
Y57749D01*
G01D02*
X1159269Y59649D01*
G01D02*
Y107247D01*
G01X1158209Y60092D02*
Y105698D01*
G01X1157361Y33149D02*
X1158384Y34172D01*
G01X1159444Y33732D02*
Y49121D01*
G01X1158384Y34172D02*
Y36793D01*
G01X1159444Y33732D02*
Y49121D01*
G01X1158384Y40707D02*
Y42080D01*
G01X1159444Y33732D02*
Y49121D01*
G01X1158384Y45906D02*
Y48681D01*
G01D02*
X1157350Y49715D01*
G01X1157369Y56620D02*
Y57749D01*
G01D02*
X1159269Y59649D01*
G01X1158209Y60092D02*
Y105698D01*
G01X1159269Y59649D02*
Y107247D01*
G01X1157361Y33149D02*
X1158384Y34172D01*
G01D02*
Y36793D01*
G01Y40707D02*
Y42080D01*
G01Y45906D02*
Y48681D01*
G01X1159444Y33732D02*
Y49121D01*
G01X1158384Y48681D02*
X1157350Y49715D01*
G01X1191043Y38820D02*
Y39580D01*
G01Y41820D02*
Y42580D01*
G01Y44820D02*
Y115828D01*
G01Y38820D02*
Y39580D01*
G01Y41820D02*
Y42580D01*
G01Y44820D02*
Y115828D01*
G01Y38820D02*
Y39580D01*
G01Y41820D02*
Y42580D01*
G01Y44820D02*
Y115828D01*
G01Y38820D02*
Y39580D01*
G01Y41820D02*
Y42580D01*
G01Y44820D02*
Y115828D01*
G01X1189983Y115388D02*
X1167751Y137620D01*
G01X1191043Y115828D02*
X1168191Y138680D01*
G01X1167751Y137620D02*
X1165069D01*
G01X1168191Y138680D02*
X1164629D01*
G01X1165069Y137620D02*
X1164568Y137119D01*
G01X1164629Y138680D02*
X1163508Y137559D01*
G01X1164568Y137119D02*
Y134840D01*
G01X1163508Y137559D02*
Y135280D01*
G01X1164568Y134840D02*
X1163448Y133720D01*
G01X1163508Y135280D02*
X1163008Y134780D01*
G01X1163448Y133720D02*
X1159697D01*
G01X1163008Y134780D02*
X1160140D01*
G01X1159697Y133720D02*
X1158208Y135209D01*
G01X1160140Y134780D02*
X1159268Y135652D01*
G01X1158208Y135209D02*
Y136748D01*
G01X1159268Y135652D02*
Y137191D01*
G01X1158208Y136748D02*
X1157336Y137620D01*
G01X1159268Y137191D02*
X1157779Y138680D01*
G01X1195220Y115948D02*
X1169748Y141420D01*
G01X1196280Y116391D02*
X1170191Y142480D01*
G01X1191043Y115828D02*
X1168191Y138680D01*
G01X1189983Y115388D02*
X1167751Y137620D01*
G01X1168191Y138680D02*
X1164629D01*
G01X1167751Y137620D02*
X1165069D01*
G01X1164629Y138680D02*
X1163508Y137559D01*
G01X1165069Y137620D02*
X1164568Y137119D01*
G01X1163508Y137559D02*
Y135280D01*
G01X1164568Y137119D02*
Y134840D01*
G01X1163508Y135280D02*
X1163008Y134780D01*
G01X1164568Y134840D02*
X1163448Y133720D01*
G01X1163008Y134780D02*
X1160140D01*
G01X1163448Y133720D02*
X1159697D01*
G01X1160140Y134780D02*
X1159268Y135652D01*
G01X1159697Y133720D02*
X1158208Y135209D01*
G01X1159268Y135652D02*
Y137191D01*
G01X1158208Y135209D02*
Y136748D01*
G01X1159268Y137191D02*
X1157779Y138680D01*
G01X1158208Y136748D02*
X1157336Y137620D01*
G01X1196280Y116391D02*
X1170191Y142480D01*
G01X1195220Y115948D02*
X1169748Y141420D01*
G01X1186560Y161040D02*
X1224520Y123080D01*
G01X1187000Y162100D02*
X1225580Y123520D01*
G01X1187500Y164500D02*
X1231894Y120106D01*
G01X1187940Y165560D02*
X1232954Y120546D01*
G01X1187000Y162100D02*
X1225580Y123520D01*
G01X1186560Y161040D02*
X1224520Y123080D01*
G01X1187940Y165560D02*
X1232954Y120546D01*
G01X1187500Y164500D02*
X1231894Y120106D01*
G01X1189983Y115388D02*
X1167751Y137620D01*
G01X1191043Y115828D02*
X1168191Y138680D01*
G01X1167751Y137620D02*
X1165069D01*
G01X1168191Y138680D02*
X1164629D01*
G01X1165069Y137620D02*
X1164568Y137119D01*
G01X1164629Y138680D02*
X1163508Y137559D01*
G01X1164568Y137119D02*
Y134840D01*
G01X1163508Y137559D02*
Y135280D01*
G01X1164568Y134840D02*
X1163448Y133720D01*
G01X1163508Y135280D02*
X1163008Y134780D01*
G01X1163448Y133720D02*
X1159697D01*
G01X1163008Y134780D02*
X1160140D01*
G01X1159697Y133720D02*
X1158208Y135209D01*
G01X1160140Y134780D02*
X1159268Y135652D01*
G01X1158208Y135209D02*
Y136748D01*
G01X1159268Y135652D02*
Y137191D01*
G01X1158208Y136748D02*
X1157336Y137620D01*
G01X1159268Y137191D02*
X1157779Y138680D01*
G01X1195220Y115948D02*
X1169748Y141420D01*
G01X1196280Y116391D02*
X1170191Y142480D01*
G01X1191043Y115828D02*
X1168191Y138680D01*
G01X1189983Y115388D02*
X1167751Y137620D01*
G01X1168191Y138680D02*
X1164629D01*
G01X1167751Y137620D02*
X1165069D01*
G01X1164629Y138680D02*
X1163508Y137559D01*
G01X1165069Y137620D02*
X1164568Y137119D01*
G01X1163508Y137559D02*
Y135280D01*
G01X1164568Y137119D02*
Y134840D01*
G01X1163508Y135280D02*
X1163008Y134780D01*
G01X1164568Y134840D02*
X1163448Y133720D01*
G01X1163008Y134780D02*
X1160140D01*
G01X1163448Y133720D02*
X1159697D01*
G01X1160140Y134780D02*
X1159268Y135652D01*
G01X1159697Y133720D02*
X1158208Y135209D01*
G01X1159268Y135652D02*
Y137191D01*
G01X1158208Y135209D02*
Y136748D01*
G01X1159268Y137191D02*
X1157779Y138680D01*
G01X1158208Y136748D02*
X1157336Y137620D01*
G01X1196280Y116391D02*
X1170191Y142480D01*
G01X1195220Y115948D02*
X1169748Y141420D01*
G01X1186560Y161040D02*
X1224520Y123080D01*
G01X1187000Y162100D02*
X1225580Y123520D01*
G01X1187500Y164500D02*
X1231894Y120106D01*
G01X1187940Y165560D02*
X1232954Y120546D01*
G01X1187000Y162100D02*
X1225580Y123520D01*
G01X1186560Y161040D02*
X1224520Y123080D01*
G01X1187940Y165560D02*
X1232954Y120546D01*
G01X1187500Y164500D02*
X1231894Y120106D01*
G01X1158400Y185000D02*
X1163365Y180035D01*
G01X1158840Y186060D02*
X1159742Y185158D01*
G01X1158400Y185000D02*
X1163365Y180035D01*
G01X1161158Y183742D02*
X1161992Y182908D01*
G01X1158400Y185000D02*
X1163365Y180035D01*
G01X1163408Y181492D02*
X1164115Y180785D01*
G01X1163365Y180033D02*
X1182360Y161040D01*
G01X1164115Y180783D02*
X1182800Y162100D01*
G01X1182360Y161040D02*
X1186560D01*
G01X1182800Y162100D02*
X1187000D01*
G01X1158255Y190145D02*
X1183900Y164500D01*
G01X1158695Y191205D02*
X1184340Y165560D01*
G01X1183900Y164500D02*
X1187500D01*
G01X1184340Y165560D02*
X1187940D01*
G01X1158840Y186060D02*
X1159742Y185158D01*
G01X1161158Y183742D02*
X1161992Y182908D01*
G01X1163408Y181492D02*
X1164115Y180785D01*
G01X1158400Y185000D02*
X1163365Y180035D01*
G01X1164115Y180783D02*
X1182800Y162100D01*
G01X1163365Y180033D02*
X1182360Y161040D01*
G01X1182800Y162100D02*
X1187000D01*
G01X1182360Y161040D02*
X1186560D01*
G01X1158695Y191205D02*
X1184340Y165560D01*
G01X1158255Y190145D02*
X1183900Y164500D01*
G01X1184340Y165560D02*
X1187940D01*
G01X1183900Y164500D02*
X1187500D01*
G01X1158400Y185000D02*
X1163365Y180035D01*
G01X1158840Y186060D02*
X1159742Y185158D01*
G01X1158400Y185000D02*
X1163365Y180035D01*
G01X1161158Y183742D02*
X1161992Y182908D01*
G01X1158400Y185000D02*
X1163365Y180035D01*
G01X1163408Y181492D02*
X1164115Y180785D01*
G01X1163365Y180033D02*
X1182360Y161040D01*
G01X1164115Y180783D02*
X1182800Y162100D01*
G01X1182360Y161040D02*
X1186560D01*
G01X1182800Y162100D02*
X1187000D01*
G01X1158255Y190145D02*
X1183900Y164500D01*
G01X1158695Y191205D02*
X1184340Y165560D01*
G01X1183900Y164500D02*
X1187500D01*
G01X1184340Y165560D02*
X1187940D01*
G01X1158840Y186060D02*
X1159742Y185158D01*
G01X1161158Y183742D02*
X1161992Y182908D01*
G01X1163408Y181492D02*
X1164115Y180785D01*
G01X1158400Y185000D02*
X1163365Y180035D01*
G01X1164115Y180783D02*
X1182800Y162100D01*
G01X1163365Y180033D02*
X1182360Y161040D01*
G01X1182800Y162100D02*
X1187000D01*
G01X1182360Y161040D02*
X1186560D01*
G01X1158695Y191205D02*
X1184340Y165560D01*
G01X1158255Y190145D02*
X1183900Y164500D01*
G01X1184340Y165560D02*
X1187940D01*
G01X1183900Y164500D02*
X1187500D01*
G01X1158364Y424130D02*
X1172067Y437833D01*
G01X1158804Y423070D02*
X1173127Y437393D01*
G01X1172067Y437833D02*
Y444110D01*
G01X1173127Y437393D02*
Y443670D01*
G01X1172067Y444110D02*
X1173837Y445880D01*
G01X1173127Y443670D02*
X1174277Y444820D01*
G01X1173837Y445880D02*
X1187108D01*
G01X1174277Y444820D02*
X1187548D01*
G01X1187108Y445880D02*
X1226794Y485566D01*
G01X1187548Y444820D02*
X1227854Y485126D01*
G01X1160692Y420040D02*
X1176839Y436187D01*
G01X1160252Y421100D02*
X1175779Y436627D01*
G01X1176839Y436187D02*
Y441164D01*
G01X1175779Y436627D02*
Y441604D01*
G01X1176839Y441164D02*
X1177421Y441746D01*
G01X1175779Y441604D02*
X1176981Y442806D01*
G01X1177421Y441746D02*
X1178811D01*
G01X1176981Y442806D02*
X1179251D01*
G01X1178811Y441746D02*
X1179449Y441108D01*
G01X1179251Y442806D02*
X1180509Y441548D01*
G01X1179449Y441108D02*
Y438984D01*
G01X1180509Y441548D02*
Y439424D01*
G01X1179449Y438984D02*
X1180767Y437666D01*
G01X1180509Y439424D02*
X1181207Y438726D01*
G01X1180767Y437666D02*
X1185645D01*
G01X1181207Y438726D02*
X1185205D01*
G01X1185645Y437666D02*
X1232954Y484975D01*
G01X1185205Y438726D02*
X1231894Y485415D01*
G01X1158804Y423070D02*
X1173127Y437393D01*
G01X1158364Y424130D02*
X1172067Y437833D01*
G01X1173127Y437393D02*
Y443670D01*
G01X1172067Y437833D02*
Y444110D01*
G01X1173127Y443670D02*
X1174277Y444820D01*
G01X1172067Y444110D02*
X1173837Y445880D01*
G01X1174277Y444820D02*
X1187548D01*
G01X1173837Y445880D02*
X1187108D01*
G01X1187548Y444820D02*
X1227854Y485126D01*
G01X1187108Y445880D02*
X1226794Y485566D01*
G01X1160252Y421100D02*
X1175779Y436627D01*
G01X1160692Y420040D02*
X1176839Y436187D01*
G01X1175779Y436627D02*
Y441604D01*
G01X1176839Y436187D02*
Y441164D01*
G01X1175779Y441604D02*
X1176981Y442806D01*
G01X1176839Y441164D02*
X1177421Y441746D01*
G01X1176981Y442806D02*
X1179251D01*
G01X1177421Y441746D02*
X1178811D01*
G01X1179251Y442806D02*
X1180509Y441548D01*
G01X1178811Y441746D02*
X1179449Y441108D01*
G01X1180509Y441548D02*
Y439424D01*
G01X1179449Y441108D02*
Y438984D01*
G01X1180509Y439424D02*
X1181207Y438726D01*
G01X1179449Y438984D02*
X1180767Y437666D01*
G01X1181207Y438726D02*
X1185205D01*
G01X1180767Y437666D02*
X1185645D01*
G01X1185205Y438726D02*
X1231894Y485415D01*
G01X1185645Y437666D02*
X1232954Y484975D01*
G01X1158364Y424130D02*
X1172067Y437833D01*
G01X1158804Y423070D02*
X1173127Y437393D01*
G01X1172067Y437833D02*
Y444110D01*
G01X1173127Y437393D02*
Y443670D01*
G01X1172067Y444110D02*
X1173837Y445880D01*
G01X1173127Y443670D02*
X1174277Y444820D01*
G01X1173837Y445880D02*
X1187108D01*
G01X1174277Y444820D02*
X1187548D01*
G01X1187108Y445880D02*
X1226794Y485566D01*
G01X1187548Y444820D02*
X1227854Y485126D01*
G01X1160692Y420040D02*
X1176839Y436187D01*
G01X1160252Y421100D02*
X1175779Y436627D01*
G01X1176839Y436187D02*
Y441164D01*
G01X1175779Y436627D02*
Y441604D01*
G01X1176839Y441164D02*
X1177421Y441746D01*
G01X1175779Y441604D02*
X1176981Y442806D01*
G01X1177421Y441746D02*
X1178811D01*
G01X1176981Y442806D02*
X1179251D01*
G01X1178811Y441746D02*
X1179449Y441108D01*
G01X1179251Y442806D02*
X1180509Y441548D01*
G01X1179449Y441108D02*
Y438984D01*
G01X1180509Y441548D02*
Y439424D01*
G01X1179449Y438984D02*
X1180767Y437666D01*
G01X1180509Y439424D02*
X1181207Y438726D01*
G01X1180767Y437666D02*
X1185645D01*
G01X1181207Y438726D02*
X1185205D01*
G01X1185645Y437666D02*
X1232954Y484975D01*
G01X1185205Y438726D02*
X1231894Y485415D01*
G01X1158804Y423070D02*
X1173127Y437393D01*
G01X1158364Y424130D02*
X1172067Y437833D01*
G01X1173127Y437393D02*
Y443670D01*
G01X1172067Y437833D02*
Y444110D01*
G01X1173127Y443670D02*
X1174277Y444820D01*
G01X1172067Y444110D02*
X1173837Y445880D01*
G01X1174277Y444820D02*
X1187548D01*
G01X1173837Y445880D02*
X1187108D01*
G01X1187548Y444820D02*
X1227854Y485126D01*
G01X1187108Y445880D02*
X1226794Y485566D01*
G01X1160252Y421100D02*
X1175779Y436627D01*
G01X1160692Y420040D02*
X1176839Y436187D01*
G01X1175779Y436627D02*
Y441604D01*
G01X1176839Y436187D02*
Y441164D01*
G01X1175779Y441604D02*
X1176981Y442806D01*
G01X1176839Y441164D02*
X1177421Y441746D01*
G01X1176981Y442806D02*
X1179251D01*
G01X1177421Y441746D02*
X1178811D01*
G01X1179251Y442806D02*
X1180509Y441548D01*
G01X1178811Y441746D02*
X1179449Y441108D01*
G01X1180509Y441548D02*
Y439424D01*
G01X1179449Y441108D02*
Y438984D01*
G01X1180509Y439424D02*
X1181207Y438726D01*
G01X1179449Y438984D02*
X1180767Y437666D01*
G01X1181207Y438726D02*
X1185205D01*
G01X1180767Y437666D02*
X1185645D01*
G01X1185205Y438726D02*
X1231894Y485415D01*
G01X1185645Y437666D02*
X1232954Y484975D01*
G01X1176391Y474768D02*
X1191043Y489420D01*
G01X1175951Y475828D02*
X1189983Y489860D01*
G01X1191043Y489420D02*
Y587429D01*
G01X1189983Y489860D02*
Y576310D01*
G01X1191043Y489420D02*
Y587429D01*
G01Y489420D02*
Y587429D01*
G01Y489420D02*
Y587429D01*
G01X1175951Y475828D02*
X1189983Y489860D01*
G01X1176391Y474768D02*
X1191043Y489420D01*
G01X1189983Y489860D02*
Y576310D01*
G01X1191043Y489420D02*
Y587429D01*
G01X1159615Y471722D02*
X1162492Y468845D01*
G01X1160055Y472782D02*
X1162932Y469905D01*
G01X1162492Y468845D02*
X1165160D01*
G01X1162932Y469905D02*
X1164720D01*
G01X1165160Y468845D02*
X1167507Y471192D01*
G01X1164720Y469905D02*
X1167067Y472252D01*
G01X1167507Y471192D02*
X1169359D01*
G01X1167067Y472252D02*
X1169799D01*
G01X1167507Y471192D02*
X1169359D01*
G01D02*
X1169969Y470582D01*
G01X1169799Y472252D02*
X1171029Y471022D01*
G01X1169969Y470582D02*
Y469068D01*
G01X1171029Y471022D02*
Y469508D01*
G01X1169969Y469068D02*
X1171199Y467838D01*
G01X1171029Y469508D02*
X1171639Y468898D01*
G01X1171199Y467838D02*
X1173469D01*
G01X1171639Y468898D02*
X1173029D01*
G01X1173469Y467838D02*
X1174699Y469068D01*
G01X1173029Y468898D02*
X1173639Y469508D01*
G01X1174699Y469068D02*
Y470582D01*
G01X1173639Y469508D02*
Y471022D01*
G01X1174699Y470582D02*
X1175309Y471192D01*
G01X1173639Y471022D02*
X1174869Y472252D01*
G01X1175309Y471192D02*
X1177398D01*
G01X1174869Y472252D02*
X1176958D01*
G01X1177398Y471192D02*
X1196143Y489937D01*
G01X1176958Y472252D02*
X1195083Y490377D01*
G01X1196143Y489937D02*
Y587829D01*
G01X1195083Y490377D02*
Y507226D01*
G01X1196143Y489937D02*
Y587829D01*
G01X1195083Y509076D02*
Y519324D01*
G01X1196143Y489937D02*
Y587829D01*
G01X1195083Y521564D02*
Y522564D01*
G01X1196143Y489937D02*
Y587829D01*
G01X1195083Y524804D02*
Y525804D01*
G01X1196143Y489937D02*
Y587829D01*
G01Y489937D02*
Y587829D01*
G01Y489937D02*
Y587829D01*
G01Y489937D02*
Y587829D01*
G01Y489937D02*
Y587829D01*
G01Y489937D02*
Y587829D01*
G01Y489937D02*
Y587829D01*
G01Y489937D02*
Y587829D01*
G01Y489937D02*
Y587829D01*
G01Y489937D02*
Y587829D01*
G01X1160055Y472782D02*
X1162932Y469905D01*
G01X1159615Y471722D02*
X1162492Y468845D01*
G01X1162932Y469905D02*
X1164720D01*
G01X1162492Y468845D02*
X1165160D01*
G01X1164720Y469905D02*
X1167067Y472252D01*
G01X1165160Y468845D02*
X1167507Y471192D01*
G01X1167067Y472252D02*
X1169799D01*
G01D02*
X1171029Y471022D01*
G01X1167507Y471192D02*
X1169359D01*
G01X1169799Y472252D02*
X1171029Y471022D01*
G01X1169359Y471192D02*
X1169969Y470582D01*
G01X1171029Y471022D02*
Y469508D01*
G01X1169969Y470582D02*
Y469068D01*
G01X1171029Y469508D02*
X1171639Y468898D01*
G01X1169969Y469068D02*
X1171199Y467838D01*
G01X1171639Y468898D02*
X1173029D01*
G01X1171199Y467838D02*
X1173469D01*
G01X1173029Y468898D02*
X1173639Y469508D01*
G01X1173469Y467838D02*
X1174699Y469068D01*
G01X1173639Y469508D02*
Y471022D01*
G01X1174699Y469068D02*
Y470582D01*
G01X1173639Y471022D02*
X1174869Y472252D01*
G01X1174699Y470582D02*
X1175309Y471192D01*
G01X1174869Y472252D02*
X1176958D01*
G01X1175309Y471192D02*
X1177398D01*
G01X1176958Y472252D02*
X1195083Y490377D01*
G01X1177398Y471192D02*
X1196143Y489937D01*
G01X1195083Y490377D02*
Y507226D01*
G01Y509076D02*
Y519324D01*
G01Y521564D02*
Y522564D01*
G01Y524804D02*
Y525804D01*
G01X1196143Y489937D02*
Y587829D01*
G01X1159332Y549868D02*
Y504633D01*
G01X1158272Y549428D02*
Y505073D01*
G01X1159332Y504633D02*
X1157100Y502401D01*
G01D02*
Y500400D01*
G01X1158272Y549428D02*
Y505073D01*
G01X1159332Y549868D02*
Y504633D01*
G01D02*
X1157100Y502401D01*
G01D02*
Y500400D01*
G01X1175951Y475828D02*
X1189983Y489860D01*
G01X1176391Y474768D02*
X1191043Y489420D01*
G01X1189983Y489860D02*
Y576310D01*
G01X1191043Y489420D02*
Y587429D01*
G01X1159615Y471722D02*
X1162492Y468845D01*
G01X1160055Y472782D02*
X1162932Y469905D01*
G01X1162492Y468845D02*
X1165160D01*
G01X1162932Y469905D02*
X1164720D01*
G01X1165160Y468845D02*
X1167507Y471192D01*
G01X1164720Y469905D02*
X1167067Y472252D01*
G01X1167507Y471192D02*
X1169359D01*
G01X1167067Y472252D02*
X1169799D01*
G01X1167507Y471192D02*
X1169359D01*
G01D02*
X1169969Y470582D01*
G01X1169799Y472252D02*
X1171029Y471022D01*
G01X1169969Y470582D02*
Y469068D01*
G01X1171029Y471022D02*
Y469508D01*
G01X1169969Y469068D02*
X1171199Y467838D01*
G01X1171029Y469508D02*
X1171639Y468898D01*
G01X1171199Y467838D02*
X1173469D01*
G01X1171639Y468898D02*
X1173029D01*
G01X1173469Y467838D02*
X1174699Y469068D01*
G01X1173029Y468898D02*
X1173639Y469508D01*
G01X1174699Y469068D02*
Y470582D01*
G01X1173639Y469508D02*
Y471022D01*
G01X1174699Y470582D02*
X1175309Y471192D01*
G01X1173639Y471022D02*
X1174869Y472252D01*
G01X1175309Y471192D02*
X1177398D01*
G01X1174869Y472252D02*
X1176958D01*
G01X1177398Y471192D02*
X1196143Y489937D01*
G01X1176958Y472252D02*
X1195083Y490377D01*
G01X1196143Y489937D02*
Y587829D01*
G01X1195083Y490377D02*
Y507226D01*
G01X1196143Y489937D02*
Y587829D01*
G01X1195083Y509076D02*
Y519324D01*
G01X1196143Y489937D02*
Y587829D01*
G01X1195083Y521564D02*
Y522564D01*
G01X1196143Y489937D02*
Y587829D01*
G01X1195083Y524804D02*
Y525804D01*
G01X1196143Y489937D02*
Y587829D01*
G01Y489937D02*
Y587829D01*
G01Y489937D02*
Y587829D01*
G01Y489937D02*
Y587829D01*
G01Y489937D02*
Y587829D01*
G01Y489937D02*
Y587829D01*
G01Y489937D02*
Y587829D01*
G01Y489937D02*
Y587829D01*
G01Y489937D02*
Y587829D01*
G01Y489937D02*
Y587829D01*
G01X1176391Y474768D02*
X1191043Y489420D01*
G01X1175951Y475828D02*
X1189983Y489860D01*
G01X1191043Y489420D02*
Y587429D01*
G01X1189983Y489860D02*
Y576310D01*
G01X1191043Y489420D02*
Y587429D01*
G01Y489420D02*
Y587429D01*
G01Y489420D02*
Y587429D01*
G01X1160055Y472782D02*
X1162932Y469905D01*
G01X1159615Y471722D02*
X1162492Y468845D01*
G01X1162932Y469905D02*
X1164720D01*
G01X1162492Y468845D02*
X1165160D01*
G01X1164720Y469905D02*
X1167067Y472252D01*
G01X1165160Y468845D02*
X1167507Y471192D01*
G01X1167067Y472252D02*
X1169799D01*
G01D02*
X1171029Y471022D01*
G01X1167507Y471192D02*
X1169359D01*
G01X1169799Y472252D02*
X1171029Y471022D01*
G01X1169359Y471192D02*
X1169969Y470582D01*
G01X1171029Y471022D02*
Y469508D01*
G01X1169969Y470582D02*
Y469068D01*
G01X1171029Y469508D02*
X1171639Y468898D01*
G01X1169969Y469068D02*
X1171199Y467838D01*
G01X1171639Y468898D02*
X1173029D01*
G01X1171199Y467838D02*
X1173469D01*
G01X1173029Y468898D02*
X1173639Y469508D01*
G01X1173469Y467838D02*
X1174699Y469068D01*
G01X1173639Y469508D02*
Y471022D01*
G01X1174699Y469068D02*
Y470582D01*
G01X1173639Y471022D02*
X1174869Y472252D01*
G01X1174699Y470582D02*
X1175309Y471192D01*
G01X1174869Y472252D02*
X1176958D01*
G01X1175309Y471192D02*
X1177398D01*
G01X1176958Y472252D02*
X1195083Y490377D01*
G01X1177398Y471192D02*
X1196143Y489937D01*
G01X1195083Y490377D02*
Y507226D01*
G01Y509076D02*
Y519324D01*
G01Y521564D02*
Y522564D01*
G01Y524804D02*
Y525804D01*
G01X1196143Y489937D02*
Y587829D01*
G01X1189983Y578214D02*
Y579368D01*
G01Y581608D02*
Y582608D01*
G01Y584848D02*
Y586986D01*
G01X1191043Y587429D02*
X1189600Y588872D01*
G01X1189983Y586986D02*
X1188669Y588300D01*
G01X1189983Y578214D02*
Y579368D01*
G01Y581608D02*
Y582608D01*
G01Y584848D02*
Y586986D01*
G01D02*
X1188669Y588300D01*
G01X1191043Y587429D02*
X1189600Y588872D01*
G01X1195083Y528044D02*
Y538014D01*
G01Y540254D02*
Y541254D01*
G01Y543494D02*
Y544494D01*
G01Y546734D02*
Y556955D01*
G01Y559195D02*
Y560195D01*
G01Y562435D02*
Y563435D01*
G01Y565675D02*
Y575841D01*
G01Y578081D02*
Y579081D01*
G01Y581321D02*
Y582321D01*
G01Y584561D02*
Y587386D01*
G01X1196143Y587829D02*
X1194600Y589372D01*
G01X1195083Y587386D02*
X1193955Y588514D01*
G01X1195083Y528044D02*
Y538014D01*
G01Y540254D02*
Y541254D01*
G01Y543494D02*
Y544494D01*
G01Y546734D02*
Y556955D01*
G01Y559195D02*
Y560195D01*
G01Y562435D02*
Y563435D01*
G01Y565675D02*
Y575841D01*
G01Y578081D02*
Y579081D01*
G01Y581321D02*
Y582321D01*
G01Y584561D02*
Y587386D01*
G01D02*
X1193955Y588514D01*
G01X1196143Y587829D02*
X1194600Y589372D01*
G01X1158000Y551200D02*
X1159332Y549868D01*
G01X1158000Y551200D02*
X1159332Y549868D01*
G01X1189983Y578214D02*
Y579368D01*
G01Y581608D02*
Y582608D01*
G01Y584848D02*
Y586986D01*
G01D02*
X1188669Y588300D01*
G01X1191043Y587429D02*
X1189600Y588872D01*
G01X1195083Y528044D02*
Y538014D01*
G01Y540254D02*
Y541254D01*
G01Y543494D02*
Y544494D01*
G01Y546734D02*
Y556955D01*
G01Y559195D02*
Y560195D01*
G01Y562435D02*
Y563435D01*
G01Y565675D02*
Y575841D01*
G01Y578081D02*
Y579081D01*
G01Y581321D02*
Y582321D01*
G01Y584561D02*
Y587386D01*
G01X1196143Y587829D02*
X1194600Y589372D01*
G01X1195083Y587386D02*
X1193955Y588514D01*
G01X1189983Y578214D02*
Y579368D01*
G01Y581608D02*
Y582608D01*
G01Y584848D02*
Y586986D01*
G01X1191043Y587429D02*
X1189600Y588872D01*
G01X1189983Y586986D02*
X1188669Y588300D01*
G01X1195083Y528044D02*
Y538014D01*
G01Y540254D02*
Y541254D01*
G01Y543494D02*
Y544494D01*
G01Y546734D02*
Y556955D01*
G01Y559195D02*
Y560195D01*
G01Y562435D02*
Y563435D01*
G01Y565675D02*
Y575841D01*
G01Y578081D02*
Y579081D01*
G01Y581321D02*
Y582321D01*
G01Y584561D02*
Y587386D01*
G01D02*
X1193955Y588514D01*
G01X1196143Y587829D02*
X1194600Y589372D01*
G01X1187035Y595890D02*
Y597260D01*
G01Y600940D02*
Y602360D01*
G01X1185975Y590000D02*
Y608011D01*
G01Y590000D02*
Y608011D01*
G01X1187035Y595890D02*
Y597260D01*
G01X1185975Y590000D02*
Y608011D01*
G01X1187035Y600940D02*
Y602360D01*
G01X1192259Y595500D02*
X1191588Y596171D01*
G01X1191358Y594900D02*
X1190528Y595730D01*
G01X1191588Y596171D02*
Y597448D01*
G01Y600938D02*
Y601829D01*
G01X1190528Y595730D02*
Y602270D01*
G01X1191588Y601829D02*
X1192359Y602600D01*
G01X1190528Y602270D02*
X1191358Y603100D01*
G01Y594900D02*
X1190528Y595730D01*
G01X1192259Y595500D02*
X1191588Y596171D01*
G01X1190528Y595730D02*
Y602270D01*
G01X1191588Y596171D02*
Y597448D01*
G01X1190528Y595730D02*
Y602270D01*
G01X1191588Y600938D02*
Y601829D01*
G01X1190528Y602270D02*
X1191358Y603100D01*
G01X1191588Y601829D02*
X1192359Y602600D01*
G01X1185975Y590000D02*
Y608011D01*
G01X1187035Y595890D02*
Y597260D01*
G01X1185975Y590000D02*
Y608011D01*
G01X1187035Y600940D02*
Y602360D01*
G01X1192259Y595500D02*
X1191588Y596171D01*
G01X1191358Y594900D02*
X1190528Y595730D01*
G01X1191588Y596171D02*
Y597448D01*
G01Y600938D02*
Y601829D01*
G01X1190528Y595730D02*
Y602270D01*
G01X1191588Y601829D02*
X1192359Y602600D01*
G01X1190528Y602270D02*
X1191358Y603100D01*
G01X1187035Y595890D02*
Y597260D01*
G01Y600940D02*
Y602360D01*
G01X1185975Y590000D02*
Y608011D01*
G01X1191358Y594900D02*
X1190528Y595730D01*
G01X1192259Y595500D02*
X1191588Y596171D01*
G01X1190528Y595730D02*
Y602270D01*
G01X1191588Y596171D02*
Y597448D01*
G01X1190528Y595730D02*
Y602270D01*
G01X1191588Y600938D02*
Y601829D01*
G01X1190528Y602270D02*
X1191358Y603100D01*
G01X1191588Y601829D02*
X1192359Y602600D01*
G01X1225873Y11700D02*
X1226820Y10753D01*
G01X1224774Y14300D02*
X1227880Y11194D01*
G01X1226820Y10753D02*
Y8220D01*
G01Y4080D02*
Y3120D01*
G01Y-1220D02*
Y-4509D01*
G01X1227880Y11194D02*
Y-4952D01*
G01X1226820Y-4509D02*
X1226109Y-5220D01*
G01X1227880Y-4952D02*
X1226552Y-6280D01*
G01X1226109Y-5220D02*
X1225593D01*
G01X1226552Y-6280D02*
X1225570D01*
G01X1226794Y94165D02*
Y25005D01*
G01Y94165D02*
Y25005D01*
G01Y94165D02*
Y25005D01*
G01Y94165D02*
Y25005D01*
G01X1227854Y39226D02*
Y24562D01*
G01X1226794Y25005D02*
X1222920Y21131D01*
G01X1227854Y24562D02*
X1223980Y20688D01*
G01X1222920Y21131D02*
Y13554D01*
G01X1223980Y20688D02*
Y19620D01*
G01X1229874Y11915D02*
X1230972D01*
G01D02*
X1232006Y10881D01*
G01X1229874Y14514D02*
X1233066Y11322D01*
G01X1232006Y10881D02*
Y8106D01*
G01Y4280D02*
Y2907D01*
G01Y-1007D02*
Y-3628D01*
G01X1233066Y11322D02*
Y-4068D01*
G01X1232006Y-3628D02*
X1230983Y-4651D01*
G01D02*
X1229874D01*
G01X1233066Y-4068D02*
X1229874Y-7260D01*
G01X1231894Y120106D02*
Y24505D01*
G01X1232954Y120546D02*
Y26134D01*
G01X1231894Y24505D02*
X1228620Y21231D01*
G01X1230654Y21762D02*
X1229680Y20788D01*
G01X1228620Y21231D02*
Y18719D01*
G01X1229680Y20788D02*
Y19920D01*
G01X1224774Y14300D02*
X1227880Y11194D01*
G01X1225873Y11700D02*
X1226820Y10753D01*
G01X1227880Y11194D02*
Y-4952D01*
G01X1226820Y10753D02*
Y8220D01*
G01X1227880Y11194D02*
Y-4952D01*
G01X1226820Y4080D02*
Y3120D01*
G01X1227880Y11194D02*
Y-4952D01*
G01X1226820Y-1220D02*
Y-4509D01*
G01X1227880Y-4952D02*
X1226552Y-6280D01*
G01X1226820Y-4509D02*
X1226109Y-5220D01*
G01X1226552Y-6280D02*
X1225570D01*
G01X1226109Y-5220D02*
X1225593D01*
G01X1227854Y39226D02*
Y24562D01*
G01X1226794Y94165D02*
Y25005D01*
G01X1227854Y24562D02*
X1223980Y20688D01*
G01X1226794Y25005D02*
X1222920Y21131D01*
G01X1223980Y20688D02*
Y19620D01*
G01X1222920Y21131D02*
Y13554D01*
G01X1229874Y14514D02*
X1233066Y11322D01*
G01X1229874Y11915D02*
X1230972D01*
G01X1229874Y14514D02*
X1233066Y11322D01*
G01X1230972Y11915D02*
X1232006Y10881D01*
G01X1233066Y11322D02*
Y-4068D01*
G01X1232006Y10881D02*
Y8106D01*
G01X1233066Y11322D02*
Y-4068D01*
G01X1232006Y4280D02*
Y2907D01*
G01X1233066Y11322D02*
Y-4068D01*
G01X1232006Y-1007D02*
Y-3628D01*
G01X1233066Y-4068D02*
X1229874Y-7260D01*
G01X1232006Y-3628D02*
X1230983Y-4651D01*
G01X1233066Y-4068D02*
X1229874Y-7260D01*
G01X1230983Y-4651D02*
X1229874D01*
G01X1232954Y120546D02*
Y26134D01*
G01X1231894Y120106D02*
Y24505D01*
G01X1230654Y21762D02*
X1229680Y20788D01*
G01X1231894Y24505D02*
X1228620Y21231D01*
G01X1229680Y20788D02*
Y19920D01*
G01X1228620Y21231D02*
Y18719D01*
G01X1225873Y11700D02*
X1226820Y10753D01*
G01X1224774Y14300D02*
X1227880Y11194D01*
G01X1226820Y10753D02*
Y8220D01*
G01Y4080D02*
Y3120D01*
G01Y-1220D02*
Y-4509D01*
G01X1227880Y11194D02*
Y-4952D01*
G01X1226820Y-4509D02*
X1226109Y-5220D01*
G01X1227880Y-4952D02*
X1226552Y-6280D01*
G01X1226109Y-5220D02*
X1225593D01*
G01X1226552Y-6280D02*
X1225570D01*
G01X1226794Y94165D02*
Y25005D01*
G01Y94165D02*
Y25005D01*
G01Y94165D02*
Y25005D01*
G01Y94165D02*
Y25005D01*
G01X1227854Y39226D02*
Y24562D01*
G01X1226794Y25005D02*
X1222920Y21131D01*
G01X1227854Y24562D02*
X1223980Y20688D01*
G01X1222920Y21131D02*
Y13554D01*
G01X1223980Y20688D02*
Y19620D01*
G01X1229874Y11915D02*
X1230972D01*
G01D02*
X1232006Y10881D01*
G01X1229874Y14514D02*
X1233066Y11322D01*
G01X1232006Y10881D02*
Y8106D01*
G01Y4280D02*
Y2907D01*
G01Y-1007D02*
Y-3628D01*
G01X1233066Y11322D02*
Y-4068D01*
G01X1232006Y-3628D02*
X1230983Y-4651D01*
G01D02*
X1229874D01*
G01X1233066Y-4068D02*
X1229874Y-7260D01*
G01X1231894Y120106D02*
Y24505D01*
G01X1232954Y120546D02*
Y26134D01*
G01X1231894Y24505D02*
X1228620Y21231D01*
G01X1230654Y21762D02*
X1229680Y20788D01*
G01X1228620Y21231D02*
Y18719D01*
G01X1229680Y20788D02*
Y19920D01*
G01X1224774Y14300D02*
X1227880Y11194D01*
G01X1225873Y11700D02*
X1226820Y10753D01*
G01X1227880Y11194D02*
Y-4952D01*
G01X1226820Y10753D02*
Y8220D01*
G01X1227880Y11194D02*
Y-4952D01*
G01X1226820Y4080D02*
Y3120D01*
G01X1227880Y11194D02*
Y-4952D01*
G01X1226820Y-1220D02*
Y-4509D01*
G01X1227880Y-4952D02*
X1226552Y-6280D01*
G01X1226820Y-4509D02*
X1226109Y-5220D01*
G01X1226552Y-6280D02*
X1225570D01*
G01X1226109Y-5220D02*
X1225593D01*
G01X1227854Y39226D02*
Y24562D01*
G01X1226794Y94165D02*
Y25005D01*
G01X1227854Y24562D02*
X1223980Y20688D01*
G01X1226794Y25005D02*
X1222920Y21131D01*
G01X1223980Y20688D02*
Y19620D01*
G01X1222920Y21131D02*
Y13554D01*
G01X1229874Y14514D02*
X1233066Y11322D01*
G01X1229874Y11915D02*
X1230972D01*
G01X1229874Y14514D02*
X1233066Y11322D01*
G01X1230972Y11915D02*
X1232006Y10881D01*
G01X1233066Y11322D02*
Y-4068D01*
G01X1232006Y10881D02*
Y8106D01*
G01X1233066Y11322D02*
Y-4068D01*
G01X1232006Y4280D02*
Y2907D01*
G01X1233066Y11322D02*
Y-4068D01*
G01X1232006Y-1007D02*
Y-3628D01*
G01X1233066Y-4068D02*
X1229874Y-7260D01*
G01X1232006Y-3628D02*
X1230983Y-4651D01*
G01X1233066Y-4068D02*
X1229874Y-7260D01*
G01X1230983Y-4651D02*
X1229874D01*
G01X1232954Y120546D02*
Y26134D01*
G01X1231894Y120106D02*
Y24505D01*
G01X1230654Y21762D02*
X1229680Y20788D01*
G01X1231894Y24505D02*
X1228620Y21231D01*
G01X1229680Y20788D02*
Y19920D01*
G01X1228620Y21231D02*
Y18719D01*
G01X1227910Y95281D02*
X1226794Y94165D01*
G01X1228970Y94841D02*
X1227854Y93725D01*
G01D02*
Y48213D01*
G01Y46313D02*
Y44418D01*
G01Y42518D02*
Y41126D01*
G01X1228970Y94841D02*
X1227854Y93725D01*
G01X1227910Y95281D02*
X1226794Y94165D01*
G01X1227854Y93725D02*
Y48213D01*
G01Y46313D02*
Y44418D01*
G01Y42518D02*
Y41126D01*
G01X1227910Y95281D02*
X1226794Y94165D01*
G01X1228970Y94841D02*
X1227854Y93725D01*
G01D02*
Y48213D01*
G01Y46313D02*
Y44418D01*
G01Y42518D02*
Y41126D01*
G01X1228970Y94841D02*
X1227854Y93725D01*
G01X1227910Y95281D02*
X1226794Y94165D01*
G01X1227854Y93725D02*
Y48213D01*
G01Y46313D02*
Y44418D01*
G01Y42518D02*
Y41126D01*
G01X1224520Y123080D02*
Y116762D01*
G01X1225580Y123520D02*
Y117202D01*
G01X1224520Y116762D02*
X1226009Y115273D01*
G01X1225580Y117202D02*
X1226449Y116333D01*
G01X1226009Y115273D02*
X1227628D01*
G01X1226449Y116333D02*
X1228068D01*
G01X1226009Y115273D02*
X1227628D01*
G01D02*
X1228500Y114401D01*
G01X1228068Y116333D02*
X1229560Y114841D01*
G01X1228500Y114401D02*
Y111905D01*
G01X1229560Y114841D02*
Y111465D01*
G01X1228500Y111905D02*
X1227628Y111033D01*
G01X1229560Y111465D02*
X1228068Y109973D01*
G01X1227628Y111033D02*
X1225909D01*
G01X1228068Y109973D02*
X1226349D01*
G01X1225909Y111033D02*
X1224420Y109544D01*
G01X1226349Y109973D02*
X1225480Y109104D01*
G01X1224420Y109544D02*
Y106162D01*
G01X1225480Y109104D02*
Y106605D01*
G01X1224420Y106162D02*
X1225909Y104673D01*
G01X1225480Y106605D02*
X1226352Y105733D01*
G01X1225909Y104673D02*
X1227048D01*
G01X1226352Y105733D02*
X1227488D01*
G01X1225909Y104673D02*
X1227048D01*
G01D02*
X1228020Y103701D01*
G01X1227488Y105733D02*
X1229080Y104141D01*
G01X1228020Y103701D02*
Y102725D01*
G01X1229080Y104141D02*
Y102285D01*
G01X1228020Y102725D02*
X1225909Y100614D01*
G01X1229080Y102285D02*
X1226969Y100174D01*
G01X1225909Y100614D02*
Y97987D01*
G01X1226969Y100174D02*
Y98427D01*
G01X1225909Y97987D02*
X1227910Y95986D01*
G01X1226969Y98427D02*
X1228970Y96426D01*
G01X1227910Y95986D02*
Y95281D01*
G01X1228970Y96426D02*
Y94841D01*
G01X1225580Y123520D02*
Y117202D01*
G01X1224520Y123080D02*
Y116762D01*
G01X1225580Y117202D02*
X1226449Y116333D01*
G01X1224520Y116762D02*
X1226009Y115273D01*
G01X1226449Y116333D02*
X1228068D01*
G01D02*
X1229560Y114841D01*
G01X1226009Y115273D02*
X1227628D01*
G01X1228068Y116333D02*
X1229560Y114841D01*
G01X1227628Y115273D02*
X1228500Y114401D01*
G01X1229560Y114841D02*
Y111465D01*
G01X1228500Y114401D02*
Y111905D01*
G01X1229560Y111465D02*
X1228068Y109973D01*
G01X1228500Y111905D02*
X1227628Y111033D01*
G01X1228068Y109973D02*
X1226349D01*
G01X1227628Y111033D02*
X1225909D01*
G01X1226349Y109973D02*
X1225480Y109104D01*
G01X1225909Y111033D02*
X1224420Y109544D01*
G01X1225480Y109104D02*
Y106605D01*
G01X1224420Y109544D02*
Y106162D01*
G01X1225480Y106605D02*
X1226352Y105733D01*
G01X1224420Y106162D02*
X1225909Y104673D01*
G01X1226352Y105733D02*
X1227488D01*
G01D02*
X1229080Y104141D01*
G01X1225909Y104673D02*
X1227048D01*
G01X1227488Y105733D02*
X1229080Y104141D01*
G01X1227048Y104673D02*
X1228020Y103701D01*
G01X1229080Y104141D02*
Y102285D01*
G01X1228020Y103701D02*
Y102725D01*
G01X1229080Y102285D02*
X1226969Y100174D01*
G01X1228020Y102725D02*
X1225909Y100614D01*
G01X1226969Y100174D02*
Y98427D01*
G01X1225909Y100614D02*
Y97987D01*
G01X1226969Y98427D02*
X1228970Y96426D01*
G01X1225909Y97987D02*
X1227910Y95986D01*
G01X1228970Y96426D02*
Y94841D01*
G01X1227910Y95986D02*
Y95281D01*
G01X1224520Y123080D02*
Y116762D01*
G01X1225580Y123520D02*
Y117202D01*
G01X1224520Y116762D02*
X1226009Y115273D01*
G01X1225580Y117202D02*
X1226449Y116333D01*
G01X1226009Y115273D02*
X1227628D01*
G01X1226449Y116333D02*
X1228068D01*
G01X1226009Y115273D02*
X1227628D01*
G01D02*
X1228500Y114401D01*
G01X1228068Y116333D02*
X1229560Y114841D01*
G01X1228500Y114401D02*
Y111905D01*
G01X1229560Y114841D02*
Y111465D01*
G01X1228500Y111905D02*
X1227628Y111033D01*
G01X1229560Y111465D02*
X1228068Y109973D01*
G01X1227628Y111033D02*
X1225909D01*
G01X1228068Y109973D02*
X1226349D01*
G01X1225909Y111033D02*
X1224420Y109544D01*
G01X1226349Y109973D02*
X1225480Y109104D01*
G01X1224420Y109544D02*
Y106162D01*
G01X1225480Y109104D02*
Y106605D01*
G01X1224420Y106162D02*
X1225909Y104673D01*
G01X1225480Y106605D02*
X1226352Y105733D01*
G01X1225909Y104673D02*
X1227048D01*
G01X1226352Y105733D02*
X1227488D01*
G01X1225909Y104673D02*
X1227048D01*
G01D02*
X1228020Y103701D01*
G01X1227488Y105733D02*
X1229080Y104141D01*
G01X1228020Y103701D02*
Y102725D01*
G01X1229080Y104141D02*
Y102285D01*
G01X1228020Y102725D02*
X1225909Y100614D01*
G01X1229080Y102285D02*
X1226969Y100174D01*
G01X1225909Y100614D02*
Y97987D01*
G01X1226969Y100174D02*
Y98427D01*
G01X1225909Y97987D02*
X1227910Y95986D01*
G01X1226969Y98427D02*
X1228970Y96426D01*
G01X1227910Y95986D02*
Y95281D01*
G01X1228970Y96426D02*
Y94841D01*
G01X1225580Y123520D02*
Y117202D01*
G01X1224520Y123080D02*
Y116762D01*
G01X1225580Y117202D02*
X1226449Y116333D01*
G01X1224520Y116762D02*
X1226009Y115273D01*
G01X1226449Y116333D02*
X1228068D01*
G01D02*
X1229560Y114841D01*
G01X1226009Y115273D02*
X1227628D01*
G01X1228068Y116333D02*
X1229560Y114841D01*
G01X1227628Y115273D02*
X1228500Y114401D01*
G01X1229560Y114841D02*
Y111465D01*
G01X1228500Y114401D02*
Y111905D01*
G01X1229560Y111465D02*
X1228068Y109973D01*
G01X1228500Y111905D02*
X1227628Y111033D01*
G01X1228068Y109973D02*
X1226349D01*
G01X1227628Y111033D02*
X1225909D01*
G01X1226349Y109973D02*
X1225480Y109104D01*
G01X1225909Y111033D02*
X1224420Y109544D01*
G01X1225480Y109104D02*
Y106605D01*
G01X1224420Y109544D02*
Y106162D01*
G01X1225480Y106605D02*
X1226352Y105733D01*
G01X1224420Y106162D02*
X1225909Y104673D01*
G01X1226352Y105733D02*
X1227488D01*
G01D02*
X1229080Y104141D01*
G01X1225909Y104673D02*
X1227048D01*
G01X1227488Y105733D02*
X1229080Y104141D01*
G01X1227048Y104673D02*
X1228020Y103701D01*
G01X1229080Y104141D02*
Y102285D01*
G01X1228020Y103701D02*
Y102725D01*
G01X1229080Y102285D02*
X1226969Y100174D01*
G01X1228020Y102725D02*
X1225909Y100614D01*
G01X1226969Y100174D02*
Y98427D01*
G01X1225909Y100614D02*
Y97987D01*
G01X1226969Y98427D02*
X1228970Y96426D01*
G01X1225909Y97987D02*
X1227910Y95986D01*
G01X1228970Y96426D02*
Y94841D01*
G01X1227910Y95986D02*
Y95281D01*
G01X1226794Y485566D02*
Y576325D01*
G01X1227854Y485126D02*
Y587820D01*
G01X1232954Y484975D02*
Y588034D01*
G01X1231894Y485415D02*
Y506891D01*
G01X1232954Y484975D02*
Y588034D01*
G01X1231894Y509131D02*
Y518933D01*
G01X1232954Y484975D02*
Y588034D01*
G01X1231894Y521173D02*
Y522173D01*
G01X1232954Y484975D02*
Y588034D01*
G01X1231894Y524413D02*
Y525413D01*
G01X1232954Y484975D02*
Y588034D01*
G01Y484975D02*
Y588034D01*
G01Y484975D02*
Y588034D01*
G01Y484975D02*
Y588034D01*
G01Y484975D02*
Y588034D01*
G01Y484975D02*
Y588034D01*
G01Y484975D02*
Y588034D01*
G01Y484975D02*
Y588034D01*
G01Y484975D02*
Y588034D01*
G01Y484975D02*
Y588034D01*
G01X1227854Y485126D02*
Y587820D01*
G01X1226794Y485566D02*
Y576325D01*
G01X1227854Y485126D02*
Y587820D01*
G01Y485126D02*
Y587820D01*
G01Y485126D02*
Y587820D01*
G01X1231894Y485415D02*
Y506891D01*
G01Y509131D02*
Y518933D01*
G01Y521173D02*
Y522173D01*
G01Y524413D02*
Y525413D01*
G01X1232954Y484975D02*
Y588034D01*
G01X1226794Y485566D02*
Y576325D01*
G01X1227854Y485126D02*
Y587820D01*
G01X1232954Y484975D02*
Y588034D01*
G01X1231894Y485415D02*
Y506891D01*
G01X1232954Y484975D02*
Y588034D01*
G01X1231894Y509131D02*
Y518933D01*
G01X1232954Y484975D02*
Y588034D01*
G01X1231894Y521173D02*
Y522173D01*
G01X1232954Y484975D02*
Y588034D01*
G01X1231894Y524413D02*
Y525413D01*
G01X1232954Y484975D02*
Y588034D01*
G01Y484975D02*
Y588034D01*
G01Y484975D02*
Y588034D01*
G01Y484975D02*
Y588034D01*
G01Y484975D02*
Y588034D01*
G01Y484975D02*
Y588034D01*
G01Y484975D02*
Y588034D01*
G01Y484975D02*
Y588034D01*
G01Y484975D02*
Y588034D01*
G01Y484975D02*
Y588034D01*
G01X1227854Y485126D02*
Y587820D01*
G01X1226794Y485566D02*
Y576325D01*
G01X1227854Y485126D02*
Y587820D01*
G01Y485126D02*
Y587820D01*
G01Y485126D02*
Y587820D01*
G01X1231894Y485415D02*
Y506891D01*
G01Y509131D02*
Y518933D01*
G01Y521173D02*
Y522173D01*
G01Y524413D02*
Y525413D01*
G01X1232954Y484975D02*
Y588034D01*
G01X1226794Y578089D02*
Y579285D01*
G01Y581525D02*
Y582637D01*
G01Y584653D02*
Y587380D01*
G01D02*
X1225874Y588300D01*
G01X1227854Y587820D02*
X1224774Y590900D01*
G01X1231894Y527653D02*
Y538405D01*
G01Y540645D02*
Y541645D01*
G01Y543885D02*
Y544885D01*
G01Y547125D02*
Y557095D01*
G01Y559335D02*
Y560335D01*
G01Y562575D02*
Y563575D01*
G01Y565815D02*
Y576259D01*
G01Y578499D02*
Y579499D01*
G01Y581739D02*
Y582739D01*
G01Y584979D02*
Y587593D01*
G01X1232954Y588034D02*
X1229874Y591114D01*
G01X1231894Y587593D02*
X1230973Y588514D01*
G01X1232954Y588034D02*
X1229874Y591114D01*
G01X1226794Y578089D02*
Y579285D01*
G01Y581525D02*
Y582637D01*
G01Y584653D02*
Y587380D01*
G01X1227854Y587820D02*
X1224774Y590900D01*
G01X1226794Y587380D02*
X1225874Y588300D01*
G01X1227854Y587820D02*
X1224774Y590900D01*
G01X1231894Y527653D02*
Y538405D01*
G01Y540645D02*
Y541645D01*
G01Y543885D02*
Y544885D01*
G01Y547125D02*
Y557095D01*
G01Y559335D02*
Y560335D01*
G01Y562575D02*
Y563575D01*
G01Y565815D02*
Y576259D01*
G01Y578499D02*
Y579499D01*
G01Y581739D02*
Y582739D01*
G01Y584979D02*
Y587593D01*
G01D02*
X1230973Y588514D01*
G01X1232954Y588034D02*
X1229874Y591114D01*
G01X1226794Y578089D02*
Y579285D01*
G01Y581525D02*
Y582637D01*
G01Y584653D02*
Y587380D01*
G01D02*
X1225874Y588300D01*
G01X1227854Y587820D02*
X1224774Y590900D01*
G01X1231894Y527653D02*
Y538405D01*
G01Y540645D02*
Y541645D01*
G01Y543885D02*
Y544885D01*
G01Y547125D02*
Y557095D01*
G01Y559335D02*
Y560335D01*
G01Y562575D02*
Y563575D01*
G01Y565815D02*
Y576259D01*
G01Y578499D02*
Y579499D01*
G01Y581739D02*
Y582739D01*
G01Y584979D02*
Y587593D01*
G01X1232954Y588034D02*
X1229874Y591114D01*
G01X1231894Y587593D02*
X1230973Y588514D01*
G01X1232954Y588034D02*
X1229874Y591114D01*
G01X1226794Y578089D02*
Y579285D01*
G01Y581525D02*
Y582637D01*
G01Y584653D02*
Y587380D01*
G01X1227854Y587820D02*
X1224774Y590900D01*
G01X1226794Y587380D02*
X1225874Y588300D01*
G01X1227854Y587820D02*
X1224774Y590900D01*
G01X1231894Y527653D02*
Y538405D01*
G01Y540645D02*
Y541645D01*
G01Y543885D02*
Y544885D01*
G01Y547125D02*
Y557095D01*
G01Y559335D02*
Y560335D01*
G01Y562575D02*
Y563575D01*
G01Y565815D02*
Y576259D01*
G01Y578499D02*
Y579499D01*
G01Y581739D02*
Y582739D01*
G01Y584979D02*
Y587593D01*
G01D02*
X1230973Y588514D01*
G01X1232954Y588034D02*
X1229874Y591114D01*
G01X1222786Y590000D02*
Y608011D01*
G01X1223846Y595890D02*
Y597260D01*
G01X1222786Y590000D02*
Y608011D01*
G01X1223846Y600940D02*
Y602360D01*
G01X1225874Y588300D02*
X1224774D01*
G01X1229070Y595500D02*
X1228399Y596171D01*
G01X1228169Y594900D02*
X1227339Y595730D01*
G01X1228399Y596171D02*
Y597448D01*
G01Y600938D02*
Y601829D01*
G01X1227339Y595730D02*
Y602270D01*
G01X1228399Y601829D02*
X1229170Y602600D01*
G01X1227339Y602270D02*
X1228169Y603100D01*
G01X1230973Y588514D02*
X1229874D01*
G01X1223846Y595890D02*
Y597260D01*
G01Y600940D02*
Y602360D01*
G01X1222786Y590000D02*
Y608011D01*
G01X1225874Y588300D02*
X1224774D01*
G01X1228169Y594900D02*
X1227339Y595730D01*
G01X1229070Y595500D02*
X1228399Y596171D01*
G01X1227339Y595730D02*
Y602270D01*
G01X1228399Y596171D02*
Y597448D01*
G01X1227339Y595730D02*
Y602270D01*
G01X1228399Y600938D02*
Y601829D01*
G01X1227339Y602270D02*
X1228169Y603100D01*
G01X1228399Y601829D02*
X1229170Y602600D01*
G01X1230973Y588514D02*
X1229874D01*
G01X1222786Y590000D02*
Y608011D01*
G01X1223846Y595890D02*
Y597260D01*
G01X1222786Y590000D02*
Y608011D01*
G01X1223846Y600940D02*
Y602360D01*
G01X1225874Y588300D02*
X1224774D01*
G01X1229070Y595500D02*
X1228399Y596171D01*
G01X1228169Y594900D02*
X1227339Y595730D01*
G01X1228399Y596171D02*
Y597448D01*
G01Y600938D02*
Y601829D01*
G01X1227339Y595730D02*
Y602270D01*
G01X1228399Y601829D02*
X1229170Y602600D01*
G01X1227339Y602270D02*
X1228169Y603100D01*
G01X1230973Y588514D02*
X1229874D01*
G01X1223846Y595890D02*
Y597260D01*
G01Y600940D02*
Y602360D01*
G01X1222786Y590000D02*
Y608011D01*
G01X1225874Y588300D02*
X1224774D01*
G01X1228169Y594900D02*
X1227339Y595730D01*
G01X1229070Y595500D02*
X1228399Y596171D01*
G01X1227339Y595730D02*
Y602270D01*
G01X1228399Y596171D02*
Y597448D01*
G01X1227339Y595730D02*
Y602270D01*
G01X1228399Y600938D02*
Y601829D01*
G01X1227339Y602270D02*
X1228169Y603100D01*
G01X1228399Y601829D02*
X1229170Y602600D01*
G01X1230973Y588514D02*
X1229874D01*
G54D15*
G01X1882682Y11175D02*
X1879478D01*
G01X1882485Y9524D02*
X1878794D01*
G01X1879478Y11175D02*
X1879010Y11643D01*
G01X1878794Y9524D02*
X1877359Y10959D01*
G01X1879010Y11643D02*
Y15695D01*
G01X1877359Y10959D02*
Y16379D01*
G01X1879010Y15695D02*
X1882101Y18786D01*
G01X1877359Y16379D02*
X1881417Y20437D01*
G01X1882101Y18786D02*
X1884290D01*
G01X1881417Y20437D02*
X1883606D01*
G01X1884290Y18786D02*
X1887374Y21870D01*
G01X1883606Y20437D02*
X1885723Y22554D01*
G01X1887374Y21870D02*
Y28210D01*
G01X1885723Y22554D02*
Y27526D01*
G01X1887374Y28210D02*
X1882650Y32934D01*
G01X1885723Y27526D02*
X1880999Y32250D01*
G01D02*
Y48438D01*
G01X1882485Y9524D02*
X1878794D01*
G01X1882682Y11175D02*
X1879478D01*
G01X1878794Y9524D02*
X1877359Y10959D01*
G01X1879478Y11175D02*
X1879010Y11643D01*
G01X1877359Y10959D02*
Y16379D01*
G01X1879010Y11643D02*
Y15695D01*
G01X1877359Y16379D02*
X1881417Y20437D01*
G01X1879010Y15695D02*
X1882101Y18786D01*
G01X1881417Y20437D02*
X1883606D01*
G01X1882101Y18786D02*
X1884290D01*
G01X1883606Y20437D02*
X1885723Y22554D01*
G01X1884290Y18786D02*
X1887374Y21870D01*
G01X1885723Y22554D02*
Y27526D01*
G01X1887374Y21870D02*
Y28210D01*
G01X1885723Y27526D02*
X1880999Y32250D01*
G01X1887374Y28210D02*
X1882650Y32934D01*
G01X1880999Y32250D02*
Y48438D01*
G01X1893527Y-18930D02*
X1896591D01*
G01X1893594Y-17279D02*
X1895907D01*
G01X1896591Y-18930D02*
X1898200Y-17321D01*
G01X1895907Y-17279D02*
X1896549Y-16637D01*
G01D02*
Y-10444D01*
G01X1898200Y-9760D02*
X1894330Y-5890D01*
G01Y-5889D02*
X1893364Y-4923D01*
G01X1896549Y-10444D02*
X1892679Y-6574D01*
G01X1893362Y-4922D02*
X1891996D01*
G01X1891995Y-4923D02*
X1886664D01*
G01X1892679Y-6574D02*
X1885980D01*
G01X1886664Y-4923D02*
X1886263Y-4522D01*
G01X1885980Y-6574D02*
X1884612Y-5206D01*
G01X1886263Y-4522D02*
Y-2866D01*
G01X1884612Y-5206D02*
Y-2182D01*
G01X1886263Y-2866D02*
X1886606Y-2523D01*
G01X1884612Y-2182D02*
X1885922Y-872D01*
G01X1886606Y-2523D02*
X1890589D01*
G01X1885922Y-872D02*
X1889905D01*
G01X1890589Y-2523D02*
X1892318Y-794D01*
G01X1889905Y-872D02*
X1890667Y-110D01*
G01X1892318Y-794D02*
Y1864D01*
G01X1890667Y-110D02*
Y1180D01*
G01X1892318Y1864D02*
X1890790Y3392D01*
G01X1890667Y1180D02*
X1890106Y1741D01*
G01X1890790Y3392D02*
X1887614D01*
G01X1890106Y1741D02*
X1886930D01*
G01X1887614Y3392D02*
X1886562Y4444D01*
G01X1886930Y1741D02*
X1884911Y3760D01*
G01X1886562Y4444D02*
Y5537D01*
G01X1884911Y3760D02*
Y6221D01*
G01X1886562Y5537D02*
X1887399Y6374D01*
G01X1884911Y6221D02*
X1886715Y8025D01*
G01X1887399Y6374D02*
X1890449D01*
G01X1886715Y8025D02*
X1889765D01*
G01X1890449Y6374D02*
X1891735Y7660D01*
G01X1889765Y8025D02*
X1890084Y8344D01*
G01X1891735Y7660D02*
Y10686D01*
G01X1890084Y8344D02*
Y10002D01*
G01X1891735Y10686D02*
X1890369Y12052D01*
G01X1890084Y10002D02*
X1889685Y10401D01*
G01X1890369Y12052D02*
X1887577D01*
G01X1889685Y10401D02*
X1886893D01*
G01X1887577Y12052D02*
X1887178Y12451D01*
G01X1886893Y10401D02*
X1885527Y11767D01*
G01X1887178Y12451D02*
Y14445D01*
G01X1885527Y11767D02*
Y15129D01*
G01X1887178Y14445D02*
X1887717Y14984D01*
G01X1885527Y15129D02*
X1887033Y16635D01*
G01X1887717Y14984D02*
X1890470D01*
G01X1887033Y16635D02*
X1889786D01*
G01X1890470Y14984D02*
X1891789Y16303D01*
G01X1889786Y16635D02*
X1890138Y16987D01*
G01X1891789Y16303D02*
Y30214D01*
G01X1890138Y16987D02*
Y29530D01*
G01X1891789Y30214D02*
X1888099Y33904D01*
G01X1890138Y29530D02*
X1886448Y33220D01*
G01X1893594Y-17279D02*
X1895907D01*
G01X1893527Y-18930D02*
X1896591D01*
G01X1895907Y-17279D02*
X1896549Y-16637D01*
G01X1896591Y-18930D02*
X1898200Y-17321D01*
G01X1896549Y-16637D02*
Y-10444D01*
G01D02*
X1892679Y-6574D01*
G01X1898200Y-9760D02*
X1894330Y-5890D01*
G01X1896549Y-10444D02*
X1892679Y-6574D01*
G01X1894330Y-5889D02*
X1893364Y-4923D01*
G01X1892679Y-6574D02*
X1885980D01*
G01X1893362Y-4922D02*
X1891996D01*
G01X1892679Y-6574D02*
X1885980D01*
G01X1891995Y-4923D02*
X1886664D01*
G01X1885980Y-6574D02*
X1884612Y-5206D01*
G01X1886664Y-4923D02*
X1886263Y-4522D01*
G01X1884612Y-5206D02*
Y-2182D01*
G01X1886263Y-4522D02*
Y-2866D01*
G01X1884612Y-2182D02*
X1885922Y-872D01*
G01X1886263Y-2866D02*
X1886606Y-2523D01*
G01X1885922Y-872D02*
X1889905D01*
G01X1886606Y-2523D02*
X1890589D01*
G01X1889905Y-872D02*
X1890667Y-110D01*
G01X1890589Y-2523D02*
X1892318Y-794D01*
G01X1890667Y-110D02*
Y1180D01*
G01X1892318Y-794D02*
Y1864D01*
G01X1890667Y1180D02*
X1890106Y1741D01*
G01X1892318Y1864D02*
X1890790Y3392D01*
G01X1890106Y1741D02*
X1886930D01*
G01X1890790Y3392D02*
X1887614D01*
G01X1886930Y1741D02*
X1884911Y3760D01*
G01X1887614Y3392D02*
X1886562Y4444D01*
G01X1884911Y3760D02*
Y6221D01*
G01X1886562Y4444D02*
Y5537D01*
G01X1884911Y6221D02*
X1886715Y8025D01*
G01X1886562Y5537D02*
X1887399Y6374D01*
G01X1886715Y8025D02*
X1889765D01*
G01X1887399Y6374D02*
X1890449D01*
G01X1889765Y8025D02*
X1890084Y8344D01*
G01X1890449Y6374D02*
X1891735Y7660D01*
G01X1890084Y8344D02*
Y10002D01*
G01X1891735Y7660D02*
Y10686D01*
G01X1890084Y10002D02*
X1889685Y10401D01*
G01X1891735Y10686D02*
X1890369Y12052D01*
G01X1889685Y10401D02*
X1886893D01*
G01X1890369Y12052D02*
X1887577D01*
G01X1886893Y10401D02*
X1885527Y11767D01*
G01X1887577Y12052D02*
X1887178Y12451D01*
G01X1885527Y11767D02*
Y15129D01*
G01X1887178Y12451D02*
Y14445D01*
G01X1885527Y15129D02*
X1887033Y16635D01*
G01X1887178Y14445D02*
X1887717Y14984D01*
G01X1887033Y16635D02*
X1889786D01*
G01X1887717Y14984D02*
X1890470D01*
G01X1889786Y16635D02*
X1890138Y16987D01*
G01X1890470Y14984D02*
X1891789Y16303D01*
G01X1890138Y16987D02*
Y29530D01*
G01X1891789Y16303D02*
Y30214D01*
G01X1890138Y29530D02*
X1886448Y33220D01*
G01X1891789Y30214D02*
X1888099Y33904D01*
G01X1882650Y32934D02*
Y49122D01*
G01D02*
X1878865Y52907D01*
G01X1880999Y48438D02*
X1877214Y52223D01*
G01X1878865Y52907D02*
Y56430D01*
G01X1877214Y52223D02*
Y57114D01*
G01X1878865Y56430D02*
X1880658Y58223D01*
G01X1877214Y57114D02*
X1879007Y58907D01*
G01X1880658Y58223D02*
Y68764D01*
G01X1879007Y58907D02*
Y69448D01*
G01X1880658Y68764D02*
X1887706Y75812D01*
G01X1879007Y69448D02*
X1887022Y77463D01*
G01X1887706Y75812D02*
X1892833D01*
G01X1887022Y77463D02*
X1892149D01*
G01X1892833Y75812D02*
X1896093Y79072D01*
G01X1892149Y77463D02*
X1894442Y79756D01*
G01X1896093Y79072D02*
Y82478D01*
G01X1894442Y79756D02*
Y81794D01*
G01X1896093Y82478D02*
X1894756Y83815D01*
G01X1894442Y81794D02*
X1894072Y82164D01*
G01X1894756Y83815D02*
X1884338D01*
G01X1894072Y82164D02*
X1883654D01*
G01X1884338Y83815D02*
X1883936Y84217D01*
G01X1883654Y82164D02*
X1882285Y83533D01*
G01X1883936Y84217D02*
Y85915D01*
G01X1882285Y83533D02*
Y86600D01*
G01X1884359Y86266D02*
X1894963D01*
G01X1883675Y87917D02*
X1894279D01*
G01X1894620Y94470D02*
X1895938Y95788D01*
G01X1882650Y32934D02*
Y49122D01*
G01X1880999Y48438D02*
X1877214Y52223D01*
G01X1882650Y49122D02*
X1878865Y52907D01*
G01X1877214Y52223D02*
Y57114D01*
G01X1878865Y52907D02*
Y56430D01*
G01X1877214Y57114D02*
X1879007Y58907D01*
G01X1878865Y56430D02*
X1880658Y58223D01*
G01X1879007Y58907D02*
Y69448D01*
G01X1880658Y58223D02*
Y68764D01*
G01X1879007Y69448D02*
X1887022Y77463D01*
G01X1880658Y68764D02*
X1887706Y75812D01*
G01X1887022Y77463D02*
X1892149D01*
G01X1887706Y75812D02*
X1892833D01*
G01X1892149Y77463D02*
X1894442Y79756D01*
G01X1892833Y75812D02*
X1896093Y79072D01*
G01X1894442Y79756D02*
Y81794D01*
G01X1896093Y79072D02*
Y82478D01*
G01X1894442Y81794D02*
X1894072Y82164D01*
G01X1896093Y82478D02*
X1894756Y83815D01*
G01X1894072Y82164D02*
X1883654D01*
G01X1894756Y83815D02*
X1884338D01*
G01X1883654Y82164D02*
X1882285Y83533D01*
G01X1884338Y83815D02*
X1883936Y84217D01*
G01X1882285Y83533D02*
Y86600D01*
G01X1883936Y84217D02*
Y85915D01*
G01X1883675Y87917D02*
X1894279D01*
G01X1884359Y86266D02*
X1894963D01*
G01X1894620Y94470D02*
X1895938Y95788D01*
G01X1888099Y33904D02*
Y35701D01*
G01X1886448Y33220D02*
Y36385D01*
G01X1888099Y35701D02*
X1888498Y36100D01*
G01X1886448Y36385D02*
X1887814Y37751D01*
G01X1888498Y36100D02*
X1890871D01*
G01X1887814Y37751D02*
X1890187D01*
G01X1890871Y36100D02*
X1892237Y37466D01*
G01X1890187Y37751D02*
X1890586Y38150D01*
G01X1892237Y37466D02*
Y39935D01*
G01X1890586Y38150D02*
Y39251D01*
G01X1892237Y39935D02*
X1890871Y41301D01*
G01X1890586Y39251D02*
X1890187Y39650D01*
G01X1890871Y41301D02*
X1887026D01*
G01X1890187Y39650D02*
X1886342D01*
G01X1887026Y41301D02*
X1886627Y41700D01*
G01X1886342Y39650D02*
X1884976Y41016D01*
G01X1886627Y41700D02*
Y55615D01*
G01X1884976Y41016D02*
Y54931D01*
G01X1886627Y55615D02*
X1885261Y56981D01*
G01X1884976Y54931D02*
X1884577Y55330D01*
G01X1884884Y56981D02*
X1884485Y57380D01*
G01X1884200Y55330D02*
X1882834Y56696D01*
G01X1884485Y57380D02*
Y58481D01*
G01X1882834Y56696D02*
Y59165D01*
G01X1884485Y58481D02*
X1884884Y58880D01*
G01X1882834Y59165D02*
X1884200Y60531D01*
G01X1885261Y58880D02*
X1886627Y60246D01*
G01X1884577Y60531D02*
X1884976Y60930D01*
G01X1886627Y60246D02*
Y62715D01*
G01X1884976Y60930D02*
Y62031D01*
G01X1886627Y62715D02*
X1885261Y64081D01*
G01X1884976Y62031D02*
X1884577Y62430D01*
G01X1884884Y64081D02*
X1884485Y64480D01*
G01X1884200Y62430D02*
X1882834Y63796D01*
G01X1884485Y64480D02*
Y65581D01*
G01X1882834Y63796D02*
Y66265D01*
G01X1884485Y65581D02*
X1884884Y65980D01*
G01X1882834Y66265D02*
X1884200Y67631D01*
G01X1885261Y65980D02*
X1886627Y67346D01*
G01X1884577Y67631D02*
X1884976Y68030D01*
G01X1886627Y67346D02*
Y69372D01*
G01X1884976Y68030D02*
Y70056D01*
G01X1886627Y69372D02*
X1889191Y71936D01*
G01D02*
X1890599D01*
G01X1884976Y70056D02*
X1888507Y73587D01*
G01X1889191Y71936D02*
X1890599D01*
G01X1888507Y73587D02*
X1891283D01*
G01X1890599Y71936D02*
X1891571Y70964D01*
G01X1891283Y73587D02*
X1893222Y71648D01*
G01X1891571Y70964D02*
Y67366D01*
G01X1893222Y71648D02*
Y68050D01*
G01X1891571Y67366D02*
X1892778Y66159D01*
G01X1893222Y68050D02*
X1893462Y67810D01*
G01X1892778Y66159D02*
X1895958D01*
G01X1893462Y67810D02*
X1895274D01*
G01X1895958Y66159D02*
X1897325Y67526D01*
G01X1895274Y67810D02*
X1895674Y68210D01*
G01D02*
Y69848D01*
G01X1897325Y69164D02*
X1897828Y69667D01*
G01X1895674Y69848D02*
X1897144Y71318D01*
G01D02*
X1900990D01*
G01X1886448Y33220D02*
Y36385D01*
G01X1888099Y33904D02*
Y35701D01*
G01X1886448Y36385D02*
X1887814Y37751D01*
G01X1888099Y35701D02*
X1888498Y36100D01*
G01X1887814Y37751D02*
X1890187D01*
G01X1888498Y36100D02*
X1890871D01*
G01X1890187Y37751D02*
X1890586Y38150D01*
G01X1890871Y36100D02*
X1892237Y37466D01*
G01X1890586Y38150D02*
Y39251D01*
G01X1892237Y37466D02*
Y39935D01*
G01X1890586Y39251D02*
X1890187Y39650D01*
G01X1892237Y39935D02*
X1890871Y41301D01*
G01X1890187Y39650D02*
X1886342D01*
G01X1890871Y41301D02*
X1887026D01*
G01X1886342Y39650D02*
X1884976Y41016D01*
G01X1887026Y41301D02*
X1886627Y41700D01*
G01X1884976Y41016D02*
Y54931D01*
G01X1886627Y41700D02*
Y55615D01*
G01X1884976Y54931D02*
X1884577Y55330D01*
G01X1886627Y55615D02*
X1885261Y56981D01*
G01X1884200Y55330D02*
X1882834Y56696D01*
G01X1884884Y56981D02*
X1884485Y57380D01*
G01X1882834Y56696D02*
Y59165D01*
G01X1884485Y57380D02*
Y58481D01*
G01X1882834Y59165D02*
X1884200Y60531D01*
G01X1884485Y58481D02*
X1884884Y58880D01*
G01X1884577Y60531D02*
X1884976Y60930D01*
G01X1885261Y58880D02*
X1886627Y60246D01*
G01X1884976Y60930D02*
Y62031D01*
G01X1886627Y60246D02*
Y62715D01*
G01X1884976Y62031D02*
X1884577Y62430D01*
G01X1886627Y62715D02*
X1885261Y64081D01*
G01X1884200Y62430D02*
X1882834Y63796D01*
G01X1884884Y64081D02*
X1884485Y64480D01*
G01X1882834Y63796D02*
Y66265D01*
G01X1884485Y64480D02*
Y65581D01*
G01X1882834Y66265D02*
X1884200Y67631D01*
G01X1884485Y65581D02*
X1884884Y65980D01*
G01X1884577Y67631D02*
X1884976Y68030D01*
G01X1885261Y65980D02*
X1886627Y67346D01*
G01X1884976Y68030D02*
Y70056D01*
G01X1886627Y67346D02*
Y69372D01*
G01X1884976Y70056D02*
X1888507Y73587D01*
G01X1886627Y69372D02*
X1889191Y71936D01*
G01X1884976Y70056D02*
X1888507Y73587D01*
G01D02*
X1891283D01*
G01X1889191Y71936D02*
X1890599D01*
G01X1891283Y73587D02*
X1893222Y71648D01*
G01X1890599Y71936D02*
X1891571Y70964D01*
G01X1893222Y71648D02*
Y68050D01*
G01X1891571Y70964D02*
Y67366D01*
G01X1893222Y68050D02*
X1893462Y67810D01*
G01X1891571Y67366D02*
X1892778Y66159D01*
G01X1893462Y67810D02*
X1895274D01*
G01X1892778Y66159D02*
X1895958D01*
G01X1895274Y67810D02*
X1895674Y68210D01*
G01X1895958Y66159D02*
X1897325Y67526D01*
G01X1895674Y68210D02*
Y69848D01*
G01D02*
X1897144Y71318D01*
G01X1897325Y69164D02*
X1897828Y69667D01*
G01X1897144Y71318D02*
X1900990D01*
G01X1878838Y94470D02*
X1894620D01*
G01X1878226Y96121D02*
X1893936D01*
G01D02*
X1894338Y96523D01*
G01X1886210Y111492D02*
X1886590Y111872D01*
G01X1884610Y112227D02*
X1885906Y113523D01*
G01X1886590Y111872D02*
X1893912D01*
G01X1885906Y113523D02*
X1893228D01*
G01X1893912Y111872D02*
X1895424Y113384D01*
G01X1893228Y113523D02*
X1893824Y114119D01*
G01X1890283Y119919D02*
X1890685Y120321D01*
G01X1888683Y120653D02*
X1889951Y121921D01*
G01X1894241Y134666D02*
X1886894D01*
G01X1893633Y133015D02*
X1886210D01*
G01X1886894Y134666D02*
X1886495Y135065D01*
G01X1886210Y133015D02*
X1884844Y134381D01*
G01X1886495Y135065D02*
Y136766D01*
G01X1884844Y134381D02*
Y137450D01*
G01X1886495Y136766D02*
X1886792Y137063D01*
G01X1884844Y137450D02*
X1886108Y138714D01*
G01X1886792Y137063D02*
X1890560D01*
G01X1886108Y138714D02*
X1889876D01*
G01X1890560Y137063D02*
X1891966Y138469D01*
G01X1889876Y138714D02*
X1890369Y139207D01*
G01X1878226Y96121D02*
X1893936D01*
G01X1878838Y94470D02*
X1894620D01*
G01X1893936Y96121D02*
X1894338Y96523D01*
G01X1884610Y112227D02*
X1885906Y113523D01*
G01X1886210Y111492D02*
X1886590Y111872D01*
G01X1885906Y113523D02*
X1893228D01*
G01X1886590Y111872D02*
X1893912D01*
G01X1893228Y113523D02*
X1893824Y114119D01*
G01X1893912Y111872D02*
X1895424Y113384D01*
G01X1888683Y120653D02*
X1889951Y121921D01*
G01X1890283Y119919D02*
X1890685Y120321D01*
G01X1893633Y133015D02*
X1886210D01*
G01X1894241Y134666D02*
X1886894D01*
G01X1886210Y133015D02*
X1884844Y134381D01*
G01X1886894Y134666D02*
X1886495Y135065D01*
G01X1884844Y134381D02*
Y137450D01*
G01X1886495Y135065D02*
Y136766D01*
G01X1884844Y137450D02*
X1886108Y138714D01*
G01X1886495Y136766D02*
X1886792Y137063D01*
G01X1886108Y138714D02*
X1889876D01*
G01X1886792Y137063D02*
X1890560D01*
G01X1889876Y138714D02*
X1890369Y139207D01*
G01X1890560Y137063D02*
X1891966Y138469D01*
G01X1897823Y137014D02*
X1896457Y138380D01*
G01D02*
Y141622D01*
G01X1897823Y137014D02*
X1896457Y138380D01*
G01D02*
Y141622D01*
G01X1898200Y-17321D02*
Y-9760D01*
G01Y-17321D02*
Y-9760D01*
G01X1897325Y67526D02*
Y69164D01*
G01X1897828Y69667D02*
X1901674D01*
G01D02*
X1903450Y71443D01*
G01X1900990Y71318D02*
X1901799Y72127D01*
G01X1903450Y71443D02*
Y76012D01*
G01X1901799Y72127D02*
Y75328D01*
G01X1903450Y76012D02*
X1902084Y77378D01*
G01X1901799Y75328D02*
X1901400Y75727D01*
G01X1902084Y77378D02*
X1900288D01*
G01X1901400Y75727D02*
X1899604D01*
G01X1900288Y77378D02*
X1899888Y77778D01*
G01X1899604Y75727D02*
X1898237Y77094D01*
G01X1899888Y77778D02*
Y82879D01*
G01X1898237Y77094D02*
Y83563D01*
G01X1899888Y82879D02*
X1900456Y83447D01*
G01X1898237Y83563D02*
X1899772Y85098D01*
G01X1900456Y83447D02*
X1904873D01*
G01X1899772Y85098D02*
X1904189D01*
G01X1904873Y83447D02*
X1906239Y84813D01*
G01X1904189Y85098D02*
X1904588Y85497D01*
G01X1906239Y84813D02*
Y87833D01*
G01X1904588Y85497D02*
Y87149D01*
G01X1906239Y87833D02*
X1904872Y89200D01*
G01X1904588Y87149D02*
X1904188Y87549D01*
G01X1904872Y89200D02*
X1900803D01*
G01X1904188Y87549D02*
X1900119D01*
G01X1900803Y89200D02*
X1900548Y89455D01*
G01X1900119Y87549D02*
X1898897Y88771D01*
G01X1900548Y89455D02*
Y89595D01*
G01X1898897Y88771D02*
Y99309D01*
G01X1897325Y67526D02*
Y69164D01*
G01X1897828Y69667D02*
X1901674D01*
G01X1900990Y71318D02*
X1901799Y72127D01*
G01X1901674Y69667D02*
X1903450Y71443D01*
G01X1901799Y72127D02*
Y75328D01*
G01X1903450Y71443D02*
Y76012D01*
G01X1901799Y75328D02*
X1901400Y75727D01*
G01X1903450Y76012D02*
X1902084Y77378D01*
G01X1901400Y75727D02*
X1899604D01*
G01X1902084Y77378D02*
X1900288D01*
G01X1899604Y75727D02*
X1898237Y77094D01*
G01X1900288Y77378D02*
X1899888Y77778D01*
G01X1898237Y77094D02*
Y83563D01*
G01X1899888Y77778D02*
Y82879D01*
G01X1898237Y83563D02*
X1899772Y85098D01*
G01X1899888Y82879D02*
X1900456Y83447D01*
G01X1899772Y85098D02*
X1904189D01*
G01X1900456Y83447D02*
X1904873D01*
G01X1904189Y85098D02*
X1904588Y85497D01*
G01X1904873Y83447D02*
X1906239Y84813D01*
G01X1904588Y85497D02*
Y87149D01*
G01X1906239Y84813D02*
Y87833D01*
G01X1904588Y87149D02*
X1904188Y87549D01*
G01X1906239Y87833D02*
X1904872Y89200D01*
G01X1904188Y87549D02*
X1900119D01*
G01X1904872Y89200D02*
X1900803D01*
G01X1900119Y87549D02*
X1898897Y88771D01*
G01X1900803Y89200D02*
X1900548Y89455D01*
G01X1898897Y88771D02*
Y99309D01*
G01X1900548Y89455D02*
Y89595D01*
G01X1902259Y113683D02*
X1901510Y114432D01*
G01X1901575Y112032D02*
X1899859Y113748D01*
G01X1901510Y114432D02*
Y121255D01*
G01X1899859Y113748D02*
Y121939D01*
G01X1901510Y121255D02*
X1902300Y122045D01*
G01X1899859Y121939D02*
X1900649Y122729D01*
G01X1902300Y122045D02*
Y126851D01*
G01X1900649Y122729D02*
Y126167D01*
G01X1902300Y126851D02*
X1900933Y128218D01*
G01X1900649Y126167D02*
X1900249Y126567D01*
G01X1900059Y128218D02*
X1899660Y128617D01*
G01X1899375Y126567D02*
X1898009Y127933D01*
G01X1899660Y128617D02*
Y129718D01*
G01X1898009Y127933D02*
Y130402D01*
G01X1899660Y129718D02*
X1900059Y130117D01*
G01X1898009Y130402D02*
X1899375Y131768D01*
G01X1900934Y130117D02*
X1902300Y131483D01*
G01X1900250Y131768D02*
X1900649Y132167D01*
G01X1902300Y131483D02*
Y136872D01*
G01X1900649Y132167D02*
Y136188D01*
G01X1902300Y136872D02*
X1900507Y138665D01*
G01X1900649Y136188D02*
X1899823Y137014D01*
G01X1900507Y138665D02*
X1898507D01*
G01X1899823Y137014D02*
X1897823D01*
G01X1898507Y138665D02*
X1898108Y139064D01*
G01D02*
Y141431D01*
G01X1901575Y112032D02*
X1899859Y113748D01*
G01X1902259Y113683D02*
X1901510Y114432D01*
G01X1899859Y113748D02*
Y121939D01*
G01X1901510Y114432D02*
Y121255D01*
G01X1899859Y121939D02*
X1900649Y122729D01*
G01X1901510Y121255D02*
X1902300Y122045D01*
G01X1900649Y122729D02*
Y126167D01*
G01X1902300Y122045D02*
Y126851D01*
G01X1900649Y126167D02*
X1900249Y126567D01*
G01X1902300Y126851D02*
X1900933Y128218D01*
G01X1899375Y126567D02*
X1898009Y127933D01*
G01X1900059Y128218D02*
X1899660Y128617D01*
G01X1898009Y127933D02*
Y130402D01*
G01X1899660Y128617D02*
Y129718D01*
G01X1898009Y130402D02*
X1899375Y131768D01*
G01X1899660Y129718D02*
X1900059Y130117D01*
G01X1900250Y131768D02*
X1900649Y132167D01*
G01X1900934Y130117D02*
X1902300Y131483D01*
G01X1900649Y132167D02*
Y136188D01*
G01X1902300Y131483D02*
Y136872D01*
G01X1900649Y136188D02*
X1899823Y137014D01*
G01X1902300Y136872D02*
X1900507Y138665D01*
G01X1899823Y137014D02*
X1897823D01*
G01X1900507Y138665D02*
X1898507D01*
G01D02*
X1898108Y139064D01*
G01D02*
Y141431D01*
M02*
